G04 ================== begin FILE IDENTIFICATION RECORD ==================*
G04 Layout Name:  12433-1M.brd*
G04 Film Name:    TSILK*
G04 File Format:  Gerber RS274X*
G04 File Origin:  Cadence Allegro 16.2-S037*
G04 Origin Date:  Fri Dec 07 18:55:07 2012*
G04 *
G04 Layer:  VIA CLASS/FILMMASKTOP*
G04 Layer:  REF DES/ASSEMBLY_TOP*
G04 Layer:  PACKAGE GEOMETRY/SILKSCREEN_TOP*
G04 Layer:  DRAWING FORMAT/LAYER_PCB_STORY*
G04 Layer:  DRAWING FORMAT/LAYER_SILK_T*
G04 Layer:  BOARD GEOMETRY/SILKSCREEN_TOP*
G04 *
G04 Offset:    (0.00 0.00)*
G04 Mirror:    No*
G04 Mode:      Positive*
G04 Rotation:  0*
G04 FullContactRelief:  No*
G04 UndefLineWidth:     6.00*
G04 ================== end FILE IDENTIFICATION RECORD ====================*
%FSLAX35Y35*MOIN*%
%IR0*IPPOS*OFA0.00000B0.00000*MIA0B0*SFA1.00000B1.00000*%
%ADD10C,.01*%
%ADD11C,.02*%
%ADD12C,.012*%
%ADD13C,.013*%
%ADD14C,.016*%
%ADD15C,.019*%
%ADD16C,.0005*%
%ADD17C,.002*%
%ADD18C,.005*%
%ADD19C,.006*%
%ADD20C,.008*%
G75*
%LPD*%
G75*
G36*
G01X67300Y433800D02*
X69000Y435500D01*
X70700Y433800D01*
X67300D01*
G37*
G36*
G01X80200Y971300D02*
Y981300D01*
X85200D01*
Y971300D01*
X80200D01*
G37*
G36*
G01X58700Y1569400D02*
X60400Y1571100D01*
X62100Y1569400D01*
X58700D01*
G37*
G36*
G01X71289Y1623299D02*
X73289Y1625299D01*
X69289D01*
X71289Y1623299D01*
G37*
G36*
G01X94800Y433300D02*
X96500Y435000D01*
X98200Y433300D01*
X94800D01*
G37*
G36*
G01X107435Y607629D02*
X97835D01*
Y616929D01*
X98135D01*
X107435Y607629D01*
G37*
G36*
G01X100100Y864354D02*
X116900D01*
Y850404D01*
X100100D01*
Y864354D01*
G37*
G36*
G01X103150Y1460850D02*
X108150Y1465850D01*
X103150D01*
Y1460850D01*
G37*
G36*
G01X126800Y1569300D02*
X128500Y1571000D01*
X130200Y1569300D01*
X126800D01*
G37*
G36*
G01X91800D02*
X93500Y1571000D01*
X95200Y1569300D01*
X91800D01*
G37*
G36*
G01X101789Y1623299D02*
X103789Y1625299D01*
X99789D01*
X101789Y1623299D01*
G37*
G36*
G01X130289D02*
X132289Y1625299D01*
X128289D01*
X130289Y1623299D01*
G37*
G36*
G01X139300Y433300D02*
X141000Y435000D01*
X142700Y433300D01*
X139300D01*
G37*
G36*
G01X167300D02*
X169000Y435000D01*
X170700Y433300D01*
X167300D01*
G37*
G36*
G01X172585Y652429D02*
X170485Y650329D01*
X168585Y652429D01*
X172585D01*
G37*
G36*
G01X155100Y728154D02*
X171900D01*
Y714204D01*
X155100D01*
Y728154D01*
G37*
G36*
G01X149500Y872500D02*
X154500D01*
Y892500D01*
X149500D01*
Y872500D01*
G37*
G36*
G01X177650Y872650D02*
X197350D01*
Y1081350D01*
X177650D01*
Y872650D01*
G37*
G36*
G01X136600Y977600D02*
Y963600D01*
X155600D01*
Y977600D01*
X136600D01*
G37*
G36*
G01X160800Y1569300D02*
X162500Y1571000D01*
X164200Y1569300D01*
X160800D01*
G37*
G36*
G01X157789Y1623299D02*
X159789Y1625299D01*
X155789D01*
X157789Y1623299D01*
G37*
G54D10*
G01X171828Y1968527D02*
G03X182301I5236J0D01*
G01X140333D02*
G03X150806I5236J0D01*
G01X203323D02*
G03X213796I5236J0D01*
G01X266314D02*
G03X276786I5236J0D01*
G01X234819D02*
G03X245291I5236J0D01*
G01X297809D02*
G03X308281I5236J0D01*
G54D20*
G01X22100Y688100D02*
X26100D01*
G01X26900D02*
X30900D01*
G01X78500Y72300D02*
Y73400D01*
G01Y69600D02*
Y70700D01*
G01X49498Y241699D02*
X45498D01*
G01X54200Y241700D02*
X50200D01*
G01X37200Y292300D02*
Y296300D01*
G01X64700Y257000D02*
X60700D01*
G01X53400Y250800D02*
Y254800D01*
G01X70700Y590200D02*
Y589100D01*
G01Y592900D02*
Y591800D01*
G01X45900Y580100D02*
X47000D01*
G01X43200D02*
X44300D01*
G01X72100Y573400D02*
X76100D01*
G01X61000Y664300D02*
Y660300D01*
G01Y659600D02*
Y655600D01*
G01X63635Y691106D02*
X67635D01*
G01X68535D02*
X72535D01*
G01X81200Y705400D02*
X80100D01*
G01X79600Y730400D02*
X80700D01*
G01X70200Y708200D02*
X74200D01*
G01X65200D02*
X69200D01*
G01X73800Y985800D02*
Y984700D01*
G01Y988500D02*
Y987400D01*
G01X70000Y978600D02*
X68900D01*
G01X72700D02*
X71600D01*
G01X63400Y1001300D02*
X62300D01*
G01X66100D02*
X65000D01*
G01X64800Y1024200D02*
Y1023100D01*
G01Y1026900D02*
Y1025800D01*
G01X80598Y1134953D02*
X79498D01*
G01X64002Y1131147D02*
X65102D01*
G01X61302D02*
X62402D01*
G01X51500Y1765500D02*
Y1766600D01*
G01Y1762800D02*
Y1763900D01*
G01X30800Y1770700D02*
Y1771800D01*
G01Y1768000D02*
Y1769100D01*
G01X81047Y60598D02*
Y59498D01*
G01Y63298D02*
Y62198D01*
G01X114100Y378100D02*
Y382100D01*
G01X105900Y479400D02*
X101900D01*
G01X88729Y532879D02*
Y531779D01*
G01Y535579D02*
Y534479D01*
G01X98300Y560500D02*
X94300D01*
G01X131065Y675894D02*
X127065D01*
G01X125465D02*
X121465D01*
G01X125700Y725400D02*
X126800D01*
G01X123000D02*
X124100D01*
G01X83900Y705400D02*
X82800D01*
G01X82300Y730400D02*
X83400D01*
G01X113000Y771100D02*
Y767100D01*
G01Y766100D02*
Y762100D01*
G01X90300Y875654D02*
X94300D01*
G01X85500D02*
X89500D01*
G01X123300Y967100D02*
X110800D01*
G01X123300Y981100D02*
Y967100D01*
G01X110800Y981100D02*
X123300D01*
G01X110800D02*
Y963600D01*
G01X113300Y974100D02*
X110800Y976600D01*
G01X113300Y974100D02*
X110800Y971600D01*
G01X95300Y979500D02*
X96400D01*
G01X92600D02*
X93700D01*
G01X93200Y960000D02*
X92100D01*
G01X95900D02*
X94800D01*
G01X104300Y984000D02*
Y988000D01*
G01Y988800D02*
Y992800D01*
G01X101500Y977000D02*
X105500D01*
G01X127900Y989700D02*
X131900D01*
G01X132800Y978600D02*
X128800D01*
G01X102500Y1060400D02*
Y1056400D01*
G01Y1055700D02*
Y1051700D01*
G01X83298Y1134953D02*
X82198D01*
G01X92000Y1453500D02*
Y1457500D01*
G01X135500Y1474000D02*
X131500D01*
G01X104000Y1472500D02*
Y1476500D01*
G01X148700Y479500D02*
X144700D01*
G01X163100Y531300D02*
Y530200D01*
G01Y534000D02*
Y532900D01*
G01X138400Y569600D02*
X142400D01*
G01X162900Y551300D02*
Y555300D01*
G01X179221Y612535D02*
Y614535D01*
G01X157535Y606879D02*
X159535D01*
G01X165300Y699300D02*
X161300D01*
G01X146300Y1114100D02*
X142300D01*
G01X151002Y1114147D02*
X147002D01*
G01X157500Y1460500D02*
Y1464500D01*
G01X144647Y1880698D02*
Y1876698D01*
G01X144600Y1885700D02*
Y1881700D01*
G01X185100Y1654700D02*
Y1650700D01*
G01Y1650000D02*
Y1646000D01*
G54D11*
G01X-448201Y-82763D02*
Y-162763D01*
G01Y-118263D02*
X752899D01*
G01X-448201Y-162763D02*
X752899D01*
G01X-452201Y-66763D02*
G02I-12000J0D01*
G01X-457351D02*
G02I-6850J0D01*
G01X-464201Y-82763D02*
Y-50763D01*
G01X-448201Y-66763D02*
X-480201D01*
G01X-448201Y-82763D02*
X752899D01*
G01X-34601D02*
Y-162763D01*
G01X75000Y406800D02*
Y390200D01*
G01X53800Y389500D02*
Y406100D01*
G01X63700Y349400D02*
Y374400D01*
G01X75000Y427300D02*
Y410700D01*
G01X53800Y410000D02*
Y426600D01*
G01X53500Y580500D02*
Y587500D01*
G01X63200Y596500D02*
Y589500D01*
G01X50000Y658700D02*
Y675300D01*
G01X78300Y1015300D02*
Y1008300D01*
G01X73702Y1120197D02*
X66702D01*
G01X40500Y1401800D02*
X94000D01*
Y1272300D01*
X40000D01*
Y1401800D01*
G01X87200Y1529600D02*
X70600D01*
G01X67500Y1543200D02*
Y1559800D01*
G01X66350Y1693100D02*
Y1667900D01*
G01X45100Y1749400D02*
X38100D01*
G01X39500Y1784500D02*
Y1777500D01*
G01X102899Y-82763D02*
Y-162763D01*
G01X96103Y58002D02*
Y51002D01*
G01X114000Y72000D02*
Y65000D01*
G01X107000Y96800D02*
Y80200D01*
G01X92600Y556900D02*
Y564900D01*
G01X111400Y560800D02*
Y555800D01*
G01X117556Y674265D02*
X109356D01*
G01X100000Y718900D02*
Y711900D01*
G01X99500Y743900D02*
Y736900D01*
G01X104500Y790100D02*
Y806700D01*
G01X97500Y842354D02*
Y850704D01*
G01X110800Y967100D02*
Y959100D01*
G01X85000Y968550D02*
X92000D01*
G01X82600Y1035600D02*
Y1028600D01*
G01X94600Y1082300D02*
Y1098900D01*
G01X92002Y1118097D02*
X85002D01*
G01X87000Y1465500D02*
X92000D01*
G01X84000Y1475000D02*
Y1480000D01*
G01X102970Y1478140D02*
Y1483140D01*
G01X115998Y1877403D02*
X132598D01*
G01X154400Y406200D02*
Y389600D01*
G01X154300Y365000D02*
Y348400D01*
G01X154500Y385200D02*
Y368600D01*
G01X146400Y374300D02*
Y349300D01*
G01X154400Y426700D02*
Y410100D01*
G01X174600Y545300D02*
X169600D01*
G01X156400Y555100D02*
Y563100D01*
G01X167600Y611400D02*
X172600D01*
G01X154765Y605171D02*
X149765D01*
G01X152500Y706154D02*
Y714504D01*
G01X140400Y704500D02*
Y716500D01*
G01X134800Y955600D02*
Y963600D01*
G01X137498Y1120403D02*
X154098D01*
G01X139300Y1484400D02*
X145300D01*
G01X151900Y1495200D02*
Y1520200D01*
G01X154000Y1539800D02*
Y1523200D01*
G01X154100Y1559900D02*
Y1543300D01*
G01X217899Y-82763D02*
Y-162763D01*
G01X187500Y1609000D02*
Y1604000D01*
G01X184500Y1643500D02*
Y1638500D01*
G01X385399Y-82763D02*
Y-162763D01*
G01X555399Y-82763D02*
Y-162763D01*
G01X752899Y-82763D02*
Y-162763D01*
G01X780899Y-66763D02*
G02I-12000J0D01*
G01X775749D02*
G02I-6850J0D01*
G01X768899Y-82763D02*
Y-50763D01*
G01X784899Y-66763D02*
X752899D01*
G54D12*
G01X-206693Y39370D02*
X-175984D01*
G01X-214580Y199710D02*
Y169001D01*
G01X-214624Y467631D02*
Y436922D01*
G01X-214567Y733921D02*
Y703212D01*
G01Y1001681D02*
Y970972D01*
G01Y1265366D02*
Y1234657D01*
G01X-214570Y1532461D02*
Y1501752D01*
G01X-214567Y1798746D02*
Y1768037D01*
G01X-175984Y1929134D02*
X-206693D01*
G01X-76772Y7874D02*
Y31496D01*
G01X-76763Y1937008D02*
Y1960889D01*
G01X-7874Y11811D02*
Y42520D01*
G01X0Y11811D02*
Y42520D01*
G01X20106Y48110D02*
G02I-4200J0D01*
G01Y58110D02*
G02I-4200J0D01*
G01Y68110D02*
G02I-4200J0D01*
G01Y78110D02*
G02I-4200J0D01*
G01Y88110D02*
G02I-4200J0D01*
G01X35199Y220866D02*
G02I-3900J0D01*
G01Y210866D02*
G02I-3900J0D01*
G01Y230866D02*
G02I-3900J0D01*
G01X-7874Y278740D02*
Y309449D01*
G01X0Y278740D02*
Y309449D01*
G01X31299Y334663D02*
G02I0J3900D01*
G01Y344663D02*
G02I0J3900D01*
G01Y354663D02*
G02I0J3900D01*
G01X20106Y481339D02*
G02I-4200J0D01*
G01Y491339D02*
G02I-4200J0D01*
G01Y501339D02*
G02I-4200J0D01*
G01X-7874Y545669D02*
Y576378D01*
G01X0Y545669D02*
Y576378D01*
G01X20106Y511339D02*
G02I-4200J0D01*
G01Y521339D02*
G02I-4200J0D01*
G01Y741181D02*
G02I-4200J0D01*
G01Y751181D02*
G02I-4200J0D01*
G01Y761181D02*
G02I-4200J0D01*
G01Y771181D02*
G02I-4200J0D01*
G01Y781181D02*
G02I-4200J0D01*
G01X0Y862205D02*
Y831496D01*
G01X-7874Y862205D02*
Y831496D01*
G01X31299Y900017D02*
G02I0J3900D01*
G01Y910017D02*
G02I0J3900D01*
G01Y920017D02*
G02I0J3900D01*
G01Y1050687D02*
G02I0J3900D01*
G01Y1040687D02*
G02I0J3900D01*
G01X-7874Y1106299D02*
Y1137008D01*
G01X0Y1106299D02*
Y1137008D01*
G01X31299Y1060687D02*
G02I0J3900D01*
G01X20106Y1187323D02*
G02I-4200J0D01*
G01Y1197323D02*
G02I-4200J0D01*
G01Y1207323D02*
G02I-4200J0D01*
G01Y1217323D02*
G02I-4200J0D01*
G01Y1227323D02*
G02I-4200J0D01*
G01X0Y1422835D02*
Y1392126D01*
G01X-7874Y1422835D02*
Y1392126D01*
G01X20106Y1447165D02*
G02I-4200J0D01*
G01Y1457165D02*
G02I-4200J0D01*
G01Y1467165D02*
G02I-4200J0D01*
G01Y1477165D02*
G02I-4200J0D01*
G01Y1487165D02*
G02I-4200J0D01*
G01X31299Y1616041D02*
G02I0J3900D01*
G01Y1606041D02*
G02I0J3900D01*
G01X0Y1689764D02*
Y1659055D01*
G01X-7874Y1689764D02*
Y1659055D01*
G01X31299Y1626041D02*
G02I0J3900D01*
G01X35199Y1747638D02*
G02I-3900J0D01*
G01Y1737638D02*
G02I-3900J0D01*
G01Y1757638D02*
G02I-3900J0D01*
G01X20106Y1880394D02*
G02I-4200J0D01*
G01X-7874Y1956693D02*
Y1925984D01*
G01X0Y1956693D02*
Y1925984D01*
G01X20106Y1890394D02*
G02I-4200J0D01*
G01Y1900394D02*
G02I-4200J0D01*
G01Y1910394D02*
G02I-4200J0D01*
G01Y1920394D02*
G02I-4200J0D01*
G01X68889Y7615D02*
Y31496D01*
G01X84959Y161889D02*
G02I-4250J0D01*
G01Y171889D02*
G02I-4250J0D01*
G01Y181889D02*
G02I-4250J0D01*
G01Y191889D02*
G02I-4250J0D01*
G01Y204409D02*
G02I-4250J0D01*
G01Y214409D02*
G02I-4250J0D01*
G01Y224409D02*
G02I-4250J0D01*
G01Y234409D02*
G02I-4250J0D01*
G01Y244409D02*
G02I-4250J0D01*
G01Y256929D02*
G02I-4250J0D01*
G01Y266929D02*
G02I-4250J0D01*
G01Y276929D02*
G02I-4250J0D01*
G01Y286929D02*
G02I-4250J0D01*
G01X68898Y1960630D02*
Y1937008D01*
G01X114959Y161889D02*
G02I-4250J0D01*
G01Y171889D02*
G02I-4250J0D01*
G01Y181889D02*
G02I-4250J0D01*
G01Y191889D02*
G02I-4250J0D01*
G01X104959Y161889D02*
G02I-4250J0D01*
G01Y171889D02*
G02I-4250J0D01*
G01Y181889D02*
G02I-4250J0D01*
G01Y191889D02*
G02I-4250J0D01*
G01X94959Y161889D02*
G02I-4250J0D01*
G01Y171889D02*
G02I-4250J0D01*
G01Y181889D02*
G02I-4250J0D01*
G01Y191889D02*
G02I-4250J0D01*
G01X114959Y204409D02*
G02I-4250J0D01*
G01Y214409D02*
G02I-4250J0D01*
G01Y224409D02*
G02I-4250J0D01*
G01Y234409D02*
G02I-4250J0D01*
G01Y244409D02*
G02I-4250J0D01*
G01X104959Y204409D02*
G02I-4250J0D01*
G01Y214409D02*
G02I-4250J0D01*
G01Y224409D02*
G02I-4250J0D01*
G01Y234409D02*
G02I-4250J0D01*
G01Y244409D02*
G02I-4250J0D01*
G01X94959Y204409D02*
G02I-4250J0D01*
G01Y214409D02*
G02I-4250J0D01*
G01Y224409D02*
G02I-4250J0D01*
G01Y234409D02*
G02I-4250J0D01*
G01Y244409D02*
G02I-4250J0D01*
G01X114959Y256929D02*
G02I-4250J0D01*
G01Y266929D02*
G02I-4250J0D01*
G01Y276929D02*
G02I-4250J0D01*
G01Y286929D02*
G02I-4250J0D01*
G01X104959Y256929D02*
G02I-4250J0D01*
G01Y266929D02*
G02I-4250J0D01*
G01Y276929D02*
G02I-4250J0D01*
G01Y286929D02*
G02I-4250J0D01*
G01X94959Y256929D02*
G02I-4250J0D01*
G01Y266929D02*
G02I-4250J0D01*
G01Y276929D02*
G02I-4250J0D01*
G01Y286929D02*
G02I-4250J0D01*
G01X123137Y1778819D02*
G02I-4200J0D01*
G01X133137D02*
G02I-4200J0D01*
G01X168110Y39370D02*
X198819D01*
G01X183856Y161889D02*
G02I-4250J0D01*
G01Y171889D02*
G02I-4250J0D01*
G01Y181889D02*
G02I-4250J0D01*
G01Y191889D02*
G02I-4250J0D01*
G01X173856Y161889D02*
G02I-4250J0D01*
G01Y171889D02*
G02I-4250J0D01*
G01Y181889D02*
G02I-4250J0D01*
G01Y191889D02*
G02I-4250J0D01*
G01X163856Y161889D02*
G02I-4250J0D01*
G01Y171889D02*
G02I-4250J0D01*
G01Y181889D02*
G02I-4250J0D01*
G01Y191889D02*
G02I-4250J0D01*
G01X153856Y161889D02*
G02I-4250J0D01*
G01Y171889D02*
G02I-4250J0D01*
G01Y181889D02*
G02I-4250J0D01*
G01Y191889D02*
G02I-4250J0D01*
G01X183856Y204409D02*
G02I-4250J0D01*
G01Y214409D02*
G02I-4250J0D01*
G01Y224409D02*
G02I-4250J0D01*
G01Y234409D02*
G02I-4250J0D01*
G01Y244409D02*
G02I-4250J0D01*
G01X173856Y204409D02*
G02I-4250J0D01*
G01Y214409D02*
G02I-4250J0D01*
G01Y224409D02*
G02I-4250J0D01*
G01Y234409D02*
G02I-4250J0D01*
G01Y244409D02*
G02I-4250J0D01*
G01X163856Y204409D02*
G02I-4250J0D01*
G01Y214409D02*
G02I-4250J0D01*
G01Y224409D02*
G02I-4250J0D01*
G01Y234409D02*
G02I-4250J0D01*
G01Y244409D02*
G02I-4250J0D01*
G01X153856Y204409D02*
G02I-4250J0D01*
G01Y214409D02*
G02I-4250J0D01*
G01Y224409D02*
G02I-4250J0D01*
G01Y234409D02*
G02I-4250J0D01*
G01Y244409D02*
G02I-4250J0D01*
G01X183856Y256929D02*
G02I-4250J0D01*
G01Y266929D02*
G02I-4250J0D01*
G01Y276929D02*
G02I-4250J0D01*
G01Y286929D02*
G02I-4250J0D01*
G01X173856Y256929D02*
G02I-4250J0D01*
G01Y266929D02*
G02I-4250J0D01*
G01Y276929D02*
G02I-4250J0D01*
G01Y286929D02*
G02I-4250J0D01*
G01X163856Y256929D02*
G02I-4250J0D01*
G01Y266929D02*
G02I-4250J0D01*
G01Y276929D02*
G02I-4250J0D01*
G01Y286929D02*
G02I-4250J0D01*
G01X153856Y256929D02*
G02I-4250J0D01*
G01Y266929D02*
G02I-4250J0D01*
G01Y276929D02*
G02I-4250J0D01*
G01Y286929D02*
G02I-4250J0D01*
G01X169200Y1370500D02*
G02I-4200J0D01*
G01Y1390500D02*
G02I-4200J0D01*
G01Y1380500D02*
G02I-4200J0D01*
G01X143137Y1778819D02*
G02I-4200J0D01*
G01X198819Y1929134D02*
X168110D01*
G01X222441Y39370D02*
X253150D01*
G01X206693Y169291D02*
Y200000D01*
G01X214567Y169291D02*
Y200000D01*
G01X206693Y436220D02*
Y466929D01*
G01X214567Y436220D02*
Y466929D01*
G01X206693Y733858D02*
Y703149D01*
G01X214567Y733858D02*
Y703149D01*
G01X206693Y997637D02*
Y966928D01*
G01X214567Y997637D02*
Y966928D01*
G01Y1265355D02*
Y1234646D01*
G01X206693Y1265355D02*
Y1234646D01*
G01X214567Y1532284D02*
Y1501575D01*
G01X206693Y1532284D02*
Y1501575D01*
G01X214567Y1799213D02*
Y1768504D01*
G01X206693Y1799213D02*
Y1768504D01*
G01X253150Y1929134D02*
X222441D01*
G01X352362Y7874D02*
Y31496D01*
G01X352370Y1960889D02*
Y1937008D01*
G01X429134Y11811D02*
Y42520D01*
G01X421260Y11811D02*
Y42520D01*
G01X429134Y278740D02*
Y309449D01*
G01X421260Y278740D02*
Y309449D01*
G01X429134Y545669D02*
Y576378D01*
G01X421260Y545669D02*
Y576378D01*
G01X429134Y862205D02*
Y831496D01*
G01X421260Y862205D02*
Y831496D01*
G01X429134Y1106299D02*
Y1137008D01*
G01X421260Y1106299D02*
Y1137008D01*
G01X429134Y1422835D02*
Y1392126D01*
G01X421260Y1422835D02*
Y1392126D01*
G01X429134Y1689764D02*
Y1659055D01*
G01X421260Y1689764D02*
Y1659055D01*
G01X429134Y1956693D02*
Y1925984D01*
G01X421260Y1956693D02*
Y1925984D01*
G01X498023Y7615D02*
Y31496D01*
G01X498032Y1960630D02*
Y1937008D01*
G01X627953Y39370D02*
X597244D01*
G01X635827Y199972D02*
Y169263D01*
G01X635842Y467238D02*
Y436529D01*
G01X635827Y734932D02*
Y704223D01*
G01X635830Y1001701D02*
Y970992D01*
G01X635827Y1265290D02*
Y1234581D01*
G01X635831Y1532435D02*
Y1501726D01*
G01X635827Y1799178D02*
Y1768470D01*
G01X627953Y1929134D02*
X597244D01*
G54D13*
G01X26096Y266203D02*
X30496D01*
Y262703D01*
G01X26300Y301700D02*
X21900D01*
Y305200D01*
G01X25917Y1718518D02*
X30317D01*
Y1715018D01*
G01X69700Y435400D02*
X68200D01*
G01X66835Y670756D02*
X63985D01*
Y673456D01*
G01X47900Y690600D02*
Y693450D01*
X50600D01*
G01X32400Y690600D02*
Y693450D01*
X35100D01*
G01X57317Y913518D02*
X61717D01*
Y910018D01*
G01X35518Y1090583D02*
Y1086183D01*
X32018D01*
G01X61100Y1571000D02*
X59600D01*
G01X71400Y1623450D02*
X65400D01*
Y1618100D01*
G01X34000Y1652700D02*
X38400D01*
Y1649200D01*
G01X97200Y434900D02*
X95700D01*
G01X115668Y568366D02*
Y563966D01*
X112168D01*
G01X132900Y718900D02*
X128500D01*
Y722400D01*
G01X115668Y1257343D02*
Y1252943D01*
X112168D01*
G01X129200Y1570900D02*
X127700D01*
G01X94200D02*
X92700D01*
G01X101900Y1623450D02*
X95900D01*
Y1618100D01*
G01X130400Y1623450D02*
X124400D01*
Y1618100D01*
G01X141700Y434900D02*
X140200D01*
G01X169700D02*
X168200D01*
G01X170478Y650374D02*
X176814D01*
Y644783D01*
G01X143000Y678600D02*
X138600D01*
Y682100D01*
G01X149400Y1397804D02*
X145000D01*
Y1401304D01*
G01X166869Y1433819D02*
X162469D01*
Y1437319D01*
G01X140069Y1418619D02*
X135669D01*
Y1422119D01*
G01X163200Y1570900D02*
X161700D01*
G01X157900Y1623450D02*
X151900D01*
Y1618100D01*
G54D14*
G01X20206Y89610D02*
Y94610D01*
X15206D01*
G01X20206Y522839D02*
Y527839D01*
X15206D01*
G01X20206Y782681D02*
Y787681D01*
X15206D01*
G01X20206Y1228823D02*
Y1233823D01*
X15206D01*
G01X20206Y1488665D02*
Y1493665D01*
X15206D01*
G01X20206Y1921894D02*
Y1926894D01*
X15206D01*
G01X112438Y1780319D02*
Y1785319D01*
X117438D01*
G01X163600Y1364500D02*
X158600D01*
Y1369500D01*
G01X143800Y1413796D02*
X138400D01*
G01X155900Y1434304D02*
X161300D01*
G54D15*
G01X116100Y1394700D02*
X112700D01*
G54D16*
G01X27548Y266191D02*
X27445D01*
G01X27623Y266266D02*
X27370D01*
G01X27698Y266341D02*
X27295D01*
G01X27773Y266416D02*
X27220D01*
G01X27848Y266491D02*
X27145D01*
G01X27923Y266566D02*
X27070D01*
G01X27998Y266641D02*
X26995D01*
G01X28073Y266716D02*
X26920D01*
G01X28148Y266791D02*
X26845D01*
G01X28223Y266866D02*
X26770D01*
G01X28298Y266941D02*
X26695D01*
G01X28373Y267016D02*
X26620D01*
G01X28448Y267091D02*
X26545D01*
G01X28523Y267166D02*
X26470D01*
G01X26427Y267250D02*
X28580Y267233D01*
G01X28633Y267276D02*
X27496Y266138D01*
G01D02*
X26357Y267278D01*
G01X26416D02*
X28576D01*
G01X28632D02*
X26357D01*
G01X28560Y267203D02*
X26432D01*
G01X28485Y267128D02*
X26507D01*
G01X28410Y267053D02*
X26582D01*
G01X28335Y266978D02*
X26657D01*
G01X28260Y266903D02*
X26732D01*
G01X28185Y266828D02*
X26807D01*
G01X28110Y266753D02*
X26882D01*
G01X28035Y266678D02*
X26957D01*
G01X27960Y266603D02*
X27032D01*
G01X27885Y266528D02*
X27107D01*
G01X27810Y266453D02*
X27182D01*
G01X27735Y266378D02*
X27257D01*
G01X27660Y266303D02*
X27332D01*
G01X27585Y266228D02*
X27407D01*
G01X27510Y266153D02*
X27482D01*
G01X24848Y301712D02*
X24951D01*
G01X24773Y301637D02*
X25026D01*
G01X24698Y301562D02*
X25101D01*
G01X24623Y301487D02*
X25176D01*
G01X24548Y301412D02*
X25251D01*
G01X24473Y301337D02*
X25326D01*
G01X24398Y301262D02*
X25401D01*
G01X24323Y301187D02*
X25476D01*
G01X24248Y301112D02*
X25551D01*
G01X24173Y301037D02*
X25626D01*
G01X24098Y300962D02*
X25701D01*
G01X24023Y300887D02*
X25776D01*
G01X23948Y300812D02*
X25851D01*
G01X23873Y300737D02*
X25926D01*
G01X25969Y300653D02*
X23816Y300670D01*
G01X23763Y300627D02*
X24900Y301765D01*
G01D02*
X26039Y300625D01*
G01X25980D02*
X23820D01*
G01X23764D02*
X26039D01*
G01X23836Y300700D02*
X25964D01*
G01X23911Y300775D02*
X25889D01*
G01X23986Y300850D02*
X25814D01*
G01X24061Y300925D02*
X25739D01*
G01X24136Y301000D02*
X25664D01*
G01X24211Y301075D02*
X25589D01*
G01X24286Y301150D02*
X25514D01*
G01X24361Y301225D02*
X25439D01*
G01X24436Y301300D02*
X25364D01*
G01X24511Y301375D02*
X25289D01*
G01X24586Y301450D02*
X25214D01*
G01X24661Y301525D02*
X25139D01*
G01X24736Y301600D02*
X25064D01*
G01X24811Y301675D02*
X24989D01*
G01X24886Y301750D02*
X24914D01*
G01X27369Y1718506D02*
X27266D01*
G01X27444Y1718581D02*
X27191D01*
G01X27519Y1718656D02*
X27116D01*
G01X27594Y1718731D02*
X27041D01*
G01X27669Y1718806D02*
X26966D01*
G01X27744Y1718881D02*
X26891D01*
G01X27819Y1718956D02*
X26816D01*
G01X27894Y1719031D02*
X26741D01*
G01X27969Y1719106D02*
X26666D01*
G01X28044Y1719181D02*
X26591D01*
G01X28119Y1719256D02*
X26516D01*
G01X28194Y1719331D02*
X26441D01*
G01X28269Y1719406D02*
X26366D01*
G01X28344Y1719481D02*
X26291D01*
G01X26248Y1719565D02*
X28401Y1719548D01*
G01X28454Y1719591D02*
X27317Y1718453D01*
G01D02*
X26178Y1719593D01*
G01X26237D02*
X28397D01*
G01X28453D02*
X26178D01*
G01X28381Y1719518D02*
X26253D01*
G01X28306Y1719443D02*
X26328D01*
G01X28231Y1719368D02*
X26403D01*
G01X28156Y1719293D02*
X26478D01*
G01X28081Y1719218D02*
X26553D01*
G01X28006Y1719143D02*
X26628D01*
G01X27931Y1719068D02*
X26703D01*
G01X27856Y1718993D02*
X26778D01*
G01X27781Y1718918D02*
X26853D01*
G01X27706Y1718843D02*
X26928D01*
G01X27631Y1718768D02*
X27003D01*
G01X27556Y1718693D02*
X27078D01*
G01X27481Y1718618D02*
X27153D01*
G01X27406Y1718543D02*
X27228D01*
G01X27331Y1718468D02*
X27303D01*
G01X58769Y913506D02*
X58666D01*
G01X58844Y913581D02*
X58591D01*
G01X58919Y913656D02*
X58516D01*
G01X58994Y913731D02*
X58441D01*
G01X59069Y913806D02*
X58366D01*
G01X59144Y913881D02*
X58291D01*
G01X59219Y913956D02*
X58216D01*
G01X59294Y914031D02*
X58141D01*
G01X59369Y914106D02*
X58066D01*
G01X59444Y914181D02*
X57991D01*
G01X59519Y914256D02*
X57916D01*
G01X59594Y914331D02*
X57841D01*
G01X59669Y914406D02*
X57766D01*
G01X59744Y914481D02*
X57691D01*
G01X57648Y914565D02*
X59801Y914548D01*
G01X59854Y914591D02*
X58717Y913453D01*
G01D02*
X57578Y914593D01*
G01X57637D02*
X59797D01*
G01X59853D02*
X57578D01*
G01X59781Y914518D02*
X57653D01*
G01X59706Y914443D02*
X57728D01*
G01X59631Y914368D02*
X57803D01*
G01X59556Y914293D02*
X57878D01*
G01X59481Y914218D02*
X57953D01*
G01X59406Y914143D02*
X58028D01*
G01X59331Y914068D02*
X58103D01*
G01X59256Y913993D02*
X58178D01*
G01X59181Y913918D02*
X58253D01*
G01X59106Y913843D02*
X58328D01*
G01X59031Y913768D02*
X58403D01*
G01X58956Y913693D02*
X58478D01*
G01X58881Y913618D02*
X58553D01*
G01X58806Y913543D02*
X58628D01*
G01X58731Y913468D02*
X58703D01*
G01X35506Y1089131D02*
Y1089234D01*
G01X35581Y1089056D02*
Y1089309D01*
G01X35656Y1088981D02*
Y1089384D01*
G01X35731Y1088906D02*
Y1089459D01*
G01X35806Y1088831D02*
Y1089534D01*
G01X35881Y1088756D02*
Y1089609D01*
G01X35956Y1088681D02*
Y1089684D01*
G01X36031Y1088606D02*
Y1089759D01*
G01X36106Y1088531D02*
Y1089834D01*
G01X36181Y1088456D02*
Y1089909D01*
G01X36256Y1088381D02*
Y1089984D01*
G01X36331Y1088306D02*
Y1090059D01*
G01X36406Y1088231D02*
Y1090134D01*
G01X36481Y1088156D02*
Y1090209D01*
G01X36565Y1090252D02*
X36548Y1088099D01*
G01X36591Y1088046D02*
X35453Y1089183D01*
G01D02*
X36593Y1090322D01*
G01Y1090263D02*
Y1088103D01*
G01Y1088047D02*
Y1090322D01*
G01X36518Y1088119D02*
Y1090247D01*
G01X36443Y1088194D02*
Y1090172D01*
G01X36368Y1088269D02*
Y1090097D01*
G01X36293Y1088344D02*
Y1090022D01*
G01X36218Y1088419D02*
Y1089947D01*
G01X36143Y1088494D02*
Y1089872D01*
G01X36068Y1088569D02*
Y1089797D01*
G01X35993Y1088644D02*
Y1089722D01*
G01X35918Y1088719D02*
Y1089647D01*
G01X35843Y1088794D02*
Y1089572D01*
G01X35768Y1088869D02*
Y1089497D01*
G01X35693Y1088944D02*
Y1089422D01*
G01X35618Y1089019D02*
Y1089347D01*
G01X35543Y1089094D02*
Y1089272D01*
G01X35468Y1089169D02*
Y1089197D01*
G01X35452Y1652688D02*
X35349D01*
G01X35527Y1652763D02*
X35274D01*
G01X35602Y1652838D02*
X35199D01*
G01X35677Y1652913D02*
X35124D01*
G01X35752Y1652988D02*
X35049D01*
G01X35827Y1653063D02*
X34974D01*
G01X35902Y1653138D02*
X34899D01*
G01X35977Y1653213D02*
X34824D01*
G01X36052Y1653288D02*
X34749D01*
G01X36127Y1653363D02*
X34674D01*
G01X36202Y1653438D02*
X34599D01*
G01X36277Y1653513D02*
X34524D01*
G01X36352Y1653588D02*
X34449D01*
G01X36427Y1653663D02*
X34374D01*
G01X34331Y1653747D02*
X36484Y1653730D01*
G01X36537Y1653773D02*
X35400Y1652635D01*
G01D02*
X34261Y1653775D01*
G01X34320D02*
X36480D01*
G01X36536D02*
X34261D01*
G01X36464Y1653700D02*
X34336D01*
G01X36389Y1653625D02*
X34411D01*
G01X36314Y1653550D02*
X34486D01*
G01X36239Y1653475D02*
X34561D01*
G01X36164Y1653400D02*
X34636D01*
G01X36089Y1653325D02*
X34711D01*
G01X36014Y1653250D02*
X34786D01*
G01X35939Y1653175D02*
X34861D01*
G01X35864Y1653100D02*
X34936D01*
G01X35789Y1653025D02*
X35011D01*
G01X35714Y1652950D02*
X35086D01*
G01X35639Y1652875D02*
X35161D01*
G01X35564Y1652800D02*
X35236D01*
G01X35489Y1652725D02*
X35311D01*
G01X35414Y1652650D02*
X35386D01*
G01X115656Y566914D02*
Y567017D01*
G01X115731Y566839D02*
Y567092D01*
G01X115806Y566764D02*
Y567167D01*
G01X115881Y566689D02*
Y567242D01*
G01X115956Y566614D02*
Y567317D01*
G01X116031Y566539D02*
Y567392D01*
G01X116106Y566464D02*
Y567467D01*
G01X116181Y566389D02*
Y567542D01*
G01X116256Y566314D02*
Y567617D01*
G01X116331Y566239D02*
Y567692D01*
G01X116406Y566164D02*
Y567767D01*
G01X116481Y566089D02*
Y567842D01*
G01X116556Y566014D02*
Y567917D01*
G01X116631Y565939D02*
Y567992D01*
G01X116715Y568035D02*
X116698Y565882D01*
G01X116741Y565829D02*
X115603Y566966D01*
G01D02*
X116743Y568105D01*
G01Y568046D02*
Y565886D01*
G01Y565830D02*
Y568105D01*
G01X116668Y565902D02*
Y568030D01*
G01X116593Y565977D02*
Y567955D01*
G01X116518Y566052D02*
Y567880D01*
G01X116443Y566127D02*
Y567805D01*
G01X116368Y566202D02*
Y567730D01*
G01X116293Y566277D02*
Y567655D01*
G01X116218Y566352D02*
Y567580D01*
G01X116143Y566427D02*
Y567505D01*
G01X116068Y566502D02*
Y567430D01*
G01X115993Y566577D02*
Y567355D01*
G01X115918Y566652D02*
Y567280D01*
G01X115843Y566727D02*
Y567205D01*
G01X115768Y566802D02*
Y567130D01*
G01X115693Y566877D02*
Y567055D01*
G01X115618Y566952D02*
Y566980D01*
G01X131448Y718912D02*
X131551D01*
G01X131373Y718837D02*
X131626D01*
G01X131298Y718762D02*
X131701D01*
G01X131223Y718687D02*
X131776D01*
G01X131148Y718612D02*
X131851D01*
G01X131073Y718537D02*
X131926D01*
G01X130998Y718462D02*
X132001D01*
G01X130923Y718387D02*
X132076D01*
G01X130848Y718312D02*
X132151D01*
G01X130773Y718237D02*
X132226D01*
G01X130698Y718162D02*
X132301D01*
G01X130623Y718087D02*
X132376D01*
G01X130548Y718012D02*
X132451D01*
G01X130473Y717937D02*
X132526D01*
G01X132569Y717853D02*
X130416Y717870D01*
G01X130363Y717827D02*
X131500Y718965D01*
G01D02*
X132639Y717825D01*
G01X132580D02*
X130420D01*
G01X130364D02*
X132639D01*
G01X130436Y717900D02*
X132564D01*
G01X130511Y717975D02*
X132489D01*
G01X130586Y718050D02*
X132414D01*
G01X130661Y718125D02*
X132339D01*
G01X130736Y718200D02*
X132264D01*
G01X130811Y718275D02*
X132189D01*
G01X130886Y718350D02*
X132114D01*
G01X130961Y718425D02*
X132039D01*
G01X131036Y718500D02*
X131964D01*
G01X131111Y718575D02*
X131889D01*
G01X131186Y718650D02*
X131814D01*
G01X131261Y718725D02*
X131739D01*
G01X131336Y718800D02*
X131664D01*
G01X131411Y718875D02*
X131589D01*
G01X131486Y718950D02*
X131514D01*
G01X115656Y1255891D02*
Y1255994D01*
G01X115731Y1255816D02*
Y1256069D01*
G01X115806Y1255741D02*
Y1256144D01*
G01X115881Y1255666D02*
Y1256219D01*
G01X115956Y1255591D02*
Y1256294D01*
G01X116031Y1255516D02*
Y1256369D01*
G01X116106Y1255441D02*
Y1256444D01*
G01X116181Y1255366D02*
Y1256519D01*
G01X116256Y1255291D02*
Y1256594D01*
G01X116331Y1255216D02*
Y1256669D01*
G01X116406Y1255141D02*
Y1256744D01*
G01X116481Y1255066D02*
Y1256819D01*
G01X116556Y1254991D02*
Y1256894D01*
G01X116631Y1254916D02*
Y1256969D01*
G01X116715Y1257012D02*
X116698Y1254859D01*
G01X116741Y1254806D02*
X115603Y1255943D01*
G01D02*
X116743Y1257082D01*
G01Y1257023D02*
Y1254863D01*
G01Y1254807D02*
Y1257082D01*
G01X116668Y1254879D02*
Y1257007D01*
G01X116593Y1254954D02*
Y1256932D01*
G01X116518Y1255029D02*
Y1256857D01*
G01X116443Y1255104D02*
Y1256782D01*
G01X116368Y1255179D02*
Y1256707D01*
G01X116293Y1255254D02*
Y1256632D01*
G01X116218Y1255329D02*
Y1256557D01*
G01X116143Y1255404D02*
Y1256482D01*
G01X116068Y1255479D02*
Y1256407D01*
G01X115993Y1255554D02*
Y1256332D01*
G01X115918Y1255629D02*
Y1256257D01*
G01X115843Y1255704D02*
Y1256182D01*
G01X115768Y1255779D02*
Y1256107D01*
G01X115693Y1255854D02*
Y1256032D01*
G01X115618Y1255929D02*
Y1255957D01*
G01X141548Y678612D02*
X141651D01*
G01X141473Y678537D02*
X141726D01*
G01X141398Y678462D02*
X141801D01*
G01X141323Y678387D02*
X141876D01*
G01X141248Y678312D02*
X141951D01*
G01X141173Y678237D02*
X142026D01*
G01X141098Y678162D02*
X142101D01*
G01X141023Y678087D02*
X142176D01*
G01X140948Y678012D02*
X142251D01*
G01X140873Y677937D02*
X142326D01*
G01X140798Y677862D02*
X142401D01*
G01X140723Y677787D02*
X142476D01*
G01X140648Y677712D02*
X142551D01*
G01X140573Y677637D02*
X142626D01*
G01X142669Y677553D02*
X140516Y677570D01*
G01X140463Y677527D02*
X141600Y678665D01*
G01D02*
X142739Y677525D01*
G01X142680D02*
X140520D01*
G01X140464D02*
X142739D01*
G01X140536Y677600D02*
X142664D01*
G01X140611Y677675D02*
X142589D01*
G01X140686Y677750D02*
X142514D01*
G01X140761Y677825D02*
X142439D01*
G01X140836Y677900D02*
X142364D01*
G01X140911Y677975D02*
X142289D01*
G01X140986Y678050D02*
X142214D01*
G01X141061Y678125D02*
X142139D01*
G01X141136Y678200D02*
X142064D01*
G01X141211Y678275D02*
X141989D01*
G01X141286Y678350D02*
X141914D01*
G01X141361Y678425D02*
X141839D01*
G01X141436Y678500D02*
X141764D01*
G01X141511Y678575D02*
X141689D01*
G01X141586Y678650D02*
X141614D01*
G01X147948Y1397816D02*
X148051D01*
G01X147873Y1397741D02*
X148126D01*
G01X147798Y1397666D02*
X148201D01*
G01X147723Y1397591D02*
X148276D01*
G01X147648Y1397516D02*
X148351D01*
G01X147573Y1397441D02*
X148426D01*
G01X147498Y1397366D02*
X148501D01*
G01X147423Y1397291D02*
X148576D01*
G01X147348Y1397216D02*
X148651D01*
G01X147273Y1397141D02*
X148726D01*
G01X147198Y1397066D02*
X148801D01*
G01X147123Y1396991D02*
X148876D01*
G01X147048Y1396916D02*
X148951D01*
G01X146973Y1396841D02*
X149026D01*
G01X149069Y1396757D02*
X146916Y1396774D01*
G01X146863Y1396731D02*
X148000Y1397869D01*
G01D02*
X149139Y1396729D01*
G01X149080D02*
X146920D01*
G01X146864D02*
X149139D01*
G01X146936Y1396804D02*
X149064D01*
G01X147011Y1396879D02*
X148989D01*
G01X147086Y1396954D02*
X148914D01*
G01X147161Y1397029D02*
X148839D01*
G01X147236Y1397104D02*
X148764D01*
G01X147311Y1397179D02*
X148689D01*
G01X147386Y1397254D02*
X148614D01*
G01X147461Y1397329D02*
X148539D01*
G01X147536Y1397404D02*
X148464D01*
G01X147611Y1397479D02*
X148389D01*
G01X147686Y1397554D02*
X148314D01*
G01X147761Y1397629D02*
X148239D01*
G01X147836Y1397704D02*
X148164D01*
G01X147911Y1397779D02*
X148089D01*
G01X147986Y1397854D02*
X148014D01*
G01X165417Y1433831D02*
X165520D01*
G01X165342Y1433756D02*
X165595D01*
G01X165267Y1433681D02*
X165670D01*
G01X165192Y1433606D02*
X165745D01*
G01X165117Y1433531D02*
X165820D01*
G01X165042Y1433456D02*
X165895D01*
G01X164967Y1433381D02*
X165970D01*
G01X164892Y1433306D02*
X166045D01*
G01X164817Y1433231D02*
X166120D01*
G01X164742Y1433156D02*
X166195D01*
G01X164667Y1433081D02*
X166270D01*
G01X164592Y1433006D02*
X166345D01*
G01X164517Y1432931D02*
X166420D01*
G01X164442Y1432856D02*
X166495D01*
G01X166538Y1432772D02*
X164385Y1432789D01*
G01X164332Y1432746D02*
X165469Y1433884D01*
G01D02*
X166608Y1432744D01*
G01X166549D02*
X164389D01*
G01X164333D02*
X166608D01*
G01X164405Y1432819D02*
X166533D01*
G01X164480Y1432894D02*
X166458D01*
G01X164555Y1432969D02*
X166383D01*
G01X164630Y1433044D02*
X166308D01*
G01X164705Y1433119D02*
X166233D01*
G01X164780Y1433194D02*
X166158D01*
G01X164855Y1433269D02*
X166083D01*
G01X164930Y1433344D02*
X166008D01*
G01X165005Y1433419D02*
X165933D01*
G01X165080Y1433494D02*
X165858D01*
G01X165155Y1433569D02*
X165783D01*
G01X165230Y1433644D02*
X165708D01*
G01X165305Y1433719D02*
X165633D01*
G01X165380Y1433794D02*
X165558D01*
G01X165455Y1433869D02*
X165483D01*
G01X138617Y1418631D02*
X138720D01*
G01X138542Y1418556D02*
X138795D01*
G01X138467Y1418481D02*
X138870D01*
G01X138392Y1418406D02*
X138945D01*
G01X138317Y1418331D02*
X139020D01*
G01X138242Y1418256D02*
X139095D01*
G01X138167Y1418181D02*
X139170D01*
G01X138092Y1418106D02*
X139245D01*
G01X138017Y1418031D02*
X139320D01*
G01X137942Y1417956D02*
X139395D01*
G01X137867Y1417881D02*
X139470D01*
G01X137792Y1417806D02*
X139545D01*
G01X137717Y1417731D02*
X139620D01*
G01X137642Y1417656D02*
X139695D01*
G01X139738Y1417572D02*
X137585Y1417589D01*
G01X137532Y1417546D02*
X138669Y1418684D01*
G01D02*
X139808Y1417544D01*
G01X139749D02*
X137589D01*
G01X137533D02*
X139808D01*
G01X137605Y1417619D02*
X139733D01*
G01X137680Y1417694D02*
X139658D01*
G01X137755Y1417769D02*
X139583D01*
G01X137830Y1417844D02*
X139508D01*
G01X137905Y1417919D02*
X139433D01*
G01X137980Y1417994D02*
X139358D01*
G01X138055Y1418069D02*
X139283D01*
G01X138130Y1418144D02*
X139208D01*
G01X138205Y1418219D02*
X139133D01*
G01X138280Y1418294D02*
X139058D01*
G01X138355Y1418369D02*
X138983D01*
G01X138430Y1418444D02*
X138908D01*
G01X138505Y1418519D02*
X138833D01*
G01X138580Y1418594D02*
X138758D01*
G01X138655Y1418669D02*
X138683D01*
G54D17*
G01X126900Y873370D02*
X126880Y873400D01*
G01X127440Y873370D02*
X126900D01*
G01X127460Y873380D02*
X127440Y873370D01*
G01X127570Y873430D02*
X127460Y873380D01*
G01X127580Y873440D02*
X127570Y873430D01*
G01X133170Y878620D02*
X127580Y873440D01*
G01X126910Y873370D02*
Y873430D01*
G01X127010Y873370D02*
Y873520D01*
G01X127120Y873610D02*
Y873370D01*
G01X127210D02*
Y873710D01*
G01X127320Y873800D02*
Y873370D01*
G01X127410D02*
Y873890D01*
G01X127510Y873990D02*
Y873400D01*
G01X127620Y873470D02*
Y874080D01*
G01X127710Y874170D02*
Y873560D01*
G01X127820Y873650D02*
Y874260D01*
G01X127910Y874360D02*
Y873750D01*
G01X128010Y873840D02*
Y874450D01*
G01X128120Y874540D02*
Y873930D01*
G01X128210Y874020D02*
Y874640D01*
G01X128320Y874730D02*
Y874120D01*
G01X128410Y874210D02*
Y874820D01*
G01X128510Y874920D02*
Y874300D01*
G01X128620Y874400D02*
Y875010D01*
G01X128710Y875100D02*
Y874490D01*
G01X128820Y874580D02*
Y875200D01*
G01X128910Y875290D02*
Y874680D01*
G01X129010Y874770D02*
Y875380D01*
G01X129120Y875480D02*
Y874860D01*
G01X129210Y874950D02*
Y875570D01*
G01X129320Y875660D02*
Y875050D01*
G01X129410Y875140D02*
Y875750D01*
G01X129510Y875850D02*
Y875230D01*
G01X129620Y875330D02*
Y875940D01*
G01X129710Y876030D02*
Y875420D01*
G01X129820Y875510D02*
Y876120D01*
G01X129910Y876220D02*
Y875610D01*
G01X130010Y875700D02*
Y876310D01*
G01X130120Y876400D02*
Y875790D01*
G01X130210Y875880D02*
Y876500D01*
G01X130320Y876590D02*
Y875980D01*
G01X130410Y876070D02*
Y876680D01*
G01X130510Y876780D02*
Y876160D01*
G01X130620Y876250D02*
Y876870D01*
G01X130710Y876960D02*
Y876350D01*
G01X130820Y876440D02*
Y877060D01*
G01X130910Y877150D02*
Y876530D01*
G01X131010Y876620D02*
Y877240D01*
G01X131120Y877340D02*
Y876720D01*
G01X131210Y876810D02*
Y877430D01*
G01X131320Y877520D02*
Y876900D01*
G01X131410Y876990D02*
Y877620D01*
G01X131510Y877710D02*
Y877090D01*
G01X131620Y877180D02*
Y877800D01*
G01X130220Y877770D02*
Y878280D01*
G01X130260Y877730D02*
X130220Y877770D01*
G01X130720Y877730D02*
X130260D01*
G01X130760Y877770D02*
X130720Y877730D01*
G01X130320D02*
Y887980D01*
G01X130510Y887910D02*
Y877730D01*
G01X130710D02*
Y887750D01*
G01X129410Y880380D02*
Y878950D01*
G01X130150Y878370D02*
X130220Y878280D01*
G01X130100Y878390D02*
X130150Y878370D01*
G01X130090Y878390D02*
X130100D01*
G01X129840Y878510D02*
X130090Y878390D01*
G01X129830Y878530D02*
X129840Y878510D01*
G01X129410Y878960D02*
X129830Y878530D01*
G01X130210Y878290D02*
Y879020D01*
G01X129880Y879130D02*
X129810Y879240D01*
G01X130050Y878960D02*
X129880Y879130D01*
G01X130160Y878940D02*
X130050Y878960D01*
G01X130220Y879030D02*
X130160Y878940D01*
G01X129910Y879100D02*
Y878480D01*
G01X130010Y878430D02*
Y879000D01*
G01X130120Y878950D02*
Y878380D01*
G01X129710Y878640D02*
Y880320D01*
G01X129510D02*
Y878850D01*
G01X130870Y878940D02*
X133000Y879120D01*
G01X130760Y879040D02*
X130870Y878940D01*
G01X130760Y878370D02*
Y877770D01*
G01X130850Y878470D02*
X130760Y878370D01*
G01X132200Y878590D02*
X130850Y878470D01*
G01X130820Y878430D02*
Y878990D01*
G01X130910Y878940D02*
Y878480D01*
G01X131010Y878490D02*
Y878960D01*
G01X131120D02*
Y878490D01*
G01X131210Y878500D02*
Y878970D01*
G01X131320Y878980D02*
Y878510D01*
G01X131410Y878520D02*
Y878990D01*
G01X131510Y879000D02*
Y878530D01*
G01X131620Y878540D02*
Y879010D01*
G01X132270Y878420D02*
X126880Y873400D01*
G01X129800Y879350D02*
X129810Y879240D01*
G01X129890Y879400D02*
X129800Y879350D01*
G01X130120Y879400D02*
X129890D01*
G01X130220Y879300D02*
X130120Y879400D01*
G01X130220Y879030D02*
Y879300D01*
G01X129820Y879230D02*
Y878540D01*
G01X128830Y879410D02*
X128810Y879440D01*
G01X128860Y879400D02*
X128830Y879410D01*
G01X129060Y879400D02*
X128860D01*
G01X129100Y879390D02*
X129060Y879400D01*
G01X129150Y879370D02*
X129100Y879390D01*
G01X129210Y879320D02*
X129150Y879370D01*
G01X129250Y879230D02*
X129210Y879320D01*
G01X129410Y878960D02*
X129250Y879230D01*
G01X128820Y879440D02*
Y880270D01*
G01X129010Y879400D02*
Y882290D01*
G01X129210Y882280D02*
Y879300D01*
G01X129820Y879350D02*
Y880320D01*
G01X130010D02*
Y879400D01*
G01X130210Y879310D02*
Y880420D01*
G01X130120Y880320D02*
Y879400D01*
G01X130220Y880420D02*
X130120Y880320D01*
G01X129910Y879400D02*
Y880320D01*
G01X129210Y881650D02*
X129320Y881760D01*
G01X129240Y881380D02*
X129210Y881650D01*
G01X129270Y881100D02*
X129240Y881380D01*
G01X129280Y880980D02*
X129270Y881100D01*
G01X129300Y880880D02*
X129280Y880980D01*
G01X129340Y880630D02*
X129300Y880880D01*
G01X129340Y880620D02*
Y880630D01*
G01X129360Y880530D02*
X129340Y880620D01*
G01X129360Y880520D02*
Y880530D01*
G01X129380Y880400D02*
X129360Y880520D01*
G01X129480Y880320D02*
X129380Y880400D01*
G01X130120Y880320D02*
X129480D01*
G01X128810Y880260D02*
Y879440D01*
G01X128820Y880280D02*
X128810Y880260D01*
G01X128830Y880310D02*
X128820Y880280D01*
G01X128850Y880340D02*
X128830Y880310D01*
G01X128870Y880420D02*
X128850Y880340D01*
G01X128860Y880440D02*
X128870Y880420D01*
G01X128820Y880680D02*
X128860Y880440D01*
G01X128750Y881180D02*
X128820Y880680D01*
G01X128740Y881300D02*
X128750Y881180D01*
G01X128740Y881360D02*
Y881300D01*
G01X128720Y881520D02*
X128740Y881360D01*
G01X128710Y881660D02*
X128720Y881520D01*
G01X129320Y879120D02*
Y880770D01*
G01X129620Y880320D02*
Y878750D01*
G01X130220Y880420D02*
Y886260D01*
G01X128710Y884330D02*
Y881640D01*
G01Y881660D02*
X128610Y881760D01*
G01X129660D02*
X129320D01*
G01X129710Y881800D02*
X129660Y881760D01*
G01X129320Y881750D02*
Y884380D01*
G01X129710Y884250D02*
Y881800D01*
G01X129660Y884300D02*
X129710Y884250D01*
G01X129380Y884300D02*
X129660D01*
G01X129620Y881760D02*
Y884300D01*
G01X129510D02*
Y881760D01*
G01X129410D02*
Y884300D01*
G01X129100Y883850D02*
X129140D01*
G01X129000Y883750D02*
X129100Y883850D01*
G01X129000Y882310D02*
Y883750D01*
G01X129100Y882210D02*
X129000Y882310D01*
G01X129140Y882210D02*
X129100D01*
G01X129250Y882310D02*
X129140Y882210D01*
G01X129250Y883750D02*
Y882310D01*
G01X129140Y883850D02*
X129250Y883750D01*
G01X129120Y883850D02*
Y885820D01*
G01X129010Y885530D02*
Y883760D01*
G01X128580Y881760D02*
X128610D01*
G01X128540Y881800D02*
X128580Y881760D01*
G01X128540Y884250D02*
Y881800D01*
G01X128580Y884300D02*
X128540Y884250D01*
G01X128680Y884300D02*
X128580D01*
G01X128620Y881750D02*
Y884300D01*
G01X129120Y882210D02*
Y879380D01*
G01X128910Y879400D02*
Y885160D01*
G01X128780Y884380D02*
X128680Y884300D01*
G01X128780Y884430D02*
Y884380D01*
G01X128870Y884990D02*
X128780Y884430D01*
G01X128910Y885170D02*
X128870Y884990D01*
G01X128820Y884610D02*
Y880740D01*
G01X129350Y884810D02*
X129440Y885220D01*
G01X129300Y884520D02*
X129350Y884810D01*
G01X129300Y884490D02*
Y884520D01*
G01X129280Y884410D02*
X129300Y884490D01*
G01X129380Y884300D02*
X129280Y884410D01*
G01X129320Y884600D02*
Y886190D01*
G01X129520Y885500D02*
X129440Y885220D01*
G01X129530Y885510D02*
X129520Y885500D01*
G01X129560Y885620D02*
X129530Y885510D01*
G01X129570Y885620D02*
X129560D01*
G01X129610Y885730D02*
X129570Y885620D01*
G01X129620Y885740D02*
X129610Y885730D01*
G01X129620Y886600D02*
Y885740D01*
G01X129510Y885460D02*
Y886490D01*
G01X128950Y885290D02*
X128910Y885170D01*
G01X128970Y885400D02*
X128950Y885290D01*
G01X129050Y885640D02*
X128970Y885400D01*
G01X129090Y885750D02*
X129050Y885640D01*
G01X129110Y885810D02*
X129090Y885750D01*
G01X129410Y885100D02*
Y886350D01*
G01X129210Y886030D02*
Y883780D01*
G01X130170Y886350D02*
X130220Y886260D01*
G01X130070Y886340D02*
X130170Y886350D01*
G01X129960Y886270D02*
X130070Y886340D01*
G01X129940Y886250D02*
X129960Y886270D01*
G01X129720Y885950D02*
X129940Y886250D01*
G01X129710Y885940D02*
X129720Y885950D01*
G01X129710Y885930D02*
Y885940D01*
G01X129620Y885740D02*
X129710Y885930D01*
G01X130210Y886270D02*
Y887990D01*
G01X130010Y887970D02*
Y886310D01*
G01X129820Y886080D02*
Y887890D01*
G01X131680Y886330D02*
X131580Y886430D01*
G01X131720Y886220D02*
X131680Y886260D01*
G01X129170Y885960D02*
X129110Y885810D01*
G01X129180Y885970D02*
X129170Y885960D01*
G01X129460Y887220D02*
X129450Y887280D01*
G01X129460Y887210D02*
Y887220D01*
G01X129490Y887100D02*
X129460Y887210D01*
G01X129490Y887090D02*
Y887100D01*
G01X129540Y886960D02*
X129490Y887090D01*
G01X129550Y886960D02*
X129540D01*
G01X129580Y886900D02*
X129550Y886960D01*
G01X129600Y886880D02*
X129580Y886900D01*
G01X129650Y886820D02*
X129600Y886880D01*
G01X129670Y886800D02*
X129650Y886820D01*
G01X129670Y886660D02*
Y886800D01*
G01X129500Y886480D02*
X129670Y886660D01*
G01X129490Y886470D02*
X129500Y886480D01*
G01X129180Y885970D02*
X129490Y886470D01*
G01X129510Y887030D02*
Y887550D01*
G01X130820Y887600D02*
Y886440D01*
G01X130870Y886490D02*
X131580Y886430D01*
G01X131620Y886400D02*
Y886950D01*
G01X130890Y887240D02*
X130900Y887270D01*
G01X130880Y887160D02*
X130890Y887240D01*
G01X130860Y887090D02*
X130880Y887160D01*
G01X130860Y887080D02*
Y887090D01*
G01X130950Y886950D02*
X130860Y887080D01*
G01X131560Y886900D02*
X130950Y886950D01*
G01X131670Y887000D02*
X131560Y886900D01*
G01X130910Y887000D02*
Y886490D01*
G01X130760Y886390D02*
Y879040D01*
G01X130870Y886490D02*
X130760Y886390D01*
G01X131510Y886910D02*
Y886440D01*
G01X131410Y886450D02*
Y886920D01*
G01X131320D02*
Y886460D01*
G01X131210D02*
Y886930D01*
G01X131120Y886940D02*
Y886470D01*
G01X131010Y886480D02*
Y886950D01*
G01X129450Y887350D02*
Y887280D01*
G01X129460Y887360D02*
X129450Y887350D01*
G01X129530Y887620D02*
X129460Y887360D01*
G01X129540Y887630D02*
X129530Y887620D01*
G01X129710Y887830D02*
X129540Y887630D01*
G01X129720Y887840D02*
X129710Y887830D01*
G01X129950Y887960D02*
X129720Y887840D01*
G01X129970Y887970D02*
X129950Y887960D01*
G01X130250Y887990D02*
X129970Y887970D01*
G01X130260Y887990D02*
X130250D01*
G01X130520Y887910D02*
X130260Y887990D01*
G01X130530Y887900D02*
X130520Y887910D01*
G01X130730Y887740D02*
X130530Y887900D01*
G01X130750Y887730D02*
X130730Y887740D01*
G01X130870Y887500D02*
X130750Y887730D01*
G01X130870Y887480D02*
Y887500D01*
G01X130890Y887360D02*
X130870Y887480D01*
G01X130890Y887350D02*
Y887360D01*
G01X130900Y887290D02*
X130890Y887350D01*
G01X130900Y887270D02*
Y887290D01*
G01X129620Y886860D02*
Y887720D01*
G01X129710Y887830D02*
Y885940D01*
G01X129910Y886220D02*
Y887940D01*
G01X130120Y887980D02*
Y886350D01*
G01X130620Y887840D02*
Y877730D01*
G01X130410D02*
Y887940D01*
G01X130710Y888250D02*
Y888880D01*
G01X130620Y888980D02*
Y888350D01*
G01X130510Y888440D02*
Y889080D01*
G01X130410Y889170D02*
Y888540D01*
G01X130320Y888640D02*
Y889270D01*
G01X130210Y889360D02*
Y888740D01*
G01X130120Y888830D02*
Y889460D01*
G01X130010Y889560D02*
Y888930D01*
G01X129910Y889030D02*
Y889660D01*
G01X129710Y889850D02*
Y889220D01*
G01X129510Y889410D02*
Y890040D01*
G01X130820Y888790D02*
Y888160D01*
G01X130910Y888060D02*
Y888690D01*
G01X131010Y888590D02*
Y887960D01*
G01X131120Y887860D02*
Y888500D01*
G01X131210Y888400D02*
Y887770D01*
G01X131320Y887670D02*
Y888310D01*
G01X131410Y888210D02*
Y887580D01*
G01X131510Y887480D02*
Y888110D01*
G01X131600Y888030D02*
X131680Y888000D01*
G01Y887280D02*
X131650Y887350D01*
G01X131620Y887380D02*
Y888020D01*
G01X131650Y887350D02*
X126910Y891930D01*
G01X127520Y891960D02*
X131600Y888030D01*
G01X129820Y889120D02*
Y889750D01*
G01X129620Y889940D02*
Y889310D01*
G01X129410Y889510D02*
Y890140D01*
G01X129320Y890240D02*
Y889610D01*
G01X129210Y889700D02*
Y890330D01*
G01X129120Y890430D02*
Y889800D01*
G01X129010Y889900D02*
Y890520D01*
G01X128910Y890620D02*
Y889990D01*
G01X128710Y890180D02*
Y890810D01*
G01X128510Y891010D02*
Y890380D01*
G01X128320Y890570D02*
Y891200D01*
G01X128410Y891100D02*
Y890480D01*
G01X128210Y890670D02*
Y891290D01*
G01X128120Y891390D02*
Y890760D01*
G01X128010Y890860D02*
Y891490D01*
G01X127910Y891590D02*
Y890960D01*
G01X127820Y891050D02*
Y891680D01*
G01X127710Y891780D02*
Y891150D01*
G01X127620Y891250D02*
Y891870D01*
G01X127410Y891980D02*
Y891440D01*
G01X127490Y891970D02*
X127410Y891980D01*
G01X127520Y891960D02*
X127490Y891970D01*
G01X127510Y891350D02*
Y891960D01*
G01X126920Y891980D02*
X126910Y891930D01*
G01X127410Y891980D02*
X126920D01*
G01X126910Y891920D02*
Y891960D01*
G01X127010Y891980D02*
Y891830D01*
G01X127120Y891730D02*
Y891980D01*
G01X127210D02*
Y891630D01*
G01X127320Y891540D02*
Y891980D01*
G01X128620Y890910D02*
Y890280D01*
G01X128820Y890090D02*
Y890720D01*
G01X144410Y875670D02*
Y875010D01*
G01X144320Y875110D02*
Y875770D01*
G01X144210Y875860D02*
Y875210D01*
G01X144120Y875310D02*
Y875960D01*
G01X144010Y876060D02*
Y875400D01*
G01X143910Y875500D02*
Y876150D01*
G01X143820Y876250D02*
Y875600D01*
G01X143710Y875690D02*
Y876350D01*
G01X143620Y876440D02*
Y875790D01*
G01X143510Y875880D02*
Y876540D01*
G01X143410Y876640D02*
Y875980D01*
G01X143320Y876080D02*
Y876730D01*
G01X143210Y876830D02*
Y876185D01*
G01Y876180D02*
Y876230D01*
G01X143120Y876270D02*
Y876310D01*
G01Y876270D02*
Y876920D01*
G01X143010Y877020D02*
Y876370D01*
G01X142910Y876470D02*
Y877120D01*
G01X142820Y877220D02*
Y876560D01*
G01X142710Y876660D02*
Y877310D01*
G01X142620Y877410D02*
Y876750D01*
G01X142510Y876850D02*
Y877510D01*
G01X142410Y877600D02*
Y876950D01*
G01X142320Y877050D02*
Y877700D01*
G01X142210Y877790D02*
Y877140D01*
G01X142120Y877240D02*
Y877890D01*
G01X142010Y877990D02*
Y877330D01*
G01X141910Y877430D02*
Y878090D01*
G01X141820Y878180D02*
Y877530D01*
G01X141710Y877620D02*
Y878280D01*
G01X141510Y878470D02*
Y877820D01*
G01X141320Y878010D02*
Y878660D01*
G01X131710Y877890D02*
Y877270D01*
G01X131820Y877370D02*
Y877990D01*
G01X131910Y878080D02*
Y877460D01*
G01X132010Y877550D02*
Y878170D01*
G01X132120Y878270D02*
Y877650D01*
G01X132320Y877830D02*
Y879070D01*
G01X132510Y879080D02*
Y878020D01*
G01X133110Y879200D02*
X136590Y882430D01*
G01X133110Y879190D02*
Y879200D01*
G01X133060Y879150D02*
X133110Y879190D01*
G01X133000Y879120D02*
X133060Y879150D01*
G01X136910Y879460D02*
Y878990D01*
G01X136710Y878980D02*
Y879440D01*
G01X136510Y879420D02*
Y878960D01*
G01X136320Y878940D02*
Y879410D01*
G01X136120Y879390D02*
Y878920D01*
G01X135910Y878900D02*
Y879370D01*
G01X135710Y879360D02*
Y878890D01*
G01X135510Y878870D02*
Y879340D01*
G01X135320Y879320D02*
Y878850D01*
G01X135120Y878840D02*
Y879310D01*
G01X134910Y879290D02*
Y878820D01*
G01X134710Y878800D02*
Y879270D01*
G01X134510Y879250D02*
Y878790D01*
G01X134320Y878770D02*
Y879240D01*
G01X134120Y879220D02*
Y878750D01*
G01X134010Y878740D02*
Y879250D01*
G01X133710Y879750D02*
Y878720D01*
G01X133510Y878700D02*
Y879570D01*
G01X133200Y878640D02*
X133170Y878620D01*
G01X133300Y878680D02*
X133200Y878640D01*
G01X133310Y878680D02*
X133300D01*
G01X133320D02*
X133310D01*
G01X133320Y879380D02*
Y878680D01*
G01X133120Y878580D02*
Y879200D01*
G01X133010Y879130D02*
Y878480D01*
G01X132910Y878390D02*
Y879120D01*
G01X132820Y879110D02*
Y878300D01*
G01X132710Y878200D02*
Y879100D01*
G01X132620Y879090D02*
Y878110D01*
G01X132410Y877920D02*
Y879070D01*
G01X132210Y879060D02*
Y878580D01*
G01X131710Y879010D02*
Y878550D01*
G01X131820D02*
Y879020D01*
G01X131910Y879030D02*
Y878570D01*
G01X132010D02*
Y879040D01*
G01X132120Y879050D02*
Y878580D01*
G01X132300Y878530D02*
X132270Y878420D01*
G01X132200Y878590D02*
X132300Y878530D01*
G01X132210Y877740D02*
Y878360D01*
G01X133320Y878680D02*
X138470Y879120D01*
G01X138510Y879130D02*
Y879600D01*
G01X138710Y879610D02*
Y879140D01*
G01X138910Y879160D02*
Y879630D01*
G01X139120Y879650D02*
Y879180D01*
G01X139320Y879200D02*
Y879670D01*
G01X139410Y879710D02*
Y879210D01*
G01X140060Y879220D02*
X140170Y879120D01*
G01X139990Y879250D02*
X140060Y879220D01*
G01X140210Y879070D02*
Y879760D01*
G01X140410D02*
Y878880D01*
G01X140620Y878690D02*
Y879780D01*
G01X140820Y879140D02*
Y878490D01*
G01X140910Y878400D02*
Y879050D01*
G01X141010Y878950D02*
Y878300D01*
G01X141120Y878200D02*
Y878860D01*
G01X141210Y878760D02*
Y878110D01*
G01X141410Y877920D02*
Y878570D01*
G01X141620Y878370D02*
Y877720D01*
G01X138210Y879100D02*
Y879570D01*
G01X138010Y879550D02*
Y879090D01*
G01X137820Y879070D02*
Y879540D01*
G01X137620Y879520D02*
Y879050D01*
G01X137410Y879030D02*
Y879500D01*
G01X137210Y879490D02*
Y879020D01*
G01X137120Y879010D02*
Y879480D01*
G01X137010Y879470D02*
Y879000D01*
G01X136820Y878980D02*
Y879450D01*
G01X136620Y879440D02*
Y878970D01*
G01X136410Y878950D02*
Y879420D01*
G01X136210Y879400D02*
Y878930D01*
G01X136010Y878920D02*
Y879380D01*
G01X135820Y879360D02*
Y878900D01*
G01X135620Y878880D02*
Y879350D01*
G01X135410Y879330D02*
Y878860D01*
G01X135210Y878850D02*
Y879310D01*
G01X135010Y879300D02*
Y878830D01*
G01X134820Y878810D02*
Y879280D01*
G01X134620Y879260D02*
Y878790D01*
G01X134410Y878780D02*
Y879240D01*
G01X134210Y879230D02*
Y878760D01*
G01X133990Y879390D02*
X136930Y882120D01*
G01X133970Y879270D02*
X133990Y879390D01*
G01X134070Y879220D02*
X133970Y879270D01*
G01X137320Y879490D02*
Y879030D01*
G01X137510Y879040D02*
Y879510D01*
G01X137710Y879530D02*
Y879060D01*
G01X137910Y879080D02*
Y879550D01*
G01X138120Y879560D02*
Y879090D01*
G01X138320Y879110D02*
Y879580D01*
G01X138410Y879590D02*
Y879120D01*
G01X139930Y879250D02*
X139990D01*
G01X138470Y879120D02*
X139930Y879250D01*
G01X140010Y879240D02*
Y879920D01*
G01X140190Y879770D02*
X140260Y879750D01*
G01X140110Y879820D02*
X140190Y879770D01*
G01X140320Y879750D02*
Y878980D01*
G01X140510Y878790D02*
Y879770D01*
G01X140820Y879790D02*
Y879290D01*
G01X140780Y879260D02*
X140800Y879160D01*
G01X143220Y879530D02*
Y879640D01*
G01X143210Y879530D02*
X143220D01*
G01X140860Y879330D02*
X143210Y879530D01*
G01X140780Y879260D02*
X140860Y879330D01*
G01X143120Y879630D02*
Y879520D01*
G01Y879525D02*
Y885120D01*
G01X143210Y885185D02*
Y879530D01*
G01X144260Y879770D02*
Y880660D01*
G01X144220Y879730D02*
X144260Y879770D01*
G01X143540Y879730D02*
X144220D01*
G01X143470Y879700D02*
X143540Y879730D01*
G01X143310Y879550D02*
X143470Y879700D01*
G01X143290Y879540D02*
X143310Y879550D01*
G01X143230Y879530D02*
X143290Y879540D01*
G01X144210Y880700D02*
Y879730D01*
G01X144010D02*
Y880700D01*
G01X143820D02*
Y879730D01*
G01X143620D02*
Y880700D01*
G01X142910Y879980D02*
Y879510D01*
G01X142820Y879490D02*
Y879960D01*
G01X142620Y879950D02*
Y879480D01*
G01X142410Y879460D02*
Y879930D01*
G01X142210Y879910D02*
Y879440D01*
G01X142010Y879430D02*
Y879900D01*
G01X141820Y879880D02*
Y879410D01*
G01X141620Y879390D02*
Y879860D01*
G01X141410Y879850D02*
Y879380D01*
G01X141210Y879360D02*
Y879830D01*
G01X141010Y879810D02*
Y879350D01*
G01X139820Y879240D02*
Y880110D01*
G01X139620Y880300D02*
Y879220D01*
G01X139210Y879190D02*
Y879660D01*
G01X139360Y879670D02*
X134070Y879220D01*
G01X134010Y879410D02*
Y880030D01*
G01X134210Y880220D02*
Y879600D01*
G01X134410Y879780D02*
Y880400D01*
G01X133620Y879660D02*
Y878710D01*
G01X133410Y878690D02*
Y879480D01*
G01X133210Y879290D02*
Y878650D01*
G01X138620Y879610D02*
Y879140D01*
G01X138820Y879150D02*
Y879620D01*
G01X139010Y879640D02*
Y879170D01*
G01X139450Y879740D02*
X139420Y879840D01*
G01X139360Y879670D02*
X139450Y879740D01*
G01X143410Y879650D02*
Y885430D01*
G01X142840Y879970D02*
X140260Y879750D01*
G01X142910Y879970D02*
X142840D01*
G01X143000Y880070D02*
X142910Y879970D01*
G01X143000Y884170D02*
Y880070D01*
G01X140120Y879820D02*
Y879170D01*
G01X139910Y879250D02*
Y880010D01*
G01X140110Y879830D02*
Y879820D01*
G01X140100Y879830D02*
X140110D01*
G01X140100D02*
X137410Y882420D01*
G01X137620Y882230D02*
Y881590D01*
G01X137820Y881390D02*
Y882040D01*
G01X138010Y881850D02*
Y881200D01*
G01X138210Y881010D02*
Y881650D01*
G01X138320Y881560D02*
Y880910D01*
G01X138260Y880960D02*
X139420Y879840D01*
G01X139410Y879850D02*
Y880490D01*
G01X139510Y880400D02*
Y879220D01*
G01X139710Y879230D02*
Y880210D01*
G01X139320Y879950D02*
Y880590D01*
G01X139210Y880690D02*
Y880050D01*
G01X139120Y880140D02*
Y880790D01*
G01X139010Y880880D02*
Y880240D01*
G01X138910Y880330D02*
Y880980D01*
G01X138820Y881070D02*
Y880430D01*
G01X138710Y880530D02*
Y881170D01*
G01X138620Y881270D02*
Y880620D01*
G01X138510Y880720D02*
Y881360D01*
G01X138410Y881460D02*
Y880810D01*
G01X136410Y881640D02*
Y882270D01*
G01X136210Y882080D02*
Y881460D01*
G01X136010Y881270D02*
Y881890D01*
G01X135820Y881710D02*
Y881080D01*
G01X135710Y880990D02*
Y881610D01*
G01X135620Y881520D02*
Y880900D01*
G01X135510Y880810D02*
Y881430D01*
G01X135410Y881330D02*
Y880710D01*
G01X135320Y880620D02*
Y881240D01*
G01X135210Y881150D02*
Y880530D01*
G01X135120Y880430D02*
Y881060D01*
G01X135010Y880960D02*
Y880340D01*
G01X134910Y880250D02*
Y880870D01*
G01X134820Y880780D02*
Y880150D01*
G01X134710Y880060D02*
Y880680D01*
G01X134620Y880590D02*
Y879970D01*
G01X134510Y879880D02*
Y880500D01*
G01X134320Y880310D02*
Y879690D01*
G01X134120Y879500D02*
Y880120D01*
G01X133910Y879940D02*
Y878740D01*
G01X133820Y878730D02*
Y879850D01*
G01X134540Y881700D02*
X134580Y881740D01*
G01X140710Y879790D02*
Y878590D01*
G01X140910Y879330D02*
Y879800D01*
G01X141120Y879820D02*
Y879350D01*
G01X141320Y879370D02*
Y879840D01*
G01X141510Y879850D02*
Y879380D01*
G01X141710Y879400D02*
Y879870D01*
G01X141910Y879890D02*
Y879420D01*
G01X142120Y879440D02*
Y879900D01*
G01X142320Y879920D02*
Y879460D01*
G01X142510Y879470D02*
Y879940D01*
G01X142710Y879960D02*
Y879490D01*
G01X143510Y879720D02*
Y880770D01*
G01X144220Y880700D02*
X144260Y880660D01*
G01X143580Y880700D02*
X144220D01*
G01X143480Y880800D02*
X143580Y880700D01*
G01X144120D02*
Y879730D01*
G01X143910D02*
Y880700D01*
G01X143710D02*
Y879730D01*
G01X142530Y884270D02*
X142520D01*
G01X142600Y884260D02*
X142530Y884270D01*
G01X142860Y884260D02*
X142600D01*
G01X142880Y884270D02*
X142860Y884260D01*
G01X143000Y884170D02*
X142880Y884270D01*
G01X142510D02*
Y885040D01*
G01X142710Y885000D02*
Y884260D01*
G01X142910Y884240D02*
Y885040D01*
G01X137080Y882880D02*
X136940D01*
G01X139980Y885580D02*
X137080Y882880D01*
G01X136910Y882900D02*
Y882110D01*
G01X137070Y882120D02*
X138260Y880960D01*
G01X136930Y882120D02*
X137070D01*
G01X138120Y881110D02*
Y881750D01*
G01X137910Y881940D02*
Y881300D01*
G01X137710Y881490D02*
Y882140D01*
G01X137510Y882330D02*
Y881680D01*
G01X137410Y882570D02*
X139230Y884250D01*
G01X137410Y882420D02*
Y882570D01*
G01Y881780D02*
Y882420D01*
G01X139210Y884240D02*
Y884870D01*
G01X139010Y884680D02*
Y884050D01*
G01X138820Y883870D02*
Y884500D01*
G01X138620Y884310D02*
Y883680D01*
G01X138510Y883590D02*
Y884220D01*
G01X138410Y884120D02*
Y883490D01*
G01X138320Y883400D02*
Y884030D01*
G01X138210Y883940D02*
Y883310D01*
G01X138120Y883220D02*
Y883850D01*
G01X138010Y883750D02*
Y883120D01*
G01X137910Y883030D02*
Y883660D01*
G01X137820Y883570D02*
Y882940D01*
G01X137710Y882850D02*
Y883480D01*
G01X137620Y883380D02*
Y882750D01*
G01X137510Y882660D02*
Y883290D01*
G01X137410Y883200D02*
Y882550D01*
G01X137120Y882920D02*
Y882070D01*
G01X137010Y882120D02*
Y882880D01*
G01X136820Y883000D02*
Y882010D01*
G01X136710Y881920D02*
Y883100D01*
G01X136620Y883200D02*
Y881830D01*
G01X136510Y881740D02*
Y882360D01*
G01X136590Y882570D02*
X135120Y884000D01*
G01X136590Y882430D02*
Y882570D01*
G01X135210Y883900D02*
Y884540D01*
G01X135410Y884350D02*
Y883710D01*
G01X135510Y883620D02*
Y884250D01*
G01X135620Y884160D02*
Y883520D01*
G01X135710Y883420D02*
Y884060D01*
G01X135820Y883970D02*
Y883330D01*
G01X135910Y883230D02*
Y883870D01*
G01X136010Y883770D02*
Y883130D01*
G01X136120Y883040D02*
Y883680D01*
G01X136210Y883580D02*
Y882940D01*
G01X136320Y882850D02*
Y883480D01*
G01X136410Y883390D02*
Y882750D01*
G01X136510Y882650D02*
Y883290D01*
G01X137210Y883010D02*
Y881980D01*
G01X137320Y881880D02*
Y883100D01*
G01X136320Y882170D02*
Y881550D01*
G01X136120Y881360D02*
Y881990D01*
G01X135910Y881800D02*
Y881180D01*
G01X134580Y881790D02*
Y884280D01*
G01Y881740D02*
Y881790D01*
G01X134820Y884290D02*
Y884930D01*
G01X135010Y884740D02*
Y884100D01*
G01X134510Y885220D02*
Y881700D01*
G01X133550Y881740D02*
Y881790D01*
G01X133590Y881700D02*
X133550Y881740D01*
G01X134540Y881700D02*
X133590D01*
G01X133710D02*
Y884960D01*
G01X133910Y884990D02*
Y881700D01*
G01X134120D02*
Y885610D01*
G01X134320Y885410D02*
Y881700D01*
G01X133550Y884910D02*
Y881790D01*
G01X133620Y881700D02*
Y884960D01*
G01X133590Y884950D02*
X133550Y884910D01*
G01X133940Y885130D02*
X133740Y885330D01*
G01X133970Y885020D02*
X133940Y885130D01*
G01X133870Y884960D02*
X133970Y885020D01*
G01X133690Y884960D02*
X133870D01*
G01X133680D02*
X133690D01*
G01X133590Y884950D02*
X133680Y884960D01*
G01X133910Y885160D02*
Y885800D01*
G01X133820Y884960D02*
Y881700D01*
G01X135320Y883810D02*
Y884450D01*
G01X134640Y884370D02*
X134580Y884280D01*
G01X134750Y884350D02*
X134640Y884370D01*
G01X135120Y884000D02*
X134750Y884350D01*
G01X135120Y884640D02*
Y884000D01*
G01X134620Y884330D02*
Y885120D01*
G01X134710Y885030D02*
Y884360D01*
G01X134910Y884200D02*
Y884830D01*
G01X138710Y884400D02*
Y883770D01*
G01X138910Y883960D02*
Y884590D01*
G01X139120Y884770D02*
Y884140D01*
G01X139320Y884330D02*
Y884960D01*
G01X139410Y885050D02*
Y884420D01*
G01X139510Y884510D02*
Y885150D01*
G01X139620Y885240D02*
Y884610D01*
G01X139710Y884700D02*
Y885330D01*
G01X139910Y885520D02*
Y884890D01*
G01X140120Y885070D02*
Y886210D01*
G01X140210Y886200D02*
Y885170D01*
G01X142340Y884310D02*
X142520Y884270D01*
G01X142330Y884310D02*
X142340D01*
G01X142020Y884420D02*
X142330Y884310D01*
G01X142010Y884430D02*
X142020Y884420D01*
G01X141700Y884640D02*
X142010Y884430D01*
G01X141690Y884650D02*
X141700Y884640D01*
G01X141470Y884890D02*
X141690Y884650D01*
G01X141470Y884900D02*
Y884890D01*
G01X141390Y885020D02*
X141470Y884900D01*
G01X141380Y885030D02*
X141390Y885020D01*
G01X141350Y885090D02*
X141380Y885030D01*
G01X141280Y885250D02*
X141350Y885090D01*
G01X142620Y884260D02*
Y885020D01*
G01X143010Y885060D02*
Y879510D01*
G01X142990Y885050D02*
X143010Y885060D01*
G01X142730Y885000D02*
X142990Y885050D01*
G01X142720Y885000D02*
X142730D01*
G01X142700D02*
X142720D01*
G01X143320Y879550D02*
Y885290D01*
G01X143250Y885210D02*
X143160Y885150D01*
G01X143260Y885220D02*
X143250Y885210D01*
G01X143270Y885230D02*
X143260Y885220D01*
G01X143020Y885070D02*
X143010Y885060D01*
G01X143150Y885150D02*
X143020Y885070D01*
G01X142820Y885020D02*
Y884260D01*
G01X142410Y884290D02*
Y885060D01*
G01X142440Y885050D02*
X142700Y885000D01*
G01X142420Y885060D02*
X142440Y885050D01*
G01X142690Y885280D02*
X142670Y885290D01*
G01X142160Y885230D02*
X142000Y885450D01*
G01X142170Y885220D02*
X142160Y885230D01*
G01X142190Y885210D02*
X142170Y885220D01*
G01X142400Y885070D02*
X142190Y885210D01*
G01X142420Y885060D02*
X142400Y885070D01*
G01X142120Y885290D02*
Y884390D01*
G01X142210Y884350D02*
Y885190D01*
G01X142320Y885120D02*
Y884310D01*
G01X141910Y884490D02*
Y885750D01*
G01X141320Y885160D02*
Y886830D01*
G01X141410Y886920D02*
Y884980D01*
G01X141620Y884740D02*
Y887110D01*
G01X141820Y887290D02*
Y884570D01*
G01X143210Y885150D02*
Y885190D01*
G01X143270Y885230D02*
X143430Y885450D01*
G01X144010Y885020D02*
Y886570D01*
G01X143910Y886730D02*
Y884840D01*
G01X143480Y884400D02*
Y880800D01*
G01X143510Y884480D02*
X143480Y884400D01*
G01X143520Y884490D02*
X143510Y884480D01*
G01X143530Y884490D02*
X143520D01*
G01X143600Y884530D02*
X143530Y884490D01*
G01X143600Y884540D02*
Y884530D01*
G01X143610Y884550D02*
X143600Y884540D01*
G01X143710Y884620D02*
X143610Y884550D01*
G01X143720Y884630D02*
X143710Y884620D01*
G01X143940Y884860D02*
X143720Y884630D01*
G01X143710D02*
Y886970D01*
G01X143950Y884880D02*
X143940Y884860D01*
G01X144250Y885680D02*
X144240Y886020D01*
G01X144250Y885670D02*
Y885680D01*
G01Y885660D02*
Y885670D01*
G01X144230Y885500D02*
X144250Y885660D01*
G01X144230Y885480D02*
Y885500D01*
G01X143950Y884880D02*
X144230Y885480D01*
G01X144210Y886130D02*
Y885460D01*
G01X143440D02*
X143430Y885450D01*
G01X143440Y885480D02*
Y885460D01*
G01X143500Y885650D02*
X143440Y885480D01*
G01X143510Y885870D02*
Y885890D01*
G01Y885740D02*
Y885870D01*
G01X143500Y885670D02*
X143510Y885740D01*
G01X143500Y885650D02*
Y885670D01*
G01X142880Y885310D02*
X142690Y885280D01*
G01X142910Y885320D02*
X142880Y885310D01*
G01X143130Y885490D02*
X142910Y885320D01*
G01X143140Y885510D02*
X143130Y885490D01*
G01X143220Y885680D02*
X143140Y885510D01*
G01X143220Y885690D02*
Y885680D01*
G01X143230Y885730D02*
X143220Y885690D01*
G01X143230Y885790D02*
Y885730D01*
G01Y885810D02*
Y885790D01*
G01X142200Y885840D02*
Y885850D01*
G01Y885750D02*
Y885840D01*
G01X142210Y885730D02*
X142200Y885750D01*
G01X142370Y885420D02*
X142210Y885730D01*
G01X142390Y885400D02*
X142370Y885420D01*
G01X142670Y885290D02*
X142390Y885400D01*
G01X141990Y885460D02*
X142000Y885450D01*
G01X141990Y885480D02*
Y885460D01*
G01X141930Y885650D02*
X141990Y885480D01*
G01X141930Y885670D02*
Y885650D01*
G01X141920Y885740D02*
X141930Y885670D01*
G01X141910Y885760D02*
X141920Y885740D01*
G01X141910Y885820D02*
Y885760D01*
G01X141920Y885850D02*
X141910Y885820D01*
G01X142010Y885430D02*
Y884430D01*
G01X142530Y885340D02*
Y886280D01*
G01X142730Y886300D02*
Y885290D01*
G01X142930Y885340D02*
Y886250D01*
G01X143130Y886070D02*
Y885500D01*
G01X143230Y885810D02*
X143210Y885940D01*
G01X142340Y886140D02*
Y885490D01*
G01X141920Y885890D02*
X141970Y886090D01*
G01X141920Y885850D02*
Y885890D01*
G01X141250Y885340D02*
X141280Y885250D01*
G01X141240Y885350D02*
X141250Y885340D01*
G01X141210Y885490D02*
X141240Y885350D01*
G01X141190Y885570D02*
X141210Y885490D01*
G01X140410Y885350D02*
X139230Y884250D01*
G01X140690Y885610D02*
X140410Y885350D01*
G01X140740Y885640D02*
X140690Y885610D01*
G01X140890Y885670D02*
X140740Y885640D01*
G01X140910Y885680D02*
X140890Y885670D01*
G01X140930Y885680D02*
X140910D01*
G01X141100Y885660D02*
X140930Y885680D01*
G01X141110Y885660D02*
X141100D01*
G01X141190Y885570D02*
X141110Y885660D01*
G01X139820Y884790D02*
Y885430D01*
G01X139920Y885750D02*
X133690Y886260D01*
G01X140000Y885690D02*
X139920Y885750D01*
G01X139980Y885580D02*
X140000Y885690D01*
G01X133710Y885350D02*
X133740Y885330D01*
G01X133710Y885990D02*
Y885350D01*
G01D02*
X132870Y886160D01*
G01X133320Y885740D02*
Y888000D01*
G01X133510D02*
Y885550D01*
G01X133820Y885250D02*
Y885890D01*
G01X134010Y885700D02*
Y881700D01*
G01X134210D02*
Y885510D01*
G01X134410Y885310D02*
Y881700D01*
G01X137910Y885920D02*
Y886380D01*
G01X138120Y886370D02*
Y885900D01*
G01X138320Y885880D02*
Y886350D01*
G01X138510Y886340D02*
Y885870D01*
G01X138710Y885850D02*
Y886320D01*
G01X138910Y886310D02*
Y885840D01*
G01X139120Y885820D02*
Y886290D01*
G01X139320Y886270D02*
Y885810D01*
G01X139510Y885790D02*
Y886250D01*
G01X139710Y886240D02*
Y885770D01*
G01X139910Y885750D02*
Y886220D01*
G01X140410Y886180D02*
Y885350D01*
G01X140620Y885540D02*
Y886180D01*
G01X140820Y886360D02*
Y885660D01*
G01X141010Y885670D02*
Y886550D01*
G01X131820Y888000D02*
Y886220D01*
G01X132840Y886190D02*
X132870Y886160D01*
G01X132780Y886220D02*
X132840Y886190D01*
G01X131760Y886220D02*
X132780D01*
G01X132910Y886120D02*
Y886790D01*
G01X132710Y886960D02*
Y886220D01*
G01X132510D02*
Y887150D01*
G01X132320Y887340D02*
Y886220D01*
G01X132210D02*
Y888000D01*
G01X132010D02*
Y886220D01*
G01X131680Y886260D02*
Y886330D01*
G01X131760Y886220D02*
X131720D01*
G01X133120Y885930D02*
Y888000D01*
G01X133820Y886720D02*
Y886250D01*
G01X133610Y886090D02*
X136940Y882880D01*
G01X133590Y886200D02*
X133610Y886090D01*
G01X133690Y886260D02*
X133590Y886200D01*
G01X137120Y885980D02*
Y886450D01*
G01X137010Y886460D02*
Y885990D01*
G01X136820Y886010D02*
Y886480D01*
G01X136620Y886490D02*
Y886030D01*
G01X136410Y886040D02*
Y886510D01*
G01X136210Y886520D02*
Y886060D01*
G01X136010Y886070D02*
Y886540D01*
G01X135820Y886560D02*
Y886090D01*
G01X135620Y886110D02*
Y886570D01*
G01X135410Y886590D02*
Y886120D01*
G01X135210Y886140D02*
Y886610D01*
G01X135010Y886620D02*
Y886160D01*
G01X134820Y886170D02*
Y886640D01*
G01X134620Y886650D02*
Y886190D01*
G01X134410Y886200D02*
Y886670D01*
G01X134210Y886690D02*
Y886220D01*
G01X134010Y886240D02*
Y886700D01*
G01X133620Y886090D02*
Y885450D01*
G01X137320Y885970D02*
Y886440D01*
G01X137510Y886420D02*
Y885950D01*
G01X137710Y885940D02*
Y886400D01*
G01X137820Y886390D02*
Y885930D01*
G01X138010Y885910D02*
Y886380D01*
G01X138210Y886360D02*
Y885890D01*
G01X138410Y885880D02*
Y886350D01*
G01X138620Y886330D02*
Y885860D01*
G01X138820Y885850D02*
Y886310D01*
G01X139010Y886300D02*
Y885830D01*
G01X139210Y885810D02*
Y886280D01*
G01X139410Y886260D02*
Y885800D01*
G01X139620Y885780D02*
Y886250D01*
G01X139820Y886230D02*
Y885760D01*
G01X140010Y886220D02*
Y884980D01*
G01X140320Y885260D02*
Y886190D01*
G01X140510Y886180D02*
Y885450D01*
G01X140710Y885620D02*
Y886260D01*
G01X140650Y886200D02*
X141670Y887160D01*
G01X142010Y887480D02*
Y886150D01*
G01X141990Y886130D02*
X141970Y886090D01*
G01X141990Y886130D02*
X142250Y886440D01*
G01X142430Y886210D02*
Y885380D01*
G01X142630Y885300D02*
Y886290D01*
G01X142300Y886100D02*
X142200Y885850D01*
G01X142310Y886120D02*
X142300Y886100D01*
G01X142510Y886270D02*
X142310Y886120D01*
G01X142540Y886280D02*
X142510Y886270D01*
G01X142230Y885940D02*
Y885670D01*
G01X143210Y885960D02*
Y885940D01*
G01X143070Y886180D02*
X143210Y885960D01*
G01X143050Y886190D02*
X143070Y886180D01*
G01X142820Y886300D02*
X143050Y886190D01*
G01X142800Y886310D02*
X142820Y886300D01*
G01X142540Y886280D02*
X142800Y886310D01*
G01X143410Y886150D02*
Y887170D01*
G01X144240Y886030D02*
Y886020D01*
G01X144170Y886320D02*
X144240Y886030D01*
G01X144160Y886330D02*
X144170Y886320D01*
G01X143850Y886840D02*
X144160Y886330D01*
G01X143460Y886090D02*
X143440Y886130D01*
G01X143510Y885890D02*
X143460Y886090D01*
G01X143030Y886200D02*
Y885420D01*
G01X142840Y885300D02*
Y886300D01*
G01X140630Y886190D02*
X140560Y886170D01*
G01X140640Y886200D02*
X140630Y886190D01*
G01X140650Y886200D02*
X140640D01*
G01X133010Y886030D02*
Y886850D01*
G01X132860Y886820D02*
X132280Y887370D01*
G01X132910Y886790D02*
X132860Y886820D01*
G01X132950Y886790D02*
X132910D01*
G01X133060Y886890D02*
X132950Y886790D01*
G01X132410Y887250D02*
Y886220D01*
G01X132620D02*
Y887050D01*
G01X132820Y886860D02*
Y886200D01*
G01X133620Y886220D02*
Y886750D01*
G01X133630Y886740D02*
X140560Y886170D01*
G01X140910Y886450D02*
Y885680D01*
G01X141120Y885650D02*
Y886640D01*
G01X141210Y886730D02*
Y885460D01*
G01X141510Y884850D02*
Y887010D01*
G01X141710Y887200D02*
Y884630D01*
G01X143510Y884480D02*
Y887110D01*
G01X143760Y886930D02*
X143850Y886840D01*
G01X143690Y886990D02*
X143760Y886930D01*
G01X143500Y887120D02*
X143690Y886990D01*
G01X143820Y886880D02*
Y884730D01*
G01X143620Y884550D02*
Y887040D01*
G01X143250Y887240D02*
X143080Y887300D01*
G01X143350Y887200D02*
X143250Y887240D01*
G01X143360Y887200D02*
X143350D01*
G01X143490Y887130D02*
X143360Y887200D01*
G01X143500Y887120D02*
X143490Y887130D01*
G01X143120Y887290D02*
Y886475D01*
G01Y886480D02*
Y886540D01*
G01X143180Y886440D02*
X143440Y886130D01*
G01X143130Y886470D02*
X143180Y886440D01*
G01X143320Y886270D02*
Y887220D01*
G01X143210Y887250D02*
Y886460D01*
G01Y887220D02*
Y887250D01*
G01X142300Y886470D02*
X142250Y886440D01*
G01X142690Y886590D02*
X142300Y886470D01*
G01X142750Y886590D02*
X142690D01*
G01X143130Y886470D02*
X142750Y886590D01*
G01X142210Y886400D02*
Y887660D01*
G01X142410Y887850D02*
Y886510D01*
G01X142620Y886570D02*
Y888030D01*
G01X142820Y887330D02*
Y886570D01*
G01X143010Y886510D02*
Y887310D01*
G01X144120Y886400D02*
Y885240D01*
G01X137620Y885940D02*
Y886410D01*
G01X137410Y886430D02*
Y885960D01*
G01X137210Y885980D02*
Y886440D01*
G01X136910Y886470D02*
Y886000D01*
G01X136710Y886010D02*
Y886480D01*
G01X136510Y886500D02*
Y886030D01*
G01X136320Y886050D02*
Y886510D01*
G01X136120Y886530D02*
Y886070D01*
G01X135910Y886080D02*
Y886550D01*
G01X135710Y886570D02*
Y886100D01*
G01X135510Y886110D02*
Y886580D01*
G01X135320Y886600D02*
Y886130D01*
G01X135120Y886150D02*
Y886610D01*
G01X134910Y886630D02*
Y886160D01*
G01X134710Y886180D02*
Y886640D01*
G01X134510Y886660D02*
Y886200D01*
G01X134320Y886210D02*
Y886680D01*
G01X134120Y886700D02*
Y886230D01*
G01X133910Y886240D02*
Y886710D01*
G01X133710Y886730D02*
Y886260D01*
G01X133630Y886740D02*
X133540Y886830D01*
G01X131680Y887160D02*
Y887280D01*
G01X131670Y887000D02*
X131680Y887160D01*
G01X133540Y887960D02*
Y886830D01*
G01X133520Y888000D02*
X133540Y887960D01*
G01X133510Y888000D02*
X133520D01*
G01X131690D02*
X133510D01*
G01X131680D02*
X131690D01*
G01X132260Y887480D02*
X132280Y887370D01*
G01X132360Y887540D02*
X132260Y887480D01*
G01X132960Y887540D02*
X132360D01*
G01X133060Y887440D02*
X132960Y887540D01*
G01X133060Y886890D02*
Y887440D01*
G01X132320Y887510D02*
Y888000D01*
G01X132410D02*
Y887540D01*
G01X132510D02*
Y888000D01*
G01X132620D02*
Y887540D01*
G01X132710D02*
Y888000D01*
G01X132820D02*
Y887540D01*
G01X132910D02*
Y888000D01*
G01X133010D02*
Y887490D01*
G01X133210Y888000D02*
Y885830D01*
G01X133410Y885640D02*
Y888000D01*
G01X132120D02*
Y886220D01*
G01X131910D02*
Y888000D01*
G01X131710D02*
Y886220D01*
G01X141910Y887380D02*
Y885830D01*
G01X142120Y886270D02*
Y887570D01*
G01X142320Y887750D02*
Y886480D01*
G01X142510Y886530D02*
Y887940D01*
G01X142710Y888130D02*
Y887440D01*
G01X143060Y887300D02*
X143080D01*
G01X142790Y887340D02*
X143060Y887300D01*
G01X142710Y887400D02*
X142790Y887340D01*
G01X142910Y887320D02*
Y886540D01*
G01X142710Y887400D02*
X142730Y887510D01*
G01X142710Y886590D02*
Y887400D01*
G01X142820Y887590D02*
Y888220D01*
G01X142910Y888310D02*
Y887680D01*
G01X143010Y887770D02*
Y888410D01*
G01X143120Y888460D02*
Y888500D01*
G01Y888510D02*
Y887870D01*
G01X143210Y887960D02*
Y888595D01*
G01Y888590D02*
Y888540D01*
G01X143320Y888695D02*
Y888050D01*
G01X143410Y888140D02*
Y888780D01*
G01X143510Y888870D02*
Y888235D01*
G01X143620Y888335D02*
Y888970D01*
G01X143710Y889060D02*
Y888420D01*
G01X143820Y888525D02*
Y889150D01*
G01X143910Y889250D02*
Y888610D01*
G01X144010Y888700D02*
Y889340D01*
G01X144120Y889430D02*
Y888790D01*
G01X144210Y888880D02*
Y889530D01*
G01X144410Y889710D02*
Y889070D01*
G01X144320Y888980D02*
Y889620D01*
G01X144510Y889800D02*
Y889160D01*
G01X144620Y889260D02*
Y889900D01*
G01X144710Y889990D02*
Y889350D01*
G01X144820Y889440D02*
Y890080D01*
G01X144910Y890180D02*
Y889530D01*
G01X145010Y889630D02*
Y890270D01*
G01X145120Y890360D02*
Y889720D01*
G01X145210Y889810D02*
Y890460D01*
G01X145320Y890550D02*
Y889910D01*
G01X145410Y890000D02*
Y890640D01*
G01X145620Y890830D02*
Y890190D01*
G01X145820Y890370D02*
Y890980D01*
G01X145760Y890970D02*
X141670Y887160D01*
G01X146100Y890640D02*
X146120Y890660D01*
G01X142730Y887510D02*
X146100Y890640D01*
G01X146010Y890560D02*
Y890780D01*
G01X145780Y873700D02*
X140170Y879120D01*
G01X145810Y873670D02*
X145780Y873700D01*
G01X145830Y873680D02*
X145810Y873670D01*
G01X146100Y873990D02*
X145830Y873680D01*
G01X146110Y874020D02*
X146100Y873990D01*
G01Y874040D02*
X146110Y874020D01*
G01X140800Y879160D02*
X146100Y874040D01*
G01X146010Y874120D02*
Y873890D01*
G01X145910Y873770D02*
Y874220D01*
G01X145820Y874320D02*
Y873670D01*
G01X145710Y873760D02*
Y874420D01*
G01X145620Y874510D02*
Y873860D01*
G01X145510Y873950D02*
Y874610D01*
G01X145410Y874700D02*
Y874050D01*
G01X145320Y874140D02*
Y874800D01*
G01X145210Y874900D02*
Y874240D01*
G01X145120Y874340D02*
Y874990D01*
G01X145010Y875090D02*
Y874440D01*
G01X144910Y874530D02*
Y875190D01*
G01X144820Y875280D02*
Y874630D01*
G01X144710Y874730D02*
Y875380D01*
G01X144620Y875480D02*
Y874820D01*
G01X144510Y874920D02*
Y875570D01*
G01X145510Y890740D02*
Y890090D01*
G01X145710Y890280D02*
Y890920D01*
G01X146100Y890690D02*
X146120Y890660D01*
G01X145810Y890980D02*
X146100Y890690D01*
G01X145790Y890990D02*
X145810Y890980D01*
G01X145780D02*
X145790Y890990D01*
G01X145760Y890970D02*
X145780Y890980D01*
G01X145910Y890460D02*
Y890880D01*
G54D18*
G01X27500Y65233D02*
X23500D01*
Y67767D01*
G01X25433Y66833D02*
Y65233D01*
G01X27500Y69333D02*
X23500Y71000D01*
X27500Y72667D01*
G01X26100Y72067D02*
Y69933D01*
G01X27500Y73967D02*
X23500D01*
X27500Y77033D01*
X23500D01*
G01X25833Y78733D02*
X25367Y79200D01*
X25100Y79600D01*
X24967Y80133D01*
X25100Y80600D01*
X25367Y80933D01*
X25767Y81200D01*
X26233Y81267D01*
X26633Y81200D01*
X27033Y80933D01*
X27367Y80533D01*
X27500Y80067D01*
X27367Y79533D01*
X26967Y79067D01*
X26367Y78800D01*
X25700Y78733D01*
X24833Y78867D01*
X24367Y79067D01*
X23900Y79400D01*
X23567Y79867D01*
X23500Y80333D01*
X23633Y80800D01*
X23967Y81133D01*
G01X27500Y500733D02*
X23500D01*
Y503267D01*
G01X25433Y502333D02*
Y500733D01*
G01X27500Y504833D02*
X23500Y506500D01*
X27500Y508167D01*
G01X26100Y507567D02*
Y505433D01*
G01X27500Y509467D02*
X23500D01*
X27500Y512533D01*
X23500D01*
G01X26900Y514033D02*
X27233Y514433D01*
X27433Y514900D01*
X27500Y515500D01*
X27367Y516100D01*
X27100Y516567D01*
X26633Y516900D01*
X26100Y516967D01*
X25567Y516833D01*
X25233Y516500D01*
X24967Y516033D01*
X24900Y515567D01*
X24967Y515100D01*
X25233Y514500D01*
X23500Y514700D01*
Y516500D01*
G01X27000Y761733D02*
X23000D01*
Y764267D01*
G01X24933Y763333D02*
Y761733D01*
G01X27000Y765833D02*
X23000Y767500D01*
X27000Y769167D01*
G01X25600Y768567D02*
Y766433D01*
G01X27000Y770467D02*
X23000D01*
X27000Y773533D01*
X23000D01*
G01X27000Y777300D02*
X23000D01*
X25867Y774833D01*
Y778167D01*
G01X29000Y1198733D02*
X25000D01*
Y1201267D01*
G01X26933Y1200333D02*
Y1198733D01*
G01X29000Y1202833D02*
X25000Y1204500D01*
X29000Y1206167D01*
G01X27600Y1205567D02*
Y1203433D01*
G01X29000Y1207467D02*
X25000D01*
X29000Y1210533D01*
X25000D01*
G01X28200Y1212033D02*
X28667Y1212433D01*
X28933Y1212967D01*
X29000Y1213567D01*
X28933Y1214100D01*
X28600Y1214633D01*
X28200Y1214967D01*
X27800Y1215033D01*
X27333Y1214900D01*
X27000Y1214433D01*
X26867Y1213967D01*
Y1213367D01*
G01Y1213967D02*
X26667Y1214367D01*
X26333Y1214700D01*
X25933Y1214833D01*
X25533Y1214700D01*
X25200Y1214367D01*
X25000Y1213767D01*
X25067Y1213167D01*
X25333Y1212567D01*
G01X28000Y1456733D02*
X24000D01*
Y1459267D01*
G01X25933Y1458333D02*
Y1456733D01*
G01X28000Y1460833D02*
X24000Y1462500D01*
X28000Y1464167D01*
G01X26600Y1463567D02*
Y1461433D01*
G01X28000Y1465467D02*
X24000D01*
X28000Y1468533D01*
X24000D01*
G01X24667Y1470233D02*
X24267Y1470633D01*
X24067Y1471100D01*
X24000Y1471633D01*
X24133Y1472300D01*
X24467Y1472767D01*
X24867Y1472900D01*
X25267Y1472833D01*
X25600Y1472567D01*
X26267Y1471233D01*
X26733Y1470633D01*
X27400Y1470233D01*
X28000Y1470100D01*
Y1472900D01*
G01X29000Y1905233D02*
X25000D01*
Y1907767D01*
G01X26933Y1906833D02*
Y1905233D01*
G01X29000Y1909333D02*
X25000Y1911000D01*
X29000Y1912667D01*
G01X27600Y1912067D02*
Y1909933D01*
G01X29000Y1913967D02*
X25000D01*
X29000Y1917033D01*
X25000D01*
G01X29000Y1920000D02*
X25000D01*
X25800Y1919200D01*
G01X29000D02*
Y1920800D01*
G01X41000Y196733D02*
X37000D01*
Y199267D01*
G01X38933Y198333D02*
Y196733D01*
G01X41000Y200833D02*
X37000Y202500D01*
X41000Y204167D01*
G01X39600Y203567D02*
Y201433D01*
G01X41000Y205467D02*
X37000D01*
X41000Y208533D01*
X37000D01*
G01X39333Y210233D02*
X38867Y210700D01*
X38600Y211100D01*
X38467Y211633D01*
X38600Y212100D01*
X38867Y212433D01*
X39267Y212700D01*
X39733Y212767D01*
X40133Y212700D01*
X40533Y212433D01*
X40867Y212033D01*
X41000Y211567D01*
X40867Y211033D01*
X40467Y210567D01*
X39867Y210300D01*
X39200Y210233D01*
X38333Y210367D01*
X37867Y210567D01*
X37400Y210900D01*
X37067Y211367D01*
X37000Y211833D01*
X37133Y212300D01*
X37467Y212633D01*
G01X42333Y214000D02*
Y218000D01*
G01X37000Y219167D02*
X41000D01*
Y221833D01*
G01Y226333D02*
Y223667D01*
X37000D01*
Y226333D01*
G01X38933Y225267D02*
Y223667D01*
G01X41000Y228033D02*
X37000D01*
Y229367D01*
X37200Y229900D01*
X37467Y230300D01*
X37867Y230633D01*
X38333Y230900D01*
X39000Y230967D01*
X39667Y230900D01*
X40133Y230633D01*
X40533Y230300D01*
X40800Y229900D01*
X41000Y229367D01*
Y228033D01*
G01X46500Y342233D02*
X42500D01*
Y344767D01*
G01X44433Y343833D02*
Y342233D01*
G01X46500Y346333D02*
X42500Y348000D01*
X46500Y349667D01*
G01X45100Y349067D02*
Y346933D01*
G01X46500Y350967D02*
X42500D01*
X46500Y354033D01*
X42500D01*
G01X45900Y355533D02*
X46233Y355933D01*
X46433Y356400D01*
X46500Y357000D01*
X46367Y357600D01*
X46100Y358067D01*
X45633Y358400D01*
X45100Y358467D01*
X44567Y358333D01*
X44233Y358000D01*
X43967Y357533D01*
X43900Y357067D01*
X43967Y356600D01*
X44233Y356000D01*
X42500Y356200D01*
Y358000D01*
G01X47833Y359500D02*
Y363500D01*
G01X42500Y364667D02*
X46500D01*
Y367333D01*
G01Y371833D02*
Y369167D01*
X42500D01*
Y371833D01*
G01X44433Y370767D02*
Y369167D01*
G01X46500Y373533D02*
X42500D01*
Y374867D01*
X42700Y375400D01*
X42967Y375800D01*
X43367Y376133D01*
X43833Y376400D01*
X44500Y376467D01*
X45167Y376400D01*
X45633Y376133D01*
X46033Y375800D01*
X46300Y375400D01*
X46500Y374867D01*
Y373533D01*
G01X41000Y899733D02*
X37000D01*
Y902267D01*
G01X38933Y901333D02*
Y899733D01*
G01X41000Y903833D02*
X37000Y905500D01*
X41000Y907167D01*
G01X39600Y906567D02*
Y904433D01*
G01X41000Y908467D02*
X37000D01*
X41000Y911533D01*
X37000D01*
G01X41000Y915300D02*
X37000D01*
X39867Y912833D01*
Y916167D01*
G01X42333Y917000D02*
Y921000D01*
G01X37000Y922167D02*
X41000D01*
Y924833D01*
G01Y929333D02*
Y926667D01*
X37000D01*
Y929333D01*
G01X38933Y928267D02*
Y926667D01*
G01X41000Y931033D02*
X37000D01*
Y932367D01*
X37200Y932900D01*
X37467Y933300D01*
X37867Y933633D01*
X38333Y933900D01*
X39000Y933967D01*
X39667Y933900D01*
X40133Y933633D01*
X40533Y933300D01*
X40800Y932900D01*
X41000Y932367D01*
Y931033D01*
G01X43000Y1039733D02*
X39000D01*
Y1042267D01*
G01X40933Y1041333D02*
Y1039733D01*
G01X43000Y1043833D02*
X39000Y1045500D01*
X43000Y1047167D01*
G01X41600Y1046567D02*
Y1044433D01*
G01X43000Y1048467D02*
X39000D01*
X43000Y1051533D01*
X39000D01*
G01X42200Y1053033D02*
X42667Y1053433D01*
X42933Y1053967D01*
X43000Y1054567D01*
X42933Y1055100D01*
X42600Y1055633D01*
X42200Y1055967D01*
X41800Y1056033D01*
X41333Y1055900D01*
X41000Y1055433D01*
X40867Y1054967D01*
Y1054367D01*
G01Y1054967D02*
X40667Y1055367D01*
X40333Y1055700D01*
X39933Y1055833D01*
X39533Y1055700D01*
X39200Y1055367D01*
X39000Y1054767D01*
X39067Y1054167D01*
X39333Y1053567D01*
G01X44333Y1057000D02*
Y1061000D01*
G01X39000Y1062167D02*
X43000D01*
Y1064833D01*
G01Y1069333D02*
Y1066667D01*
X39000D01*
Y1069333D01*
G01X40933Y1068267D02*
Y1066667D01*
G01X43000Y1071033D02*
X39000D01*
Y1072367D01*
X39200Y1072900D01*
X39467Y1073300D01*
X39867Y1073633D01*
X40333Y1073900D01*
X41000Y1073967D01*
X41667Y1073900D01*
X42133Y1073633D01*
X42533Y1073300D01*
X42800Y1072900D01*
X43000Y1072367D01*
Y1071033D01*
G01X44000Y1601233D02*
X40000D01*
Y1603767D01*
G01X41933Y1602833D02*
Y1601233D01*
G01X44000Y1605333D02*
X40000Y1607000D01*
X44000Y1608667D01*
G01X42600Y1608067D02*
Y1605933D01*
G01X44000Y1609967D02*
X40000D01*
X44000Y1613033D01*
X40000D01*
G01X40667Y1614733D02*
X40267Y1615133D01*
X40067Y1615600D01*
X40000Y1616133D01*
X40133Y1616800D01*
X40467Y1617267D01*
X40867Y1617400D01*
X41267Y1617333D01*
X41600Y1617067D01*
X42267Y1615733D01*
X42733Y1615133D01*
X43400Y1614733D01*
X44000Y1614600D01*
Y1617400D01*
G01X45333Y1618500D02*
Y1622500D01*
G01X40000Y1623667D02*
X44000D01*
Y1626333D01*
G01Y1630833D02*
Y1628167D01*
X40000D01*
Y1630833D01*
G01X41933Y1629767D02*
Y1628167D01*
G01X44000Y1632533D02*
X40000D01*
Y1633867D01*
X40200Y1634400D01*
X40467Y1634800D01*
X40867Y1635133D01*
X41333Y1635400D01*
X42000Y1635467D01*
X42667Y1635400D01*
X43133Y1635133D01*
X43533Y1634800D01*
X43800Y1634400D01*
X44000Y1633867D01*
Y1632533D01*
G01X50000Y1710233D02*
X46000D01*
Y1712767D01*
G01X47933Y1711833D02*
Y1710233D01*
G01X50000Y1714333D02*
X46000Y1716000D01*
X50000Y1717667D01*
G01X48600Y1717067D02*
Y1714933D01*
G01X50000Y1718967D02*
X46000D01*
X50000Y1722033D01*
X46000D01*
G01X50000Y1725000D02*
X46000D01*
X46800Y1724200D01*
G01X50000D02*
Y1725800D01*
G01X51333Y1727500D02*
Y1731500D01*
G01X46000Y1732667D02*
X50000D01*
Y1735333D01*
G01Y1739833D02*
Y1737167D01*
X46000D01*
Y1739833D01*
G01X47933Y1738767D02*
Y1737167D01*
G01X50000Y1741533D02*
X46000D01*
Y1742867D01*
X46200Y1743400D01*
X46467Y1743800D01*
X46867Y1744133D01*
X47333Y1744400D01*
X48000Y1744467D01*
X48667Y1744400D01*
X49133Y1744133D01*
X49533Y1743800D01*
X49800Y1743400D01*
X50000Y1742867D01*
Y1741533D01*
G01X65500Y1788333D02*
X61500D01*
Y1789667D01*
X61700Y1790200D01*
X61967Y1790600D01*
X62367Y1790933D01*
X62833Y1791200D01*
X63500Y1791267D01*
X64167Y1791200D01*
X64633Y1790933D01*
X65033Y1790600D01*
X65300Y1790200D01*
X65500Y1789667D01*
Y1788333D01*
G01X61833Y1795767D02*
X61633Y1795367D01*
X61500Y1794900D01*
Y1794367D01*
X61700Y1793767D01*
X62033Y1793300D01*
X62433Y1792967D01*
X63100Y1792700D01*
X63700Y1792633D01*
X64300Y1792767D01*
X64700Y1792967D01*
X65100Y1793367D01*
X65367Y1793833D01*
X65500Y1794300D01*
Y1794767D01*
X65367Y1795233D01*
X65167Y1795633D01*
X64900Y1795967D01*
G01X61500Y1802500D02*
Y1804100D01*
G01Y1803300D02*
X65500D01*
G01Y1802500D02*
Y1804100D01*
G01Y1806267D02*
X61500D01*
X65500Y1809333D01*
X61500D01*
G01X65500Y1810967D02*
X61500D01*
Y1812567D01*
X61700Y1813100D01*
X62167Y1813500D01*
X62700Y1813633D01*
X63233Y1813500D01*
X63633Y1813167D01*
X63833Y1812567D01*
Y1810967D01*
G01X61500Y1815333D02*
X64367D01*
X64967Y1815600D01*
X65367Y1816133D01*
X65500Y1816800D01*
X65367Y1817467D01*
X64967Y1818000D01*
X64367Y1818267D01*
X61500D01*
G01Y1821300D02*
X65500D01*
G01X61500Y1819767D02*
Y1822833D01*
G01X65500Y1828967D02*
X61500D01*
Y1830633D01*
X61700Y1831167D01*
X61967Y1831500D01*
X62500Y1831633D01*
X63033Y1831500D01*
X63367Y1831100D01*
X63567Y1830633D01*
Y1828967D01*
G01Y1830633D02*
X65500Y1831633D01*
G01Y1833133D02*
X61500Y1834800D01*
X65500Y1836467D01*
G01X64100Y1835867D02*
Y1833733D01*
G01X61500Y1839300D02*
X65500D01*
G01X61500Y1837767D02*
Y1840833D01*
G01Y1843000D02*
Y1844600D01*
G01Y1843800D02*
X65500D01*
G01Y1843000D02*
Y1844600D01*
G01Y1846767D02*
X61500D01*
X65500Y1849833D01*
X61500D01*
G01X63500Y1853200D02*
Y1854533D01*
X64700D01*
X65100Y1854133D01*
X65367Y1853667D01*
X65500Y1853000D01*
X65367Y1852333D01*
X65100Y1851867D01*
X64700Y1851467D01*
X64233Y1851200D01*
X63700Y1851067D01*
X63233D01*
X62833Y1851200D01*
X62367Y1851467D01*
X61967Y1851867D01*
X61700Y1852267D01*
X61500Y1852800D01*
Y1853267D01*
X61633Y1853800D01*
X61900Y1854200D01*
G01X63833Y1860533D02*
X63367Y1861000D01*
X63100Y1861400D01*
X62967Y1861933D01*
X63100Y1862400D01*
X63367Y1862733D01*
X63767Y1863000D01*
X64233Y1863067D01*
X64633Y1863000D01*
X65033Y1862733D01*
X65367Y1862333D01*
X65500Y1861867D01*
X65367Y1861333D01*
X64967Y1860867D01*
X64367Y1860600D01*
X63700Y1860533D01*
X62833Y1860667D01*
X62367Y1860867D01*
X61900Y1861200D01*
X61567Y1861667D01*
X61500Y1862133D01*
X61633Y1862600D01*
X61967Y1862933D01*
G01X61500Y1866300D02*
X61633Y1865767D01*
X61967Y1865367D01*
X62367Y1865100D01*
X62900Y1864900D01*
X63500Y1864833D01*
X64100Y1864900D01*
X64633Y1865100D01*
X65033Y1865367D01*
X65367Y1865767D01*
X65500Y1866300D01*
X65367Y1866833D01*
X65033Y1867233D01*
X64633Y1867500D01*
X64100Y1867700D01*
X63500Y1867767D01*
X62900Y1867700D01*
X62367Y1867500D01*
X61967Y1867233D01*
X61633Y1866833D01*
X61500Y1866300D01*
G01X65500Y1869133D02*
X61500Y1870800D01*
X65500Y1872467D01*
G01X64100Y1871867D02*
Y1869733D01*
G01X126467Y534600D02*
X126800Y535133D01*
X127000Y535733D01*
Y536267D01*
X126800Y536800D01*
X126467Y537200D01*
X126000Y537400D01*
X125533Y537267D01*
X125133Y536933D01*
X124867Y536333D01*
X124733Y535533D01*
X124467Y535067D01*
X124000Y534867D01*
X123533Y535000D01*
X123200Y535333D01*
X123000Y535800D01*
Y536267D01*
X123133Y536733D01*
X123467Y537133D01*
G01X127000Y541833D02*
Y539167D01*
X123000D01*
Y541833D01*
G01X124933Y540767D02*
Y539167D01*
G01X127000Y543467D02*
X123000D01*
X127000Y546533D01*
X123000D01*
G01X126467Y548100D02*
X126800Y548633D01*
X127000Y549233D01*
Y549767D01*
X126800Y550300D01*
X126467Y550700D01*
X126000Y550900D01*
X125533Y550767D01*
X125133Y550433D01*
X124867Y549833D01*
X124733Y549033D01*
X124467Y548567D01*
X124000Y548367D01*
X123533Y548500D01*
X123200Y548833D01*
X123000Y549300D01*
Y549767D01*
X123133Y550233D01*
X123467Y550633D01*
G01X127000Y554000D02*
X126933Y553467D01*
X126667Y553000D01*
X126267Y552600D01*
X125800Y552333D01*
X125267Y552200D01*
X124733D01*
X124200Y552333D01*
X123733Y552600D01*
X123333Y553000D01*
X123067Y553467D01*
X123000Y554000D01*
X123067Y554533D01*
X123333Y555000D01*
X123733Y555400D01*
X124200Y555667D01*
X124733Y555800D01*
X125267D01*
X125800Y555667D01*
X126267Y555400D01*
X126667Y555000D01*
X126933Y554533D01*
X127000Y554000D01*
G01Y557167D02*
X123000D01*
Y558833D01*
X123200Y559367D01*
X123467Y559700D01*
X124000Y559833D01*
X124533Y559700D01*
X124867Y559300D01*
X125067Y558833D01*
Y557167D01*
G01Y558833D02*
X127000Y559833D01*
G01X123500Y519500D02*
X127500D01*
G01X123500Y517967D02*
Y521033D01*
G01X127500Y522267D02*
X123500D01*
X126833Y524000D01*
X123500Y525733D01*
X127500D01*
G01Y527167D02*
X123500D01*
Y528767D01*
X123700Y529300D01*
X124167Y529700D01*
X124700Y529833D01*
X125233Y529700D01*
X125633Y529367D01*
X125833Y528767D01*
Y527167D01*
G01X127000Y564000D02*
X123000D01*
X123800Y563200D01*
G01X127000D02*
Y564800D01*
G01X121000Y1232500D02*
X125000D01*
G01X121000Y1230967D02*
Y1234033D01*
G01X125000Y1235267D02*
X121000D01*
X124333Y1237000D01*
X121000Y1238733D01*
X125000D01*
G01Y1240167D02*
X121000D01*
Y1241767D01*
X121200Y1242300D01*
X121667Y1242700D01*
X122200Y1242833D01*
X122733Y1242700D01*
X123133Y1242367D01*
X123333Y1241767D01*
Y1240167D01*
G01X124467Y1249100D02*
X124800Y1249633D01*
X125000Y1250233D01*
Y1250767D01*
X124800Y1251300D01*
X124467Y1251700D01*
X124000Y1251900D01*
X123533Y1251767D01*
X123133Y1251433D01*
X122867Y1250833D01*
X122733Y1250033D01*
X122467Y1249567D01*
X122000Y1249367D01*
X121533Y1249500D01*
X121200Y1249833D01*
X121000Y1250300D01*
Y1250767D01*
X121133Y1251233D01*
X121467Y1251633D01*
G01X125000Y1256333D02*
Y1253667D01*
X121000D01*
Y1256333D01*
G01X122933Y1255267D02*
Y1253667D01*
G01X125000Y1257967D02*
X121000D01*
X125000Y1261033D01*
X121000D01*
G01X124467Y1262600D02*
X124800Y1263133D01*
X125000Y1263733D01*
Y1264267D01*
X124800Y1264800D01*
X124467Y1265200D01*
X124000Y1265400D01*
X123533Y1265267D01*
X123133Y1264933D01*
X122867Y1264333D01*
X122733Y1263533D01*
X122467Y1263067D01*
X122000Y1262867D01*
X121533Y1263000D01*
X121200Y1263333D01*
X121000Y1263800D01*
Y1264267D01*
X121133Y1264733D01*
X121467Y1265133D01*
G01X125000Y1268500D02*
X124933Y1267967D01*
X124667Y1267500D01*
X124267Y1267100D01*
X123800Y1266833D01*
X123267Y1266700D01*
X122733D01*
X122200Y1266833D01*
X121733Y1267100D01*
X121333Y1267500D01*
X121067Y1267967D01*
X121000Y1268500D01*
X121067Y1269033D01*
X121333Y1269500D01*
X121733Y1269900D01*
X122200Y1270167D01*
X122733Y1270300D01*
X123267D01*
X123800Y1270167D01*
X124267Y1269900D01*
X124667Y1269500D01*
X124933Y1269033D01*
X125000Y1268500D01*
G01Y1271667D02*
X121000D01*
Y1273333D01*
X121200Y1273867D01*
X121467Y1274200D01*
X122000Y1274333D01*
X122533Y1274200D01*
X122867Y1273800D01*
X123067Y1273333D01*
Y1271667D01*
G01Y1273333D02*
X125000Y1274333D01*
G01X121667Y1280733D02*
X121267Y1281133D01*
X121067Y1281600D01*
X121000Y1282133D01*
X121133Y1282800D01*
X121467Y1283267D01*
X121867Y1283400D01*
X122267Y1283333D01*
X122600Y1283067D01*
X123267Y1281733D01*
X123733Y1281133D01*
X124400Y1280733D01*
X125000Y1280600D01*
Y1283400D01*
G54D19*
G01X-430254Y-152763D02*
Y-135263D01*
G01X-421958D02*
X-430254Y-146055D01*
G01X-420648Y-152763D02*
X-426543Y-141097D01*
G01X-412973Y-152763D02*
Y-135263D01*
X-402929Y-152763D01*
Y-135263D01*
G01X-390451Y-152763D02*
X-392198Y-152471D01*
X-393726Y-151305D01*
X-395036Y-149555D01*
X-395910Y-147513D01*
X-396346Y-145180D01*
Y-142846D01*
X-395910Y-140513D01*
X-395036Y-138471D01*
X-393726Y-136722D01*
X-392198Y-135555D01*
X-390451Y-135263D01*
X-388705Y-135555D01*
X-387176Y-136722D01*
X-385866Y-138471D01*
X-384992Y-140513D01*
X-384556Y-142846D01*
Y-145180D01*
X-384992Y-147513D01*
X-385866Y-149555D01*
X-387176Y-151305D01*
X-388705Y-152471D01*
X-390451Y-152763D01*
G01X-377536D02*
X-368366Y-135263D01*
G01X-377536D02*
X-368366Y-152763D01*
G01X-362001Y-158596D02*
X-348901D01*
G01X-342099Y-152763D02*
Y-135263D01*
X-333803D01*
G01X-336859Y-143721D02*
X-342099D01*
G01X-325910Y-152763D02*
X-320451Y-135263D01*
X-314992Y-152763D01*
G01X-316958Y-146638D02*
X-323945D01*
G01X-307973Y-152763D02*
Y-135263D01*
X-297929Y-152763D01*
Y-135263D01*
G01X-263148Y-136722D02*
X-264458Y-135846D01*
X-265986Y-135263D01*
X-267733D01*
X-269698Y-136138D01*
X-271226Y-137596D01*
X-272318Y-139347D01*
X-273191Y-142263D01*
X-273410Y-144888D01*
X-272973Y-147513D01*
X-272318Y-149263D01*
X-271008Y-151013D01*
X-269479Y-152180D01*
X-267951Y-152763D01*
X-266423D01*
X-264894Y-152180D01*
X-263584Y-151305D01*
X-262492Y-150139D01*
G01X-250451Y-152763D02*
X-252198Y-152471D01*
X-253726Y-151305D01*
X-255036Y-149555D01*
X-255910Y-147513D01*
X-256346Y-145180D01*
Y-142846D01*
X-255910Y-140513D01*
X-255036Y-138471D01*
X-253726Y-136722D01*
X-252198Y-135555D01*
X-250451Y-135263D01*
X-248705Y-135555D01*
X-247176Y-136722D01*
X-245866Y-138471D01*
X-244992Y-140513D01*
X-244556Y-142846D01*
Y-145180D01*
X-244992Y-147513D01*
X-245866Y-149555D01*
X-247176Y-151305D01*
X-248705Y-152471D01*
X-250451Y-152763D01*
G01X-237973D02*
Y-135263D01*
X-227929Y-152763D01*
Y-135263D01*
G01X-215451D02*
Y-152763D01*
G01X-220473Y-135263D02*
X-210429D01*
G01X-202318Y-152763D02*
Y-135263D01*
X-196859D01*
X-195113Y-136138D01*
X-194021Y-137305D01*
X-193584Y-139638D01*
X-194021Y-141972D01*
X-195331Y-143430D01*
X-196859Y-144305D01*
X-202318D01*
G01X-196859D02*
X-193584Y-152763D01*
G01X-180451D02*
X-182198Y-152471D01*
X-183726Y-151305D01*
X-185036Y-149555D01*
X-185910Y-147513D01*
X-186346Y-145180D01*
Y-142846D01*
X-185910Y-140513D01*
X-185036Y-138471D01*
X-183726Y-136722D01*
X-182198Y-135555D01*
X-180451Y-135263D01*
X-178705Y-135555D01*
X-177176Y-136722D01*
X-175866Y-138471D01*
X-174992Y-140513D01*
X-174556Y-142846D01*
Y-145180D01*
X-174992Y-147513D01*
X-175866Y-149555D01*
X-177176Y-151305D01*
X-178705Y-152471D01*
X-180451Y-152763D01*
G01X-167318Y-135263D02*
Y-152763D01*
X-158584D01*
G01X-126205Y-143430D02*
X-125331Y-142555D01*
X-124676Y-141097D01*
X-124239Y-139054D01*
X-124676Y-137305D01*
X-125549Y-136138D01*
X-127078Y-135263D01*
X-132973D01*
Y-152763D01*
X-125768D01*
X-124239Y-151597D01*
X-123366Y-149846D01*
X-122929Y-147805D01*
X-123366Y-145763D01*
X-124676Y-144013D01*
X-126205Y-143430D01*
X-132973D01*
G01X-110451Y-152763D02*
X-112198Y-152471D01*
X-113726Y-151305D01*
X-115036Y-149555D01*
X-115910Y-147513D01*
X-116346Y-145180D01*
Y-142846D01*
X-115910Y-140513D01*
X-115036Y-138471D01*
X-113726Y-136722D01*
X-112198Y-135555D01*
X-110451Y-135263D01*
X-108705Y-135555D01*
X-107176Y-136722D01*
X-105866Y-138471D01*
X-104992Y-140513D01*
X-104556Y-142846D01*
Y-145180D01*
X-104992Y-147513D01*
X-105866Y-149555D01*
X-107176Y-151305D01*
X-108705Y-152471D01*
X-110451Y-152763D01*
G01X-98410D02*
X-92951Y-135263D01*
X-87492Y-152763D01*
G01X-89458Y-146638D02*
X-96445D01*
G01X-79818Y-152763D02*
Y-135263D01*
X-74359D01*
X-72613Y-136138D01*
X-71521Y-137305D01*
X-71084Y-139638D01*
X-71521Y-141972D01*
X-72831Y-143430D01*
X-74359Y-144305D01*
X-79818D01*
G01X-74359D02*
X-71084Y-152763D01*
G01X-62754D02*
Y-135263D01*
X-58388D01*
X-56641Y-136138D01*
X-55331Y-137305D01*
X-54239Y-139054D01*
X-53366Y-141097D01*
X-53148Y-144013D01*
X-53366Y-146930D01*
X-54239Y-148972D01*
X-55331Y-150722D01*
X-56641Y-151888D01*
X-58388Y-152763D01*
X-62754D01*
G01X-282378Y-107763D02*
Y-90263D01*
X-276701Y-104846D01*
X-271024Y-90263D01*
Y-107763D01*
G01X-259201D02*
X-260511Y-107471D01*
X-261821Y-106305D01*
X-262695Y-104263D01*
X-263131Y-101930D01*
X-262695Y-99596D01*
X-261821Y-97555D01*
X-260511Y-96388D01*
X-259201Y-96097D01*
X-257891Y-96388D01*
X-256581Y-97555D01*
X-255708Y-99596D01*
X-255489Y-101930D01*
X-255708Y-104263D01*
X-256581Y-106305D01*
X-257891Y-107471D01*
X-259201Y-107763D01*
G01X-237771Y-90263D02*
Y-107763D01*
G01Y-105139D02*
X-238644Y-106597D01*
X-239955Y-107471D01*
X-241483Y-107763D01*
X-243229Y-107180D01*
X-244539Y-105722D01*
X-245413Y-103972D01*
X-245631Y-101930D01*
X-245413Y-99888D01*
X-244539Y-98138D01*
X-243229Y-96680D01*
X-241483Y-96097D01*
X-239955Y-96388D01*
X-238863Y-96972D01*
X-237771Y-98138D01*
G01X-227476Y-99888D02*
X-220489D01*
X-221144Y-97846D01*
X-222236Y-96680D01*
X-223764Y-96097D01*
X-225293Y-96388D01*
X-226603Y-97263D01*
X-227476Y-99305D01*
X-227913Y-101055D01*
Y-102805D01*
X-227476Y-104555D01*
X-226384Y-106305D01*
X-225074Y-107471D01*
X-223546Y-107763D01*
X-222018Y-107180D01*
X-220489Y-105430D01*
G01X-206701Y-107763D02*
Y-90263D01*
G01X-901Y-152763D02*
Y-135263D01*
X-3521Y-138763D01*
G01Y-152763D02*
X1719D01*
G01X12451Y-138180D02*
X13761Y-136430D01*
X15289Y-135555D01*
X17036Y-135263D01*
X19219Y-135846D01*
X20747Y-137305D01*
X21184Y-139054D01*
X20966Y-140805D01*
X20092Y-142263D01*
X15726Y-145180D01*
X13761Y-147221D01*
X12451Y-150139D01*
X12014Y-152763D01*
X21184D01*
G01X36719D02*
Y-135263D01*
X28640Y-147805D01*
X39558D01*
G01X46796Y-149263D02*
X48105Y-151305D01*
X49852Y-152471D01*
X51817Y-152763D01*
X53564Y-152471D01*
X55311Y-151013D01*
X56402Y-149263D01*
X56621Y-147513D01*
X56184Y-145472D01*
X54656Y-144013D01*
X53127Y-143430D01*
X51162D01*
G01X53127D02*
X54437Y-142555D01*
X55529Y-141097D01*
X55966Y-139347D01*
X55529Y-137596D01*
X54437Y-136138D01*
X52472Y-135263D01*
X50507Y-135555D01*
X48542Y-136722D01*
G01X64296Y-149263D02*
X65605Y-151305D01*
X67352Y-152471D01*
X69317Y-152763D01*
X71064Y-152471D01*
X72811Y-151013D01*
X73902Y-149263D01*
X74121Y-147513D01*
X73684Y-145472D01*
X72156Y-144013D01*
X70627Y-143430D01*
X68662D01*
G01X70627D02*
X71937Y-142555D01*
X73029Y-141097D01*
X73466Y-139347D01*
X73029Y-137596D01*
X71937Y-136138D01*
X69972Y-135263D01*
X68007Y-135555D01*
X66042Y-136722D01*
G01X-14018Y-107763D02*
Y-90263D01*
X-8778D01*
X-7031Y-91138D01*
X-5721Y-93180D01*
X-5284Y-95513D01*
X-5721Y-97846D01*
X-6813Y-99596D01*
X-8778Y-100472D01*
X-14018D01*
G01X12652Y-91722D02*
X11342Y-90846D01*
X9814Y-90263D01*
X8067D01*
X6102Y-91138D01*
X4574Y-92596D01*
X3482Y-94347D01*
X2609Y-97263D01*
X2390Y-99888D01*
X2827Y-102513D01*
X3482Y-104263D01*
X4792Y-106013D01*
X6321Y-107180D01*
X7849Y-107763D01*
X9377D01*
X10906Y-107180D01*
X12216Y-106305D01*
X13308Y-105139D01*
G01X27095Y-98430D02*
X27969Y-97555D01*
X28624Y-96097D01*
X29061Y-94054D01*
X28624Y-92305D01*
X27751Y-91138D01*
X26222Y-90263D01*
X20327D01*
Y-107763D01*
X27532D01*
X29061Y-106597D01*
X29934Y-104846D01*
X30371Y-102805D01*
X29934Y-100763D01*
X28624Y-99013D01*
X27095Y-98430D01*
X20327D01*
G01X36299Y-113596D02*
X49399D01*
G01X55327Y-107763D02*
Y-90263D01*
X65371Y-107763D01*
Y-90263D01*
G01X77849Y-107763D02*
X76102Y-107471D01*
X74574Y-106305D01*
X73264Y-104555D01*
X72390Y-102513D01*
X71954Y-100180D01*
Y-97846D01*
X72390Y-95513D01*
X73264Y-93471D01*
X74574Y-91722D01*
X76102Y-90555D01*
X77849Y-90263D01*
X79595Y-90555D01*
X81124Y-91722D01*
X82434Y-93471D01*
X83308Y-95513D01*
X83744Y-97846D01*
Y-100180D01*
X83308Y-102513D01*
X82434Y-104555D01*
X81124Y-106305D01*
X79595Y-107471D01*
X77849Y-107763D01*
G01X128690Y-90263D02*
X134149Y-107763D01*
X139608Y-90263D01*
G01X156016Y-107763D02*
X147282D01*
Y-90263D01*
X156016D01*
G01X152522Y-98721D02*
X147282D01*
G01X164782Y-107763D02*
Y-90263D01*
X170241D01*
X171987Y-91138D01*
X173079Y-92305D01*
X173516Y-94638D01*
X173079Y-96972D01*
X171769Y-98430D01*
X170241Y-99305D01*
X164782D01*
G01X170241D02*
X173516Y-107763D01*
G01X186649Y-108346D02*
X186212Y-108055D01*
Y-107471D01*
X186649Y-107180D01*
X187086Y-107471D01*
Y-108055D01*
X186649Y-108346D01*
G01X97835Y617329D02*
X107535Y607629D01*
X97835D01*
Y617329D01*
G01X151649Y-152763D02*
Y-135263D01*
X149029Y-138763D01*
G01Y-152763D02*
X154269D01*
G01X163472D02*
Y-135263D01*
X169149Y-149846D01*
X174826Y-135263D01*
Y-152763D01*
G01X266599Y-135263D02*
Y-152763D01*
G01X261577Y-135263D02*
X271621D01*
G01X279514Y-150430D02*
X281261Y-151888D01*
X283226Y-152763D01*
X284972D01*
X286719Y-151888D01*
X288029Y-150430D01*
X288684Y-148388D01*
X288247Y-146347D01*
X287156Y-144596D01*
X285191Y-143430D01*
X282571Y-142846D01*
X281042Y-141680D01*
X280387Y-139638D01*
X280824Y-137596D01*
X281916Y-136138D01*
X283444Y-135263D01*
X284972D01*
X286501Y-135846D01*
X287811Y-137305D01*
G01X298979Y-135263D02*
X304219D01*
G01X301599D02*
Y-152763D01*
G01X298979D02*
X304219D01*
G01X314732Y-135263D02*
Y-152763D01*
X323466D01*
G01X331796D02*
Y-135263D01*
G01X340092D02*
X331796Y-146055D01*
G01X341402Y-152763D02*
X335507Y-141097D01*
G01X253482Y-90263D02*
Y-107763D01*
X262216D01*
G01X279279D02*
Y-96097D01*
G01Y-98138D02*
X278406Y-96972D01*
X277095Y-96388D01*
X275567Y-96097D01*
X274039Y-96680D01*
X272729Y-97846D01*
X271855Y-99596D01*
X271419Y-101930D01*
X271855Y-104263D01*
X272729Y-106013D01*
X274039Y-107180D01*
X275567Y-107763D01*
X277095Y-107471D01*
X278406Y-106597D01*
X279279Y-105430D01*
G01X288264Y-113013D02*
X289574Y-113596D01*
X291321Y-113013D01*
X292412Y-111847D01*
X293286Y-110388D01*
X294595Y-105722D01*
X297434Y-96097D01*
G01X290447D02*
X294595Y-105722D01*
G01X307074Y-99888D02*
X314061D01*
X313406Y-97846D01*
X312314Y-96680D01*
X310786Y-96097D01*
X309257Y-96388D01*
X307947Y-97263D01*
X307074Y-99305D01*
X306637Y-101055D01*
Y-102805D01*
X307074Y-104555D01*
X308166Y-106305D01*
X309476Y-107471D01*
X311004Y-107763D01*
X312532Y-107180D01*
X314061Y-105430D01*
G01X324792Y-107763D02*
Y-96097D01*
G01Y-98430D02*
X325884Y-97263D01*
X326976Y-96388D01*
X328504Y-96097D01*
X329595Y-96388D01*
X330906Y-97263D01*
G01X342074Y-105722D02*
X343166Y-106888D01*
X344694Y-107763D01*
X346004D01*
X347314Y-107180D01*
X348187Y-106305D01*
X348624Y-105139D01*
X348406Y-103388D01*
X347532Y-102513D01*
X343602Y-100763D01*
X342729Y-98721D01*
X343166Y-97263D01*
X344039Y-96388D01*
X345349Y-96097D01*
X346659Y-96388D01*
X347969Y-97263D01*
G01X404346Y-107763D02*
Y-90263D01*
X408712D01*
X410459Y-91138D01*
X411769Y-92305D01*
X412861Y-94054D01*
X413734Y-96097D01*
X413952Y-99013D01*
X413734Y-101930D01*
X412861Y-103972D01*
X411769Y-105722D01*
X410459Y-106888D01*
X408712Y-107763D01*
X404346D01*
G01X423374Y-99888D02*
X430361D01*
X429706Y-97846D01*
X428614Y-96680D01*
X427086Y-96097D01*
X425557Y-96388D01*
X424247Y-97263D01*
X423374Y-99305D01*
X422937Y-101055D01*
Y-102805D01*
X423374Y-104555D01*
X424466Y-106305D01*
X425776Y-107471D01*
X427304Y-107763D01*
X428832Y-107180D01*
X430361Y-105430D01*
G01X440874Y-105722D02*
X441966Y-106888D01*
X443494Y-107763D01*
X444804D01*
X446114Y-107180D01*
X446987Y-106305D01*
X447424Y-105139D01*
X447206Y-103388D01*
X446332Y-102513D01*
X442402Y-100763D01*
X441529Y-98721D01*
X441966Y-97263D01*
X442839Y-96388D01*
X444149Y-96097D01*
X445459Y-96388D01*
X446769Y-97263D01*
G01X461649Y-96097D02*
Y-107763D01*
G01Y-91430D02*
X461212Y-91138D01*
Y-90555D01*
X461649Y-90263D01*
X462086Y-90555D01*
Y-91138D01*
X461649Y-91430D01*
G01X476092Y-112138D02*
X477621Y-113305D01*
X479367Y-113596D01*
X480895Y-113305D01*
X482206Y-111847D01*
X483079Y-109805D01*
Y-96097D01*
G01Y-98430D02*
X482206Y-97263D01*
X480895Y-96388D01*
X479367Y-96097D01*
X477621Y-96680D01*
X476529Y-97846D01*
X475655Y-99888D01*
X475219Y-101930D01*
X475437Y-103680D01*
X476311Y-105722D01*
X477621Y-107180D01*
X479367Y-107763D01*
X480677Y-107471D01*
X482206Y-106305D01*
X483079Y-105139D01*
G01X492937Y-107763D02*
Y-96097D01*
G01Y-99013D02*
X493811Y-97555D01*
X495121Y-96388D01*
X496867Y-96097D01*
X498395Y-96388D01*
X499706Y-97555D01*
X500361Y-99596D01*
Y-107763D01*
G01X510874Y-99888D02*
X517861D01*
X517206Y-97846D01*
X516114Y-96680D01*
X514586Y-96097D01*
X513057Y-96388D01*
X511747Y-97263D01*
X510874Y-99305D01*
X510437Y-101055D01*
Y-102805D01*
X510874Y-104555D01*
X511966Y-106305D01*
X513276Y-107471D01*
X514804Y-107763D01*
X516332Y-107180D01*
X517861Y-105430D01*
G01X528592Y-107763D02*
Y-96097D01*
G01Y-98430D02*
X529684Y-97263D01*
X530776Y-96388D01*
X532304Y-96097D01*
X533395Y-96388D01*
X534706Y-97263D01*
G01X448096Y-152763D02*
Y-135263D01*
X452462D01*
X454209Y-136138D01*
X455519Y-137305D01*
X456611Y-139054D01*
X457484Y-141097D01*
X457702Y-144013D01*
X457484Y-146930D01*
X456611Y-148972D01*
X455519Y-150722D01*
X454209Y-151888D01*
X452462Y-152763D01*
X448096D01*
G01X470399Y-141097D02*
Y-152763D01*
G01Y-136430D02*
X469962Y-136138D01*
Y-135555D01*
X470399Y-135263D01*
X470836Y-135555D01*
Y-136138D01*
X470399Y-136430D01*
G01X487899Y-152763D02*
X486589Y-152471D01*
X485279Y-151305D01*
X484405Y-149263D01*
X483969Y-146930D01*
X484405Y-144596D01*
X485279Y-142555D01*
X486589Y-141388D01*
X487899Y-141097D01*
X489209Y-141388D01*
X490519Y-142555D01*
X491392Y-144596D01*
X491611Y-146930D01*
X491392Y-149263D01*
X490519Y-151305D01*
X489209Y-152471D01*
X487899Y-152763D01*
G01X575349D02*
Y-135263D01*
X572729Y-138763D01*
G01Y-152763D02*
X577969D01*
G01X588701Y-138180D02*
X590011Y-136430D01*
X591539Y-135555D01*
X593286Y-135263D01*
X595469Y-135846D01*
X596997Y-137305D01*
X597434Y-139054D01*
X597216Y-140805D01*
X596342Y-142263D01*
X591976Y-145180D01*
X590011Y-147221D01*
X588701Y-150139D01*
X588264Y-152763D01*
X597434D01*
G01X606419Y-153346D02*
X614279Y-135263D01*
G01X627849D02*
X626102Y-135846D01*
X624792Y-137305D01*
X623919Y-139054D01*
X623264Y-141388D01*
X623046Y-144013D01*
X623264Y-146638D01*
X623919Y-148972D01*
X624792Y-150722D01*
X626102Y-152180D01*
X627849Y-152763D01*
X629595Y-152180D01*
X630906Y-150722D01*
X631779Y-148972D01*
X632434Y-146638D01*
X632652Y-144013D01*
X632434Y-141388D01*
X631779Y-139054D01*
X630906Y-137305D01*
X629595Y-135846D01*
X627849Y-135263D01*
G01X644912Y-152763D02*
X645349Y-148972D01*
X646004Y-145763D01*
X646877Y-142846D01*
X647969Y-139638D01*
X649716Y-135263D01*
X640982D01*
G01X658919Y-153346D02*
X666779Y-135263D01*
G01X676201Y-138180D02*
X677511Y-136430D01*
X679039Y-135555D01*
X680786Y-135263D01*
X682969Y-135846D01*
X684497Y-137305D01*
X684934Y-139054D01*
X684716Y-140805D01*
X683842Y-142263D01*
X679476Y-145180D01*
X677511Y-147221D01*
X676201Y-150139D01*
X675764Y-152763D01*
X684934D01*
G01X697849Y-135263D02*
X696102Y-135846D01*
X694792Y-137305D01*
X693919Y-139054D01*
X693264Y-141388D01*
X693046Y-144013D01*
X693264Y-146638D01*
X693919Y-148972D01*
X694792Y-150722D01*
X696102Y-152180D01*
X697849Y-152763D01*
X699595Y-152180D01*
X700906Y-150722D01*
X701779Y-148972D01*
X702434Y-146638D01*
X702652Y-144013D01*
X702434Y-141388D01*
X701779Y-139054D01*
X700906Y-137305D01*
X699595Y-135846D01*
X697849Y-135263D01*
G01X715349Y-152763D02*
Y-135263D01*
X712729Y-138763D01*
G01Y-152763D02*
X717969D01*
G01X728701Y-138180D02*
X730011Y-136430D01*
X731539Y-135555D01*
X733286Y-135263D01*
X735469Y-135846D01*
X736997Y-137305D01*
X737434Y-139054D01*
X737216Y-140805D01*
X736342Y-142263D01*
X731976Y-145180D01*
X730011Y-147221D01*
X728701Y-150139D01*
X728264Y-152763D01*
X737434D01*
G01X623046Y-107763D02*
Y-90263D01*
X627412D01*
X629159Y-91138D01*
X630469Y-92305D01*
X631561Y-94054D01*
X632434Y-96097D01*
X632652Y-99013D01*
X632434Y-101930D01*
X631561Y-103972D01*
X630469Y-105722D01*
X629159Y-106888D01*
X627412Y-107763D01*
X623046D01*
G01X649279D02*
Y-96097D01*
G01Y-98138D02*
X648406Y-96972D01*
X647095Y-96388D01*
X645567Y-96097D01*
X644039Y-96680D01*
X642729Y-97846D01*
X641855Y-99596D01*
X641419Y-101930D01*
X641855Y-104263D01*
X642729Y-106013D01*
X644039Y-107180D01*
X645567Y-107763D01*
X647095Y-107471D01*
X648406Y-106597D01*
X649279Y-105430D01*
G01X662849Y-90263D02*
Y-107763D01*
G01X659792Y-96097D02*
X665906D01*
G01X677074Y-99888D02*
X684061D01*
X683406Y-97846D01*
X682314Y-96680D01*
X680786Y-96097D01*
X679257Y-96388D01*
X677947Y-97263D01*
X677074Y-99305D01*
X676637Y-101055D01*
Y-102805D01*
X677074Y-104555D01*
X678166Y-106305D01*
X679476Y-107471D01*
X681004Y-107763D01*
X682532Y-107180D01*
X684061Y-105430D01*
G01X-24594Y94110D02*
Y42110D01*
X19706D01*
Y94110D01*
X-24594D01*
G01Y527339D02*
Y475339D01*
X19706D01*
Y527339D01*
X-24594D01*
G01Y787181D02*
Y735181D01*
X19706D01*
Y787181D01*
X-24594D01*
G01Y1233323D02*
Y1181323D01*
X19706D01*
Y1233323D01*
X-24594D01*
G01Y1493165D02*
Y1441165D01*
X19706D01*
Y1493165D01*
X-24594D01*
G01Y1926394D02*
Y1874394D01*
X19706D01*
Y1926394D01*
X-24594D01*
G01X25208Y54317D02*
X25083Y54067D01*
X25000Y53775D01*
Y53442D01*
X25125Y53067D01*
X25333Y52775D01*
X25583Y52567D01*
X26000Y52400D01*
X26375Y52358D01*
X26750Y52442D01*
X27000Y52567D01*
X27250Y52817D01*
X27417Y53108D01*
X27500Y53400D01*
Y53692D01*
X27417Y53983D01*
X27292Y54233D01*
X27125Y54442D01*
G01X27500Y55542D02*
X25000D01*
X27500Y57458D01*
X25000D01*
G01X26458Y58808D02*
X26167Y59100D01*
X26000Y59350D01*
X25917Y59683D01*
X26000Y59975D01*
X26167Y60183D01*
X26417Y60350D01*
X26708Y60392D01*
X26958Y60350D01*
X27208Y60183D01*
X27417Y59933D01*
X27500Y59642D01*
X27417Y59308D01*
X27167Y59017D01*
X26792Y58850D01*
X26375Y58808D01*
X25833Y58892D01*
X25542Y59017D01*
X25250Y59225D01*
X25042Y59517D01*
X25000Y59808D01*
X25083Y60100D01*
X25292Y60308D01*
G01X24175Y177500D02*
Y180000D01*
G01X25925D02*
Y177500D01*
G01Y178750D02*
X24175D01*
G01X27358Y179583D02*
X27608Y179833D01*
X27900Y179958D01*
X28233Y180000D01*
X28650Y179917D01*
X28942Y179708D01*
X29025Y179458D01*
X28983Y179208D01*
X28817Y179000D01*
X27983Y178583D01*
X27608Y178292D01*
X27358Y177875D01*
X27275Y177500D01*
X29025D01*
G01X13017Y204000D02*
Y201500D01*
X14683D01*
G01X17783D02*
X16117D01*
Y204000D01*
X17783D01*
G01X17117Y202792D02*
X16117D01*
G01X19133Y201500D02*
Y204000D01*
X19967D01*
X20300Y203875D01*
X20550Y203708D01*
X20758Y203458D01*
X20925Y203167D01*
X20967Y202750D01*
X20925Y202333D01*
X20758Y202042D01*
X20550Y201792D01*
X20300Y201625D01*
X19967Y201500D01*
X19133D01*
G01X22358Y202542D02*
X22650Y202833D01*
X22900Y203000D01*
X23233Y203083D01*
X23525Y203000D01*
X23733Y202833D01*
X23900Y202583D01*
X23942Y202292D01*
X23900Y202042D01*
X23733Y201792D01*
X23483Y201583D01*
X23192Y201500D01*
X22858Y201583D01*
X22567Y201833D01*
X22400Y202208D01*
X22358Y202625D01*
X22442Y203167D01*
X22567Y203458D01*
X22775Y203750D01*
X23067Y203958D01*
X23358Y204000D01*
X23650Y203917D01*
X23858Y203708D01*
G01X-9701Y227766D02*
X5099D01*
Y235066D01*
X34799D01*
Y206666D01*
X5099D01*
Y213966D01*
X-9701D01*
Y227766D01*
G01X24317Y294792D02*
X24067Y294917D01*
X23775Y295000D01*
X23442D01*
X23067Y294875D01*
X22775Y294667D01*
X22567Y294417D01*
X22400Y294000D01*
X22358Y293625D01*
X22442Y293250D01*
X22567Y293000D01*
X22817Y292750D01*
X23108Y292583D01*
X23400Y292500D01*
X23692D01*
X23983Y292583D01*
X24233Y292708D01*
X24442Y292875D01*
G01X25708Y294583D02*
X25958Y294833D01*
X26250Y294958D01*
X26583Y295000D01*
X27000Y294917D01*
X27292Y294708D01*
X27375Y294458D01*
X27333Y294208D01*
X27167Y294000D01*
X26333Y293583D01*
X25958Y293292D01*
X25708Y292875D01*
X25625Y292500D01*
X27375D01*
G01X28683Y293000D02*
X28933Y292708D01*
X29267Y292542D01*
X29642Y292500D01*
X29975Y292542D01*
X30308Y292750D01*
X30517Y293000D01*
X30558Y293250D01*
X30475Y293542D01*
X30183Y293750D01*
X29892Y293833D01*
X29517D01*
G01X29892D02*
X30142Y293958D01*
X30350Y294167D01*
X30433Y294417D01*
X30350Y294667D01*
X30142Y294875D01*
X29767Y295000D01*
X29392Y294958D01*
X29017Y294792D01*
G01X15500Y253067D02*
X13000D01*
Y254108D01*
X13125Y254442D01*
X13292Y254650D01*
X13625Y254733D01*
X13958Y254650D01*
X14167Y254400D01*
X14292Y254108D01*
Y253067D01*
G01Y254108D02*
X15500Y254733D01*
G01X13417Y256208D02*
X13167Y256458D01*
X13042Y256750D01*
X13000Y257083D01*
X13083Y257500D01*
X13292Y257792D01*
X13542Y257875D01*
X13792Y257833D01*
X14000Y257667D01*
X14417Y256833D01*
X14708Y256458D01*
X15125Y256208D01*
X15500Y256125D01*
Y257875D01*
G01X14458Y259308D02*
X14167Y259600D01*
X14000Y259850D01*
X13917Y260183D01*
X14000Y260475D01*
X14167Y260683D01*
X14417Y260850D01*
X14708Y260892D01*
X14958Y260850D01*
X15208Y260683D01*
X15417Y260433D01*
X15500Y260142D01*
X15417Y259808D01*
X15167Y259517D01*
X14792Y259350D01*
X14375Y259308D01*
X13833Y259392D01*
X13542Y259517D01*
X13250Y259725D01*
X13042Y260017D01*
X13000Y260308D01*
X13083Y260600D01*
X13292Y260808D01*
G01X11500Y253067D02*
X9000D01*
Y254108D01*
X9125Y254442D01*
X9292Y254650D01*
X9625Y254733D01*
X9958Y254650D01*
X10167Y254400D01*
X10292Y254108D01*
Y253067D01*
G01Y254108D02*
X11500Y254733D01*
G01X9417Y256208D02*
X9167Y256458D01*
X9042Y256750D01*
X9000Y257083D01*
X9083Y257500D01*
X9292Y257792D01*
X9542Y257875D01*
X9792Y257833D01*
X10000Y257667D01*
X10417Y256833D01*
X10708Y256458D01*
X11125Y256208D01*
X11500Y256125D01*
Y257875D01*
G01X11125Y259183D02*
X11333Y259433D01*
X11458Y259725D01*
X11500Y260100D01*
X11417Y260475D01*
X11250Y260767D01*
X10958Y260975D01*
X10625Y261017D01*
X10292Y260933D01*
X10083Y260725D01*
X9917Y260433D01*
X9875Y260142D01*
X9917Y259850D01*
X10083Y259475D01*
X9000Y259600D01*
Y260725D01*
G01X29017Y276000D02*
Y278500D01*
X30058D01*
X30392Y278375D01*
X30600Y278208D01*
X30683Y277875D01*
X30600Y277542D01*
X30350Y277333D01*
X30058Y277208D01*
X29017D01*
G01X30058D02*
X30683Y276000D01*
G01X32950D02*
Y278500D01*
X32450Y278000D01*
G01Y276000D02*
X33450D01*
G01X35258Y277042D02*
X35550Y277333D01*
X35800Y277500D01*
X36133Y277583D01*
X36425Y277500D01*
X36633Y277333D01*
X36800Y277083D01*
X36842Y276792D01*
X36800Y276542D01*
X36633Y276292D01*
X36383Y276083D01*
X36092Y276000D01*
X35758Y276083D01*
X35467Y276333D01*
X35300Y276708D01*
X35258Y277125D01*
X35342Y277667D01*
X35467Y277958D01*
X35675Y278250D01*
X35967Y278458D01*
X36258Y278500D01*
X36550Y278417D01*
X36758Y278208D01*
G01X38358Y277042D02*
X38650Y277333D01*
X38900Y277500D01*
X39233Y277583D01*
X39525Y277500D01*
X39733Y277333D01*
X39900Y277083D01*
X39942Y276792D01*
X39900Y276542D01*
X39733Y276292D01*
X39483Y276083D01*
X39192Y276000D01*
X38858Y276083D01*
X38567Y276333D01*
X38400Y276708D01*
X38358Y277125D01*
X38442Y277667D01*
X38567Y277958D01*
X38775Y278250D01*
X39067Y278458D01*
X39358Y278500D01*
X39650Y278417D01*
X39858Y278208D01*
G01X7000Y253950D02*
X6958Y253617D01*
X6792Y253325D01*
X6542Y253075D01*
X6250Y252908D01*
X5917Y252825D01*
X5583D01*
X5250Y252908D01*
X4958Y253075D01*
X4708Y253325D01*
X4542Y253617D01*
X4500Y253950D01*
X4542Y254283D01*
X4708Y254575D01*
X4958Y254825D01*
X5250Y254992D01*
X5583Y255075D01*
X5917D01*
X6250Y254992D01*
X6542Y254825D01*
X6792Y254575D01*
X6958Y254283D01*
X7000Y253950D01*
G01X6333Y254283D02*
X7000Y254783D01*
G01X6500Y256133D02*
X6792Y256383D01*
X6958Y256717D01*
X7000Y257092D01*
X6958Y257425D01*
X6750Y257758D01*
X6500Y257967D01*
X6250Y258008D01*
X5958Y257925D01*
X5750Y257633D01*
X5667Y257342D01*
Y256967D01*
G01Y257342D02*
X5542Y257592D01*
X5333Y257800D01*
X5083Y257883D01*
X4833Y257800D01*
X4625Y257592D01*
X4500Y257217D01*
X4542Y256842D01*
X4708Y256467D01*
G01X17096Y251803D02*
X30096D01*
G01X17096Y265803D02*
Y251803D01*
G01X30096Y265803D02*
X17096D01*
G01X12017Y242500D02*
Y245000D01*
X13058D01*
X13392Y244875D01*
X13600Y244708D01*
X13683Y244375D01*
X13600Y244042D01*
X13350Y243833D01*
X13058Y243708D01*
X12017D01*
G01X13058D02*
X13683Y242500D01*
G01X15950D02*
Y245000D01*
X15450Y244500D01*
G01Y242500D02*
X16450D01*
G01X18258Y244583D02*
X18508Y244833D01*
X18800Y244958D01*
X19133Y245000D01*
X19550Y244917D01*
X19842Y244708D01*
X19925Y244458D01*
X19883Y244208D01*
X19717Y244000D01*
X18883Y243583D01*
X18508Y243292D01*
X18258Y242875D01*
X18175Y242500D01*
X19925D01*
G01X21358Y244583D02*
X21608Y244833D01*
X21900Y244958D01*
X22233Y245000D01*
X22650Y244917D01*
X22942Y244708D01*
X23025Y244458D01*
X22983Y244208D01*
X22817Y244000D01*
X21983Y243583D01*
X21608Y243292D01*
X21358Y242875D01*
X21275Y242500D01*
X23025D01*
G01X42200Y250900D02*
Y242900D01*
X24600D01*
Y250900D01*
X42200D01*
G01X-9701Y355463D02*
X5099D01*
Y362763D01*
X34799D01*
Y334363D01*
X5099D01*
Y341663D01*
X-9701D01*
Y355463D01*
G01X15500Y302517D02*
X13000D01*
Y303558D01*
X13125Y303892D01*
X13292Y304100D01*
X13625Y304183D01*
X13958Y304100D01*
X14167Y303850D01*
X14292Y303558D01*
Y302517D01*
G01Y303558D02*
X15500Y304183D01*
G01Y306450D02*
X13000D01*
X13500Y305950D01*
G01X15500D02*
Y306950D01*
G01Y309550D02*
X13000D01*
X13500Y309050D01*
G01X15500D02*
Y310050D01*
G01X15000Y311733D02*
X15292Y311983D01*
X15458Y312317D01*
X15500Y312692D01*
X15458Y313025D01*
X15250Y313358D01*
X15000Y313567D01*
X14750Y313608D01*
X14458Y313525D01*
X14250Y313233D01*
X14167Y312942D01*
Y312567D01*
G01Y312942D02*
X14042Y313192D01*
X13833Y313400D01*
X13583Y313483D01*
X13333Y313400D01*
X13125Y313192D01*
X13000Y312817D01*
X13042Y312442D01*
X13208Y312067D01*
G01X21283Y312682D02*
X17283D01*
Y305282D01*
G01X13667Y319500D02*
Y322000D01*
X14708D01*
X15042Y321875D01*
X15250Y321708D01*
X15333Y321375D01*
X15250Y321042D01*
X15000Y320833D01*
X14708Y320708D01*
X13667D01*
G01X14708D02*
X15333Y319500D01*
G01X16808Y321583D02*
X17058Y321833D01*
X17350Y321958D01*
X17683Y322000D01*
X18100Y321917D01*
X18392Y321708D01*
X18475Y321458D01*
X18433Y321208D01*
X18267Y321000D01*
X17433Y320583D01*
X17058Y320292D01*
X16808Y319875D01*
X16725Y319500D01*
X18475D01*
G01X19992Y319792D02*
X20283Y319583D01*
X20617Y319500D01*
X20950Y319583D01*
X21242Y319833D01*
X21450Y320208D01*
X21533Y320583D01*
Y321042D01*
X21450Y321417D01*
X21242Y321750D01*
X20992Y321917D01*
X20700Y322000D01*
X20367Y321917D01*
X20117Y321750D01*
X19950Y321500D01*
X19867Y321167D01*
X19950Y320875D01*
X20158Y320583D01*
X20408Y320417D01*
X20700Y320375D01*
X21033Y320458D01*
X21283Y320667D01*
X21533Y321042D01*
G01X27100Y323300D02*
Y319300D01*
X34500D01*
G01X22300Y316100D02*
Y302100D01*
G01X35300Y316100D02*
X22300D01*
G01Y302100D02*
X35300D01*
G01X9417Y327900D02*
Y330400D01*
X10458D01*
X10792Y330275D01*
X11000Y330108D01*
X11083Y329775D01*
X11000Y329442D01*
X10750Y329233D01*
X10458Y329108D01*
X9417D01*
G01X10458D02*
X11083Y327900D01*
G01X13350D02*
Y330400D01*
X12850Y329900D01*
G01Y327900D02*
X13850D01*
G01X15658Y329983D02*
X15908Y330233D01*
X16200Y330358D01*
X16533Y330400D01*
X16950Y330317D01*
X17242Y330108D01*
X17325Y329858D01*
X17283Y329608D01*
X17117Y329400D01*
X16283Y328983D01*
X15908Y328692D01*
X15658Y328275D01*
X15575Y327900D01*
X17325D01*
G01X18633Y328400D02*
X18883Y328108D01*
X19217Y327942D01*
X19592Y327900D01*
X19925Y327942D01*
X20258Y328150D01*
X20467Y328400D01*
X20508Y328650D01*
X20425Y328942D01*
X20133Y329150D01*
X19842Y329233D01*
X19467D01*
G01X19842D02*
X20092Y329358D01*
X20300Y329567D01*
X20383Y329817D01*
X20300Y330067D01*
X20092Y330275D01*
X19717Y330400D01*
X19342Y330358D01*
X18967Y330192D01*
G01X22000Y324500D02*
Y332500D01*
X39600D01*
Y324500D01*
X22000D01*
G01X16100Y388800D02*
Y406800D01*
G01X27300Y388800D02*
X16100D01*
G01Y427300D02*
X27300D01*
G01X16100Y409300D02*
Y427300D01*
G01X27300Y409300D02*
X16100D01*
G01Y406800D02*
X27300D01*
G01X23708Y489317D02*
X23583Y489067D01*
X23500Y488775D01*
Y488442D01*
X23625Y488067D01*
X23833Y487775D01*
X24083Y487567D01*
X24500Y487400D01*
X24875Y487358D01*
X25250Y487442D01*
X25500Y487567D01*
X25750Y487817D01*
X25917Y488108D01*
X26000Y488400D01*
Y488692D01*
X25917Y488983D01*
X25792Y489233D01*
X25625Y489442D01*
G01X26000Y490542D02*
X23500D01*
X26000Y492458D01*
X23500D01*
G01X25625Y493683D02*
X25833Y493933D01*
X25958Y494225D01*
X26000Y494600D01*
X25917Y494975D01*
X25750Y495267D01*
X25458Y495475D01*
X25125Y495517D01*
X24792Y495433D01*
X24583Y495225D01*
X24417Y494933D01*
X24375Y494642D01*
X24417Y494350D01*
X24583Y493975D01*
X23500Y494100D01*
Y495225D01*
G01X22300Y564217D02*
X17300D01*
Y567383D01*
G01X19717Y566217D02*
Y564217D01*
G01X18133Y569817D02*
X17633Y570317D01*
X17383Y570900D01*
X17300Y571567D01*
X17467Y572400D01*
X17883Y572983D01*
X18383Y573150D01*
X18883Y573067D01*
X19300Y572733D01*
X20133Y571067D01*
X20717Y570317D01*
X21550Y569817D01*
X22300Y569650D01*
Y573150D01*
G01X22467Y577000D02*
X22383Y576833D01*
X22217D01*
X22133Y577000D01*
X22217Y577167D01*
X22383D01*
X22467Y577000D01*
G01X20217D02*
X20133Y576833D01*
X19967D01*
X19883Y577000D01*
X19967Y577167D01*
X20133D01*
X20217Y577000D01*
G01X21300Y580767D02*
X21883Y581267D01*
X22217Y581933D01*
X22300Y582683D01*
X22217Y583350D01*
X21800Y584017D01*
X21300Y584433D01*
X20800Y584517D01*
X20217Y584350D01*
X19800Y583767D01*
X19633Y583183D01*
Y582433D01*
G01Y583183D02*
X19383Y583683D01*
X18967Y584100D01*
X18467Y584267D01*
X17967Y584100D01*
X17550Y583683D01*
X17300Y582933D01*
X17383Y582183D01*
X17717Y581433D01*
G01X22300Y586117D02*
X17300Y588200D01*
X22300Y590283D01*
G01X20550Y589533D02*
Y586867D01*
G01X22467Y592300D02*
X17300Y595300D01*
G01X22300Y599400D02*
X17300D01*
X18300Y598400D01*
G01X22300D02*
Y600400D01*
G01X21550Y603167D02*
X21967Y603667D01*
X22217Y604250D01*
X22300Y605000D01*
X22133Y605750D01*
X21800Y606333D01*
X21217Y606750D01*
X20550Y606833D01*
X19883Y606667D01*
X19467Y606250D01*
X19133Y605667D01*
X19050Y605083D01*
X19133Y604500D01*
X19467Y603750D01*
X17300Y604000D01*
Y606250D01*
G01Y608517D02*
X22300Y610600D01*
X17300Y612683D01*
G01X29067Y563500D02*
Y566000D01*
X30108D01*
X30442Y565875D01*
X30650Y565708D01*
X30733Y565375D01*
X30650Y565042D01*
X30400Y564833D01*
X30108Y564708D01*
X29067D01*
G01X30108D02*
X30733Y563500D01*
G01X32208Y564542D02*
X32500Y564833D01*
X32750Y565000D01*
X33083Y565083D01*
X33375Y565000D01*
X33583Y564833D01*
X33750Y564583D01*
X33792Y564292D01*
X33750Y564042D01*
X33583Y563792D01*
X33333Y563583D01*
X33042Y563500D01*
X32708Y563583D01*
X32417Y563833D01*
X32250Y564208D01*
X32208Y564625D01*
X32292Y565167D01*
X32417Y565458D01*
X32625Y565750D01*
X32917Y565958D01*
X33208Y566000D01*
X33500Y565917D01*
X33708Y565708D01*
G01X36600Y563500D02*
Y566000D01*
X35058Y564208D01*
X37142D01*
G01X35400Y568800D02*
Y572800D01*
X28000D01*
G01X23850Y651000D02*
Y648500D01*
G01X22892Y651000D02*
X24808D01*
G01X27867Y650792D02*
X27617Y650917D01*
X27325Y651000D01*
X26992D01*
X26617Y650875D01*
X26325Y650667D01*
X26117Y650417D01*
X25950Y650000D01*
X25908Y649625D01*
X25992Y649250D01*
X26117Y649000D01*
X26367Y648750D01*
X26658Y648583D01*
X26950Y648500D01*
X27242D01*
X27533Y648583D01*
X27783Y648708D01*
X27992Y648875D01*
G01X30050Y648500D02*
Y651000D01*
X29550Y650500D01*
G01Y648500D02*
X30550D01*
G01X33650D02*
Y651000D01*
X32108Y649208D01*
X34192D01*
G01X11575Y646500D02*
Y649000D01*
G01X13325D02*
Y646500D01*
G01Y647750D02*
X11575D01*
G01X15467Y646500D02*
X15550Y647042D01*
X15675Y647500D01*
X15842Y647917D01*
X16050Y648375D01*
X16383Y649000D01*
X14717D01*
G01X12300Y676000D02*
X23500D01*
G01X12300Y658000D02*
Y676000D01*
G01X23500Y658000D02*
X12300D01*
G01X13808Y685717D02*
X13683Y685467D01*
X13600Y685175D01*
Y684842D01*
X13725Y684467D01*
X13933Y684175D01*
X14183Y683967D01*
X14600Y683800D01*
X14975Y683758D01*
X15350Y683842D01*
X15600Y683967D01*
X15850Y684217D01*
X16017Y684508D01*
X16100Y684800D01*
Y685092D01*
X16017Y685383D01*
X15892Y685633D01*
X15725Y685842D01*
G01Y686983D02*
X15933Y687233D01*
X16058Y687525D01*
X16100Y687900D01*
X16017Y688275D01*
X15850Y688567D01*
X15558Y688775D01*
X15225Y688817D01*
X14892Y688733D01*
X14683Y688525D01*
X14517Y688233D01*
X14475Y687942D01*
X14517Y687650D01*
X14683Y687275D01*
X13600Y687400D01*
Y688525D01*
G01X15600Y690083D02*
X15892Y690333D01*
X16058Y690667D01*
X16100Y691042D01*
X16058Y691375D01*
X15850Y691708D01*
X15600Y691917D01*
X15350Y691958D01*
X15058Y691875D01*
X14850Y691583D01*
X14767Y691292D01*
Y690917D01*
G01Y691292D02*
X14642Y691542D01*
X14433Y691750D01*
X14183Y691833D01*
X13933Y691750D01*
X13725Y691542D01*
X13600Y691167D01*
X13642Y690792D01*
X13808Y690417D01*
G01X18208Y685717D02*
X18083Y685467D01*
X18000Y685175D01*
Y684842D01*
X18125Y684467D01*
X18333Y684175D01*
X18583Y683967D01*
X19000Y683800D01*
X19375Y683758D01*
X19750Y683842D01*
X20000Y683967D01*
X20250Y684217D01*
X20417Y684508D01*
X20500Y684800D01*
Y685092D01*
X20417Y685383D01*
X20292Y685633D01*
X20125Y685842D01*
G01Y686983D02*
X20333Y687233D01*
X20458Y687525D01*
X20500Y687900D01*
X20417Y688275D01*
X20250Y688567D01*
X19958Y688775D01*
X19625Y688817D01*
X19292Y688733D01*
X19083Y688525D01*
X18917Y688233D01*
X18875Y687942D01*
X18917Y687650D01*
X19083Y687275D01*
X18000Y687400D01*
Y688525D01*
G01X18417Y690208D02*
X18167Y690458D01*
X18042Y690750D01*
X18000Y691083D01*
X18083Y691500D01*
X18292Y691792D01*
X18542Y691875D01*
X18792Y691833D01*
X19000Y691667D01*
X19417Y690833D01*
X19708Y690458D01*
X20125Y690208D01*
X20500Y690125D01*
Y691875D01*
G01X-9701Y920817D02*
X5099D01*
Y928117D01*
X34799D01*
Y899717D01*
X5099D01*
Y907017D01*
X-9701D01*
Y920817D01*
G01X22017Y933500D02*
Y931000D01*
X23683D01*
G01X26783D02*
X25117D01*
Y933500D01*
X26783D01*
G01X26117Y932292D02*
X25117D01*
G01X28133Y931000D02*
Y933500D01*
X28967D01*
X29300Y933375D01*
X29550Y933208D01*
X29758Y932958D01*
X29925Y932667D01*
X29967Y932250D01*
X29925Y931833D01*
X29758Y931542D01*
X29550Y931292D01*
X29300Y931125D01*
X28967Y931000D01*
X28133D01*
G01X32650D02*
Y933500D01*
X31108Y931708D01*
X33192D01*
G01X13517Y1037500D02*
Y1035000D01*
X15183D01*
G01X18283D02*
X16617D01*
Y1037500D01*
X18283D01*
G01X17617Y1036292D02*
X16617D01*
G01X19633Y1035000D02*
Y1037500D01*
X20467D01*
X20800Y1037375D01*
X21050Y1037208D01*
X21258Y1036958D01*
X21425Y1036667D01*
X21467Y1036250D01*
X21425Y1035833D01*
X21258Y1035542D01*
X21050Y1035292D01*
X20800Y1035125D01*
X20467Y1035000D01*
X19633D01*
G01X22733Y1035500D02*
X22983Y1035208D01*
X23317Y1035042D01*
X23692Y1035000D01*
X24025Y1035042D01*
X24358Y1035250D01*
X24567Y1035500D01*
X24608Y1035750D01*
X24525Y1036042D01*
X24233Y1036250D01*
X23942Y1036333D01*
X23567D01*
G01X23942D02*
X24192Y1036458D01*
X24400Y1036667D01*
X24483Y1036917D01*
X24400Y1037167D01*
X24192Y1037375D01*
X23817Y1037500D01*
X23442Y1037458D01*
X23067Y1037292D01*
G01X-9701Y1061487D02*
X5099D01*
Y1068787D01*
X34799D01*
Y1040387D01*
X5099D01*
Y1047687D01*
X-9701D01*
Y1061487D01*
G01X28100Y1085600D02*
Y1081600D01*
X35500D01*
G01X22967Y1109200D02*
Y1111700D01*
X24008D01*
X24342Y1111575D01*
X24550Y1111408D01*
X24633Y1111075D01*
X24550Y1110742D01*
X24300Y1110533D01*
X24008Y1110408D01*
X22967D01*
G01X24008D02*
X24633Y1109200D01*
G01X25983Y1109700D02*
X26233Y1109408D01*
X26567Y1109242D01*
X26942Y1109200D01*
X27275Y1109242D01*
X27608Y1109450D01*
X27817Y1109700D01*
X27858Y1109950D01*
X27775Y1110242D01*
X27483Y1110450D01*
X27192Y1110533D01*
X26817D01*
G01X27192D02*
X27442Y1110658D01*
X27650Y1110867D01*
X27733Y1111117D01*
X27650Y1111367D01*
X27442Y1111575D01*
X27067Y1111700D01*
X26692Y1111658D01*
X26317Y1111492D01*
G01X29917Y1109200D02*
X30000Y1109742D01*
X30125Y1110200D01*
X30292Y1110617D01*
X30500Y1111075D01*
X30833Y1111700D01*
X29167D01*
G01X29700Y1104000D02*
Y1108000D01*
X22300D01*
G01X19500Y1090950D02*
X19458Y1090617D01*
X19292Y1090325D01*
X19042Y1090075D01*
X18750Y1089908D01*
X18417Y1089825D01*
X18083D01*
X17750Y1089908D01*
X17458Y1090075D01*
X17208Y1090325D01*
X17042Y1090617D01*
X17000Y1090950D01*
X17042Y1091283D01*
X17208Y1091575D01*
X17458Y1091825D01*
X17750Y1091992D01*
X18083Y1092075D01*
X18417D01*
X18750Y1091992D01*
X19042Y1091825D01*
X19292Y1091575D01*
X19458Y1091283D01*
X19500Y1090950D01*
G01X18833Y1091283D02*
X19500Y1091783D01*
G01X18458Y1093258D02*
X18167Y1093550D01*
X18000Y1093800D01*
X17917Y1094133D01*
X18000Y1094425D01*
X18167Y1094633D01*
X18417Y1094800D01*
X18708Y1094842D01*
X18958Y1094800D01*
X19208Y1094633D01*
X19417Y1094383D01*
X19500Y1094092D01*
X19417Y1093758D01*
X19167Y1093467D01*
X18792Y1093300D01*
X18375Y1093258D01*
X17833Y1093342D01*
X17542Y1093467D01*
X17250Y1093675D01*
X17042Y1093967D01*
X17000Y1094258D01*
X17083Y1094550D01*
X17292Y1094758D01*
G01X21118Y1086583D02*
X35118D01*
G01X21118Y1099583D02*
Y1086583D01*
G01X35118Y1099583D02*
X21118D01*
G01X17575Y1359000D02*
Y1361500D01*
G01X19325D02*
Y1359000D01*
G01Y1360250D02*
X17575D01*
G01X22050Y1359000D02*
Y1361500D01*
X20508Y1359708D01*
X22592D01*
G01X12517Y1602000D02*
Y1599500D01*
X14183D01*
G01X17283D02*
X15617D01*
Y1602000D01*
X17283D01*
G01X16617Y1600792D02*
X15617D01*
G01X18633Y1599500D02*
Y1602000D01*
X19467D01*
X19800Y1601875D01*
X20050Y1601708D01*
X20258Y1601458D01*
X20425Y1601167D01*
X20467Y1600750D01*
X20425Y1600333D01*
X20258Y1600042D01*
X20050Y1599792D01*
X19800Y1599625D01*
X19467Y1599500D01*
X18633D01*
G01X21858Y1601583D02*
X22108Y1601833D01*
X22400Y1601958D01*
X22733Y1602000D01*
X23150Y1601917D01*
X23442Y1601708D01*
X23525Y1601458D01*
X23483Y1601208D01*
X23317Y1601000D01*
X22483Y1600583D01*
X22108Y1600292D01*
X21858Y1599875D01*
X21775Y1599500D01*
X23525D01*
G01X-9701Y1626841D02*
X5099D01*
Y1634141D01*
X34799D01*
Y1605741D01*
X5099D01*
Y1613041D01*
X-9701D01*
Y1626841D01*
G01X5819Y1642924D02*
Y1645424D01*
X6860D01*
X7194Y1645299D01*
X7402Y1645132D01*
X7485Y1644799D01*
X7402Y1644466D01*
X7152Y1644257D01*
X6860Y1644132D01*
X5819D01*
G01X6860D02*
X7485Y1642924D01*
G01X8960Y1645007D02*
X9210Y1645257D01*
X9502Y1645382D01*
X9835Y1645424D01*
X10252Y1645341D01*
X10544Y1645132D01*
X10627Y1644882D01*
X10585Y1644632D01*
X10419Y1644424D01*
X9585Y1644007D01*
X9210Y1643716D01*
X8960Y1643299D01*
X8877Y1642924D01*
X10627D01*
G01X12769D02*
X12852Y1643466D01*
X12977Y1643924D01*
X13144Y1644341D01*
X13352Y1644799D01*
X13685Y1645424D01*
X12019D01*
G01X16600Y1646300D02*
Y1642300D01*
X24000D01*
G01X5919Y1638324D02*
Y1640824D01*
X6960D01*
X7294Y1640699D01*
X7502Y1640532D01*
X7585Y1640199D01*
X7502Y1639866D01*
X7252Y1639657D01*
X6960Y1639532D01*
X5919D01*
G01X6960D02*
X7585Y1638324D01*
G01X9060Y1640407D02*
X9310Y1640657D01*
X9602Y1640782D01*
X9935Y1640824D01*
X10352Y1640741D01*
X10644Y1640532D01*
X10727Y1640282D01*
X10685Y1640032D01*
X10519Y1639824D01*
X9685Y1639407D01*
X9310Y1639116D01*
X9060Y1638699D01*
X8977Y1638324D01*
X10727D01*
G01X12952D02*
X13244Y1638366D01*
X13577Y1638491D01*
X13785Y1638699D01*
X13869Y1638991D01*
X13785Y1639282D01*
X13535Y1639532D01*
X13160Y1639657D01*
X12744D01*
X12494Y1639741D01*
X12285Y1639949D01*
X12202Y1640241D01*
X12327Y1640532D01*
X12619Y1640741D01*
X12952Y1640824D01*
X13285Y1640741D01*
X13577Y1640532D01*
X13702Y1640241D01*
X13619Y1639949D01*
X13410Y1639741D01*
X13160Y1639657D01*
X12744D01*
X12369Y1639532D01*
X12119Y1639282D01*
X12035Y1638991D01*
X12119Y1638699D01*
X12327Y1638491D01*
X12660Y1638366D01*
X12952Y1638324D01*
G01X24000Y1638200D02*
Y1642200D01*
X16600D01*
G01X25000Y1638300D02*
X38000D01*
G01X25000Y1652300D02*
Y1638300D01*
G01X38000Y1652300D02*
X25000D01*
G01X65650Y1667900D02*
Y1693100D01*
X27350D01*
Y1667900D01*
X65650D01*
G01X14717Y1663700D02*
Y1666200D01*
X15758D01*
X16092Y1666075D01*
X16300Y1665908D01*
X16383Y1665575D01*
X16300Y1665242D01*
X16050Y1665033D01*
X15758Y1664908D01*
X14717D01*
G01X15758D02*
X16383Y1663700D01*
G01X18650D02*
Y1666200D01*
X18150Y1665700D01*
G01Y1663700D02*
X19150D01*
G01X20958Y1665783D02*
X21208Y1666033D01*
X21500Y1666158D01*
X21833Y1666200D01*
X22250Y1666117D01*
X22542Y1665908D01*
X22625Y1665658D01*
X22583Y1665408D01*
X22417Y1665200D01*
X21583Y1664783D01*
X21208Y1664492D01*
X20958Y1664075D01*
X20875Y1663700D01*
X22625D01*
G01X24058Y1664742D02*
X24350Y1665033D01*
X24600Y1665200D01*
X24933Y1665283D01*
X25225Y1665200D01*
X25433Y1665033D01*
X25600Y1664783D01*
X25642Y1664492D01*
X25600Y1664242D01*
X25433Y1663992D01*
X25183Y1663783D01*
X24892Y1663700D01*
X24558Y1663783D01*
X24267Y1664033D01*
X24100Y1664408D01*
X24058Y1664825D01*
X24142Y1665367D01*
X24267Y1665658D01*
X24475Y1665950D01*
X24767Y1666158D01*
X25058Y1666200D01*
X25350Y1666117D01*
X25558Y1665908D01*
G01X12900Y1653100D02*
Y1661100D01*
X30500D01*
Y1653100D01*
X12900D01*
G01X4017Y1719500D02*
Y1722000D01*
X5058D01*
X5392Y1721875D01*
X5600Y1721708D01*
X5683Y1721375D01*
X5600Y1721042D01*
X5350Y1720833D01*
X5058Y1720708D01*
X4017D01*
G01X5058D02*
X5683Y1719500D01*
G01X7950D02*
Y1722000D01*
X7450Y1721500D01*
G01Y1719500D02*
X8450D01*
G01X10258Y1721583D02*
X10508Y1721833D01*
X10800Y1721958D01*
X11133Y1722000D01*
X11550Y1721917D01*
X11842Y1721708D01*
X11925Y1721458D01*
X11883Y1721208D01*
X11717Y1721000D01*
X10883Y1720583D01*
X10508Y1720292D01*
X10258Y1719875D01*
X10175Y1719500D01*
X11925D01*
G01X14150D02*
Y1722000D01*
X13650Y1721500D01*
G01Y1719500D02*
X14650D01*
G01X16400Y1722700D02*
Y1718700D01*
X23800D01*
G01X32000Y1720567D02*
X29500D01*
Y1721608D01*
X29625Y1721942D01*
X29792Y1722150D01*
X30125Y1722233D01*
X30458Y1722150D01*
X30667Y1721900D01*
X30792Y1721608D01*
Y1720567D01*
G01Y1721608D02*
X32000Y1722233D01*
G01X31500Y1723583D02*
X31792Y1723833D01*
X31958Y1724167D01*
X32000Y1724542D01*
X31958Y1724875D01*
X31750Y1725208D01*
X31500Y1725417D01*
X31250Y1725458D01*
X30958Y1725375D01*
X30750Y1725083D01*
X30667Y1724792D01*
Y1724417D01*
G01Y1724792D02*
X30542Y1725042D01*
X30333Y1725250D01*
X30083Y1725333D01*
X29833Y1725250D01*
X29625Y1725042D01*
X29500Y1724667D01*
X29542Y1724292D01*
X29708Y1723917D01*
G01X29917Y1726808D02*
X29667Y1727058D01*
X29542Y1727350D01*
X29500Y1727683D01*
X29583Y1728100D01*
X29792Y1728392D01*
X30042Y1728475D01*
X30292Y1728433D01*
X30500Y1728267D01*
X30917Y1727433D01*
X31208Y1727058D01*
X31625Y1726808D01*
X32000Y1726725D01*
Y1728475D01*
G01X27900Y1727100D02*
X23900D01*
Y1719700D01*
G01X17567Y1686000D02*
Y1688500D01*
X18608D01*
X18942Y1688375D01*
X19150Y1688208D01*
X19233Y1687875D01*
X19150Y1687542D01*
X18900Y1687333D01*
X18608Y1687208D01*
X17567D01*
G01X18608D02*
X19233Y1686000D01*
G01X20583Y1686500D02*
X20833Y1686208D01*
X21167Y1686042D01*
X21542Y1686000D01*
X21875Y1686042D01*
X22208Y1686250D01*
X22417Y1686500D01*
X22458Y1686750D01*
X22375Y1687042D01*
X22083Y1687250D01*
X21792Y1687333D01*
X21417D01*
G01X21792D02*
X22042Y1687458D01*
X22250Y1687667D01*
X22333Y1687917D01*
X22250Y1688167D01*
X22042Y1688375D01*
X21667Y1688500D01*
X21292Y1688458D01*
X20917Y1688292D01*
G01X24600Y1686000D02*
Y1688500D01*
X24100Y1688000D01*
G01Y1686000D02*
X25100D01*
G01X18200Y1694800D02*
Y1690800D01*
X25600D01*
G01X15000Y1709950D02*
X14958Y1709617D01*
X14792Y1709325D01*
X14542Y1709075D01*
X14250Y1708908D01*
X13917Y1708825D01*
X13583D01*
X13250Y1708908D01*
X12958Y1709075D01*
X12708Y1709325D01*
X12542Y1709617D01*
X12500Y1709950D01*
X12542Y1710283D01*
X12708Y1710575D01*
X12958Y1710825D01*
X13250Y1710992D01*
X13583Y1711075D01*
X13917D01*
X14250Y1710992D01*
X14542Y1710825D01*
X14792Y1710575D01*
X14958Y1710283D01*
X15000Y1709950D01*
G01X14333Y1710283D02*
X15000Y1710783D01*
G01Y1713050D02*
X14958Y1713342D01*
X14833Y1713675D01*
X14625Y1713883D01*
X14333Y1713967D01*
X14042Y1713883D01*
X13792Y1713633D01*
X13667Y1713258D01*
Y1712842D01*
X13583Y1712592D01*
X13375Y1712383D01*
X13083Y1712300D01*
X12792Y1712425D01*
X12583Y1712717D01*
X12500Y1713050D01*
X12583Y1713383D01*
X12792Y1713675D01*
X13083Y1713800D01*
X13375Y1713717D01*
X13583Y1713508D01*
X13667Y1713258D01*
Y1712842D01*
X13792Y1712467D01*
X14042Y1712217D01*
X14333Y1712133D01*
X14625Y1712217D01*
X14833Y1712425D01*
X14958Y1712758D01*
X15000Y1713050D01*
G01X16917Y1704118D02*
X29917D01*
G01X16917Y1718118D02*
Y1704118D01*
G01X29917Y1718118D02*
X16917D01*
G01X10500Y1694017D02*
X8000D01*
Y1695058D01*
X8125Y1695392D01*
X8292Y1695600D01*
X8625Y1695683D01*
X8958Y1695600D01*
X9167Y1695350D01*
X9292Y1695058D01*
Y1694017D01*
G01Y1695058D02*
X10500Y1695683D01*
G01Y1697950D02*
X8000D01*
X8500Y1697450D01*
G01X10500D02*
Y1698450D01*
G01X8417Y1700258D02*
X8167Y1700508D01*
X8042Y1700800D01*
X8000Y1701133D01*
X8083Y1701550D01*
X8292Y1701842D01*
X8542Y1701925D01*
X8792Y1701883D01*
X9000Y1701717D01*
X9417Y1700883D01*
X9708Y1700508D01*
X10125Y1700258D01*
X10500Y1700175D01*
Y1701925D01*
G01Y1704067D02*
X9958Y1704150D01*
X9500Y1704275D01*
X9083Y1704442D01*
X8625Y1704650D01*
X8000Y1704983D01*
Y1703317D01*
G01X12500Y1695200D02*
Y1703200D01*
X30100D01*
Y1695200D01*
X12500D01*
G01X-9701Y1754538D02*
X5099D01*
Y1761838D01*
X34799D01*
Y1733438D01*
X5099D01*
Y1740738D01*
X-9701D01*
Y1754538D01*
G01X21617Y1763700D02*
Y1766200D01*
X22658D01*
X22992Y1766075D01*
X23200Y1765908D01*
X23283Y1765575D01*
X23200Y1765242D01*
X22950Y1765033D01*
X22658Y1764908D01*
X21617D01*
G01X22658D02*
X23283Y1763700D01*
G01X25550D02*
Y1766200D01*
X25050Y1765700D01*
G01Y1763700D02*
X26050D01*
G01X28650Y1766200D02*
X28317Y1766117D01*
X28067Y1765908D01*
X27900Y1765658D01*
X27775Y1765325D01*
X27733Y1764950D01*
X27775Y1764575D01*
X27900Y1764242D01*
X28067Y1763992D01*
X28317Y1763783D01*
X28650Y1763700D01*
X28983Y1763783D01*
X29233Y1763992D01*
X29400Y1764242D01*
X29525Y1764575D01*
X29567Y1764950D01*
X29525Y1765325D01*
X29400Y1765658D01*
X29233Y1765908D01*
X28983Y1766117D01*
X28650Y1766200D01*
G01X31750D02*
X31417Y1766117D01*
X31167Y1765908D01*
X31000Y1765658D01*
X30875Y1765325D01*
X30833Y1764950D01*
X30875Y1764575D01*
X31000Y1764242D01*
X31167Y1763992D01*
X31417Y1763783D01*
X31750Y1763700D01*
X32083Y1763783D01*
X32333Y1763992D01*
X32500Y1764242D01*
X32625Y1764575D01*
X32667Y1764950D01*
X32625Y1765325D01*
X32500Y1765658D01*
X32333Y1765908D01*
X32083Y1766117D01*
X31750Y1766200D01*
G01X7867Y1773300D02*
Y1775800D01*
X8908D01*
X9242Y1775675D01*
X9450Y1775508D01*
X9533Y1775175D01*
X9450Y1774842D01*
X9200Y1774633D01*
X8908Y1774508D01*
X7867D01*
G01X8908D02*
X9533Y1773300D01*
G01X11092Y1773592D02*
X11383Y1773383D01*
X11717Y1773300D01*
X12050Y1773383D01*
X12342Y1773633D01*
X12550Y1774008D01*
X12633Y1774383D01*
Y1774842D01*
X12550Y1775217D01*
X12342Y1775550D01*
X12092Y1775717D01*
X11800Y1775800D01*
X11467Y1775717D01*
X11217Y1775550D01*
X11050Y1775300D01*
X10967Y1774967D01*
X11050Y1774675D01*
X11258Y1774383D01*
X11508Y1774217D01*
X11800Y1774175D01*
X12133Y1774258D01*
X12383Y1774467D01*
X12633Y1774842D01*
G01X13983Y1773675D02*
X14233Y1773467D01*
X14525Y1773342D01*
X14900Y1773300D01*
X15275Y1773383D01*
X15567Y1773550D01*
X15775Y1773842D01*
X15817Y1774175D01*
X15733Y1774508D01*
X15525Y1774717D01*
X15233Y1774883D01*
X14942Y1774925D01*
X14650Y1774883D01*
X14275Y1774717D01*
X14400Y1775800D01*
X15525D01*
G01X9017Y1763800D02*
Y1766300D01*
X10058D01*
X10392Y1766175D01*
X10600Y1766008D01*
X10683Y1765675D01*
X10600Y1765342D01*
X10350Y1765133D01*
X10058Y1765008D01*
X9017D01*
G01X10058D02*
X10683Y1763800D01*
G01X12950D02*
Y1766300D01*
X12450Y1765800D01*
G01Y1763800D02*
X13450D01*
G01X16050Y1766300D02*
X15717Y1766217D01*
X15467Y1766008D01*
X15300Y1765758D01*
X15175Y1765425D01*
X15133Y1765050D01*
X15175Y1764675D01*
X15300Y1764342D01*
X15467Y1764092D01*
X15717Y1763883D01*
X16050Y1763800D01*
X16383Y1763883D01*
X16633Y1764092D01*
X16800Y1764342D01*
X16925Y1764675D01*
X16967Y1765050D01*
X16925Y1765425D01*
X16800Y1765758D01*
X16633Y1766008D01*
X16383Y1766217D01*
X16050Y1766300D01*
G01X19650Y1763800D02*
Y1766300D01*
X18108Y1764508D01*
X20192D01*
G01X25300Y1767600D02*
Y1771600D01*
X17900D01*
G01X8083Y1780200D02*
Y1782700D01*
X8917D01*
X9250Y1782575D01*
X9500Y1782408D01*
X9708Y1782158D01*
X9875Y1781867D01*
X9917Y1781450D01*
X9875Y1781033D01*
X9708Y1780742D01*
X9500Y1780492D01*
X9250Y1780325D01*
X8917Y1780200D01*
X8083D01*
G01X12100D02*
Y1782700D01*
X11600Y1782200D01*
G01Y1780200D02*
X12600D01*
G01X15200D02*
Y1782700D01*
X14700Y1782200D01*
G01Y1780200D02*
X15700D01*
G01X38500Y1785000D02*
X17500D01*
G01D02*
Y1777000D01*
G01D02*
X38500D01*
G01X36100Y1772400D02*
Y1776400D01*
X28700D01*
G01X13817Y1789492D02*
X13567Y1789617D01*
X13275Y1789700D01*
X12942D01*
X12567Y1789575D01*
X12275Y1789367D01*
X12067Y1789117D01*
X11900Y1788700D01*
X11858Y1788325D01*
X11942Y1787950D01*
X12067Y1787700D01*
X12317Y1787450D01*
X12608Y1787283D01*
X12900Y1787200D01*
X13192D01*
X13483Y1787283D01*
X13733Y1787408D01*
X13942Y1787575D01*
G01X16500Y1787200D02*
Y1789700D01*
X14958Y1787908D01*
X17042D01*
G01X18183Y1787575D02*
X18433Y1787367D01*
X18725Y1787242D01*
X19100Y1787200D01*
X19475Y1787283D01*
X19767Y1787450D01*
X19975Y1787742D01*
X20017Y1788075D01*
X19933Y1788408D01*
X19725Y1788617D01*
X19433Y1788783D01*
X19142Y1788825D01*
X18850Y1788783D01*
X18475Y1788617D01*
X18600Y1789700D01*
X19725D01*
G01X25134Y1831023D02*
Y1833523D01*
G01X26884D02*
Y1831023D01*
G01Y1832273D02*
X25134D01*
G01X28192Y1831398D02*
X28442Y1831190D01*
X28734Y1831065D01*
X29109Y1831023D01*
X29484Y1831106D01*
X29776Y1831273D01*
X29984Y1831565D01*
X30026Y1831898D01*
X29942Y1832231D01*
X29734Y1832440D01*
X29442Y1832606D01*
X29151Y1832648D01*
X28859Y1832606D01*
X28484Y1832440D01*
X28609Y1833523D01*
X29734D01*
G01X48500Y80917D02*
X43500D01*
Y84083D01*
G01X45917Y82917D02*
Y80917D01*
G01X48500Y88100D02*
X43500D01*
X44500Y87100D01*
G01X48500D02*
Y89100D01*
G01X48667Y93700D02*
X48583Y93533D01*
X48417D01*
X48333Y93700D01*
X48417Y93867D01*
X48583D01*
X48667Y93700D01*
G01X46417D02*
X46333Y93533D01*
X46167D01*
X46083Y93700D01*
X46167Y93867D01*
X46333D01*
X46417Y93700D01*
G01X47500Y97467D02*
X48083Y97967D01*
X48417Y98633D01*
X48500Y99383D01*
X48417Y100050D01*
X48000Y100717D01*
X47500Y101133D01*
X47000Y101217D01*
X46417Y101050D01*
X46000Y100467D01*
X45833Y99883D01*
Y99133D01*
G01Y99883D02*
X45583Y100383D01*
X45167Y100800D01*
X44667Y100967D01*
X44167Y100800D01*
X43750Y100383D01*
X43500Y99633D01*
X43583Y98883D01*
X43917Y98133D01*
G01X48500Y102817D02*
X43500Y104900D01*
X48500Y106983D01*
G01X46750Y106233D02*
Y103567D01*
G01X48667Y109000D02*
X43500Y112000D01*
G01X48500Y116100D02*
X43500D01*
X44500Y115100D01*
G01X48500D02*
Y117100D01*
G01X47750Y119867D02*
X48167Y120367D01*
X48417Y120950D01*
X48500Y121700D01*
X48333Y122450D01*
X48000Y123033D01*
X47417Y123450D01*
X46750Y123533D01*
X46083Y123367D01*
X45667Y122950D01*
X45333Y122367D01*
X45250Y121783D01*
X45333Y121200D01*
X45667Y120450D01*
X43500Y120700D01*
Y122950D01*
G01Y125217D02*
X48500Y127300D01*
X43500Y129383D01*
G01X66200Y74700D02*
Y97700D01*
G01X105000Y74700D02*
X66200D01*
G01X95103Y58502D02*
X74103D01*
G01D02*
Y50502D01*
G01D02*
X95103D01*
G01X52617Y81800D02*
Y84300D01*
X53658D01*
X53992Y84175D01*
X54200Y84008D01*
X54283Y83675D01*
X54200Y83342D01*
X53950Y83133D01*
X53658Y83008D01*
X52617D01*
G01X53658D02*
X54283Y81800D01*
G01X56550D02*
Y84300D01*
X56050Y83800D01*
G01Y81800D02*
X57050D01*
G01X58858Y83883D02*
X59108Y84133D01*
X59400Y84258D01*
X59733Y84300D01*
X60150Y84217D01*
X60442Y84008D01*
X60525Y83758D01*
X60483Y83508D01*
X60317Y83300D01*
X59483Y82883D01*
X59108Y82592D01*
X58858Y82175D01*
X58775Y81800D01*
X60525D01*
G01X62750Y84300D02*
X62417Y84217D01*
X62167Y84008D01*
X62000Y83758D01*
X61875Y83425D01*
X61833Y83050D01*
X61875Y82675D01*
X62000Y82342D01*
X62167Y82092D01*
X62417Y81883D01*
X62750Y81800D01*
X63083Y81883D01*
X63333Y82092D01*
X63500Y82342D01*
X63625Y82675D01*
X63667Y83050D01*
X63625Y83425D01*
X63500Y83758D01*
X63333Y84008D01*
X63083Y84217D01*
X62750Y84300D01*
G01X52617Y85800D02*
Y88300D01*
X53658D01*
X53992Y88175D01*
X54200Y88008D01*
X54283Y87675D01*
X54200Y87342D01*
X53950Y87133D01*
X53658Y87008D01*
X52617D01*
G01X53658D02*
X54283Y85800D01*
G01X56550D02*
Y88300D01*
X56050Y87800D01*
G01Y85800D02*
X57050D01*
G01X59567D02*
X59650Y86342D01*
X59775Y86800D01*
X59942Y87217D01*
X60150Y87675D01*
X60483Y88300D01*
X58817D01*
G01X61958Y87883D02*
X62208Y88133D01*
X62500Y88258D01*
X62833Y88300D01*
X63250Y88217D01*
X63542Y88008D01*
X63625Y87758D01*
X63583Y87508D01*
X63417Y87300D01*
X62583Y86883D01*
X62208Y86592D01*
X61958Y86175D01*
X61875Y85800D01*
X63625D01*
G01X59000Y48567D02*
X56500D01*
Y49608D01*
X56625Y49942D01*
X56792Y50150D01*
X57125Y50233D01*
X57458Y50150D01*
X57667Y49900D01*
X57792Y49608D01*
Y48567D01*
G01Y49608D02*
X59000Y50233D01*
G01X57958Y51708D02*
X57667Y52000D01*
X57500Y52250D01*
X57417Y52583D01*
X57500Y52875D01*
X57667Y53083D01*
X57917Y53250D01*
X58208Y53292D01*
X58458Y53250D01*
X58708Y53083D01*
X58917Y52833D01*
X59000Y52542D01*
X58917Y52208D01*
X58667Y51917D01*
X58292Y51750D01*
X57875Y51708D01*
X57333Y51792D01*
X57042Y51917D01*
X56750Y52125D01*
X56542Y52417D01*
X56500Y52708D01*
X56583Y53000D01*
X56792Y53208D01*
G01X58708Y54892D02*
X58917Y55183D01*
X59000Y55517D01*
X58917Y55850D01*
X58667Y56142D01*
X58292Y56350D01*
X57917Y56433D01*
X57458D01*
X57083Y56350D01*
X56750Y56142D01*
X56583Y55892D01*
X56500Y55600D01*
X56583Y55267D01*
X56750Y55017D01*
X57000Y54850D01*
X57333Y54767D01*
X57625Y54850D01*
X57917Y55058D01*
X58083Y55308D01*
X58125Y55600D01*
X58042Y55933D01*
X57833Y56183D01*
X57458Y56433D01*
G01X65998Y51103D02*
X69998D01*
Y58503D01*
G01X59000Y66067D02*
X56500D01*
Y67108D01*
X56625Y67442D01*
X56792Y67650D01*
X57125Y67733D01*
X57458Y67650D01*
X57667Y67400D01*
X57792Y67108D01*
Y66067D01*
G01Y67108D02*
X59000Y67733D01*
G01X57958Y69208D02*
X57667Y69500D01*
X57500Y69750D01*
X57417Y70083D01*
X57500Y70375D01*
X57667Y70583D01*
X57917Y70750D01*
X58208Y70792D01*
X58458Y70750D01*
X58708Y70583D01*
X58917Y70333D01*
X59000Y70042D01*
X58917Y69708D01*
X58667Y69417D01*
X58292Y69250D01*
X57875Y69208D01*
X57333Y69292D01*
X57042Y69417D01*
X56750Y69625D01*
X56542Y69917D01*
X56500Y70208D01*
X56583Y70500D01*
X56792Y70708D01*
G01X59000Y73017D02*
X58458Y73100D01*
X58000Y73225D01*
X57583Y73392D01*
X57125Y73600D01*
X56500Y73933D01*
Y72267D01*
G01X65398Y65603D02*
X69398D01*
Y73003D01*
G01X56567Y60500D02*
Y63000D01*
X57608D01*
X57942Y62875D01*
X58150Y62708D01*
X58233Y62375D01*
X58150Y62042D01*
X57900Y61833D01*
X57608Y61708D01*
X56567D01*
G01X57608D02*
X58233Y60500D01*
G01X59708Y61542D02*
X60000Y61833D01*
X60250Y62000D01*
X60583Y62083D01*
X60875Y62000D01*
X61083Y61833D01*
X61250Y61583D01*
X61292Y61292D01*
X61250Y61042D01*
X61083Y60792D01*
X60833Y60583D01*
X60542Y60500D01*
X60208Y60583D01*
X59917Y60833D01*
X59750Y61208D01*
X59708Y61625D01*
X59792Y62167D01*
X59917Y62458D01*
X60125Y62750D01*
X60417Y62958D01*
X60708Y63000D01*
X61000Y62917D01*
X61208Y62708D01*
G01X62683Y60875D02*
X62933Y60667D01*
X63225Y60542D01*
X63600Y60500D01*
X63975Y60583D01*
X64267Y60750D01*
X64475Y61042D01*
X64517Y61375D01*
X64433Y61708D01*
X64225Y61917D01*
X63933Y62083D01*
X63642Y62125D01*
X63350Y62083D01*
X62975Y61917D01*
X63100Y63000D01*
X64225D01*
G01X72700Y61500D02*
Y65500D01*
X65300D01*
G01X61208Y50317D02*
X61083Y50067D01*
X61000Y49775D01*
Y49442D01*
X61125Y49067D01*
X61333Y48775D01*
X61583Y48567D01*
X62000Y48400D01*
X62375Y48358D01*
X62750Y48442D01*
X63000Y48567D01*
X63250Y48817D01*
X63417Y49108D01*
X63500Y49400D01*
Y49692D01*
X63417Y49983D01*
X63292Y50233D01*
X63125Y50442D01*
G01X61417Y51708D02*
X61167Y51958D01*
X61042Y52250D01*
X61000Y52583D01*
X61083Y53000D01*
X61292Y53292D01*
X61542Y53375D01*
X61792Y53333D01*
X62000Y53167D01*
X62417Y52333D01*
X62708Y51958D01*
X63125Y51708D01*
X63500Y51625D01*
Y53375D01*
G01X63208Y54892D02*
X63417Y55183D01*
X63500Y55517D01*
X63417Y55850D01*
X63167Y56142D01*
X62792Y56350D01*
X62417Y56433D01*
X61958D01*
X61583Y56350D01*
X61250Y56142D01*
X61083Y55892D01*
X61000Y55600D01*
X61083Y55267D01*
X61250Y55017D01*
X61500Y54850D01*
X61833Y54767D01*
X62125Y54850D01*
X62417Y55058D01*
X62583Y55308D01*
X62625Y55600D01*
X62542Y55933D01*
X62333Y56183D01*
X61958Y56433D01*
G01X61404Y67867D02*
X61279Y67617D01*
X61196Y67325D01*
Y66992D01*
X61321Y66617D01*
X61529Y66325D01*
X61779Y66117D01*
X62196Y65950D01*
X62571Y65908D01*
X62946Y65992D01*
X63196Y66117D01*
X63446Y66367D01*
X63613Y66658D01*
X63696Y66950D01*
Y67242D01*
X63613Y67533D01*
X63488Y67783D01*
X63321Y67992D01*
G01X61613Y69258D02*
X61363Y69508D01*
X61238Y69800D01*
X61196Y70133D01*
X61279Y70550D01*
X61488Y70842D01*
X61738Y70925D01*
X61988Y70883D01*
X62196Y70717D01*
X62613Y69883D01*
X62904Y69508D01*
X63321Y69258D01*
X63696Y69175D01*
Y70925D01*
G01Y73067D02*
X63154Y73150D01*
X62696Y73275D01*
X62279Y73442D01*
X61821Y73650D01*
X61196Y73983D01*
Y72317D01*
G01X66200Y97700D02*
X105000D01*
G01X52617Y98300D02*
Y100800D01*
X53658D01*
X53992Y100675D01*
X54200Y100508D01*
X54283Y100175D01*
X54200Y99842D01*
X53950Y99633D01*
X53658Y99508D01*
X52617D01*
G01X53658D02*
X54283Y98300D01*
G01X56550D02*
Y100800D01*
X56050Y100300D01*
G01Y98300D02*
X57050D01*
G01X59650D02*
Y100800D01*
X59150Y100300D01*
G01Y98300D02*
X60150D01*
G01X62750D02*
X63042Y98342D01*
X63375Y98467D01*
X63583Y98675D01*
X63667Y98967D01*
X63583Y99258D01*
X63333Y99508D01*
X62958Y99633D01*
X62542D01*
X62292Y99717D01*
X62083Y99925D01*
X62000Y100217D01*
X62125Y100508D01*
X62417Y100717D01*
X62750Y100800D01*
X63083Y100717D01*
X63375Y100508D01*
X63500Y100217D01*
X63417Y99925D01*
X63208Y99717D01*
X62958Y99633D01*
X62542D01*
X62167Y99508D01*
X61917Y99258D01*
X61833Y98967D01*
X61917Y98675D01*
X62125Y98467D01*
X62458Y98342D01*
X62750Y98300D01*
G01X52617Y90300D02*
Y92800D01*
X53658D01*
X53992Y92675D01*
X54200Y92508D01*
X54283Y92175D01*
X54200Y91842D01*
X53950Y91633D01*
X53658Y91508D01*
X52617D01*
G01X53658D02*
X54283Y90300D01*
G01X56550D02*
Y92800D01*
X56050Y92300D01*
G01Y90300D02*
X57050D01*
G01X59650D02*
Y92800D01*
X59150Y92300D01*
G01Y90300D02*
X60150D01*
G01X61958Y91342D02*
X62250Y91633D01*
X62500Y91800D01*
X62833Y91883D01*
X63125Y91800D01*
X63333Y91633D01*
X63500Y91383D01*
X63542Y91092D01*
X63500Y90842D01*
X63333Y90592D01*
X63083Y90383D01*
X62792Y90300D01*
X62458Y90383D01*
X62167Y90633D01*
X62000Y91008D01*
X61958Y91425D01*
X62042Y91967D01*
X62167Y92258D01*
X62375Y92550D01*
X62667Y92758D01*
X62958Y92800D01*
X63250Y92717D01*
X63458Y92508D01*
G01X52617Y106300D02*
Y108800D01*
X53658D01*
X53992Y108675D01*
X54200Y108508D01*
X54283Y108175D01*
X54200Y107842D01*
X53950Y107633D01*
X53658Y107508D01*
X52617D01*
G01X53658D02*
X54283Y106300D01*
G01X56550D02*
Y108800D01*
X56050Y108300D01*
G01Y106300D02*
X57050D01*
G01X59650D02*
Y108800D01*
X59150Y108300D01*
G01Y106300D02*
X60150D01*
G01X63250D02*
Y108800D01*
X61708Y107008D01*
X63792D01*
G01X52617Y132300D02*
Y134800D01*
X53658D01*
X53992Y134675D01*
X54200Y134508D01*
X54283Y134175D01*
X54200Y133842D01*
X53950Y133633D01*
X53658Y133508D01*
X52617D01*
G01X53658D02*
X54283Y132300D01*
G01X56550D02*
Y134800D01*
X56050Y134300D01*
G01Y132300D02*
X57050D01*
G01X59567D02*
X59650Y132842D01*
X59775Y133300D01*
X59942Y133717D01*
X60150Y134175D01*
X60483Y134800D01*
X58817D01*
G01X61833Y132675D02*
X62083Y132467D01*
X62375Y132342D01*
X62750Y132300D01*
X63125Y132383D01*
X63417Y132550D01*
X63625Y132842D01*
X63667Y133175D01*
X63583Y133508D01*
X63375Y133717D01*
X63083Y133883D01*
X62792Y133925D01*
X62500Y133883D01*
X62125Y133717D01*
X62250Y134800D01*
X63375D01*
G01X52617Y110300D02*
Y112800D01*
X53658D01*
X53992Y112675D01*
X54200Y112508D01*
X54283Y112175D01*
X54200Y111842D01*
X53950Y111633D01*
X53658Y111508D01*
X52617D01*
G01X53658D02*
X54283Y110300D01*
G01X56550D02*
Y112800D01*
X56050Y112300D01*
G01Y110300D02*
X57050D01*
G01X59567D02*
X59650Y110842D01*
X59775Y111300D01*
X59942Y111717D01*
X60150Y112175D01*
X60483Y112800D01*
X58817D01*
G01X63250Y110300D02*
Y112800D01*
X61708Y111008D01*
X63792D01*
G01X52617Y94300D02*
Y96800D01*
X53658D01*
X53992Y96675D01*
X54200Y96508D01*
X54283Y96175D01*
X54200Y95842D01*
X53950Y95633D01*
X53658Y95508D01*
X52617D01*
G01X53658D02*
X54283Y94300D01*
G01X56550D02*
Y96800D01*
X56050Y96300D01*
G01Y94300D02*
X57050D01*
G01X59567D02*
X59650Y94842D01*
X59775Y95300D01*
X59942Y95717D01*
X60150Y96175D01*
X60483Y96800D01*
X58817D01*
G01X61833Y94800D02*
X62083Y94508D01*
X62417Y94342D01*
X62792Y94300D01*
X63125Y94342D01*
X63458Y94550D01*
X63667Y94800D01*
X63708Y95050D01*
X63625Y95342D01*
X63333Y95550D01*
X63042Y95633D01*
X62667D01*
G01X63042D02*
X63292Y95758D01*
X63500Y95967D01*
X63583Y96217D01*
X63500Y96467D01*
X63292Y96675D01*
X62917Y96800D01*
X62542Y96758D01*
X62167Y96592D01*
G01X52517Y102500D02*
Y105000D01*
X53558D01*
X53892Y104875D01*
X54100Y104708D01*
X54183Y104375D01*
X54100Y104042D01*
X53850Y103833D01*
X53558Y103708D01*
X52517D01*
G01X53558D02*
X54183Y102500D01*
G01X56450D02*
Y105000D01*
X55950Y104500D01*
G01Y102500D02*
X56950D01*
G01X59467D02*
X59550Y103042D01*
X59675Y103500D01*
X59842Y103917D01*
X60050Y104375D01*
X60383Y105000D01*
X58717D01*
G01X62650Y102500D02*
Y105000D01*
X62150Y104500D01*
G01Y102500D02*
X63150D01*
G01X61100Y118317D02*
X58600D01*
Y119358D01*
X58725Y119692D01*
X58892Y119900D01*
X59225Y119983D01*
X59558Y119900D01*
X59767Y119650D01*
X59892Y119358D01*
Y118317D01*
G01Y119358D02*
X61100Y119983D01*
G01Y122250D02*
X58600D01*
X59100Y121750D01*
G01X61100D02*
Y122750D01*
G01Y125350D02*
X61058Y125642D01*
X60933Y125975D01*
X60725Y126183D01*
X60433Y126267D01*
X60142Y126183D01*
X59892Y125933D01*
X59767Y125558D01*
Y125142D01*
X59683Y124892D01*
X59475Y124683D01*
X59183Y124600D01*
X58892Y124725D01*
X58683Y125017D01*
X58600Y125350D01*
X58683Y125683D01*
X58892Y125975D01*
X59183Y126100D01*
X59475Y126017D01*
X59683Y125808D01*
X59767Y125558D01*
Y125142D01*
X59892Y124767D01*
X60142Y124517D01*
X60433Y124433D01*
X60725Y124517D01*
X60933Y124725D01*
X61058Y125058D01*
X61100Y125350D01*
G01Y128950D02*
X58600D01*
X60392Y127408D01*
Y129492D01*
G01X57100Y118317D02*
X54600D01*
Y119358D01*
X54725Y119692D01*
X54892Y119900D01*
X55225Y119983D01*
X55558Y119900D01*
X55767Y119650D01*
X55892Y119358D01*
Y118317D01*
G01Y119358D02*
X57100Y119983D01*
G01Y122250D02*
X54600D01*
X55100Y121750D01*
G01X57100D02*
Y122750D01*
G01Y125350D02*
X57058Y125642D01*
X56933Y125975D01*
X56725Y126183D01*
X56433Y126267D01*
X56142Y126183D01*
X55892Y125933D01*
X55767Y125558D01*
Y125142D01*
X55683Y124892D01*
X55475Y124683D01*
X55183Y124600D01*
X54892Y124725D01*
X54683Y125017D01*
X54600Y125350D01*
X54683Y125683D01*
X54892Y125975D01*
X55183Y126100D01*
X55475Y126017D01*
X55683Y125808D01*
X55767Y125558D01*
Y125142D01*
X55892Y124767D01*
X56142Y124517D01*
X56433Y124433D01*
X56725Y124517D01*
X56933Y124725D01*
X57058Y125058D01*
X57100Y125350D01*
G01X56058Y127658D02*
X55767Y127950D01*
X55600Y128200D01*
X55517Y128533D01*
X55600Y128825D01*
X55767Y129033D01*
X56017Y129200D01*
X56308Y129242D01*
X56558Y129200D01*
X56808Y129033D01*
X57017Y128783D01*
X57100Y128492D01*
X57017Y128158D01*
X56767Y127867D01*
X56392Y127700D01*
X55975Y127658D01*
X55433Y127742D01*
X55142Y127867D01*
X54850Y128075D01*
X54642Y128367D01*
X54600Y128658D01*
X54683Y128950D01*
X54892Y129158D01*
G01X52617Y114300D02*
Y116800D01*
X53658D01*
X53992Y116675D01*
X54200Y116508D01*
X54283Y116175D01*
X54200Y115842D01*
X53950Y115633D01*
X53658Y115508D01*
X52617D01*
G01X53658D02*
X54283Y114300D01*
G01X56550D02*
Y116800D01*
X56050Y116300D01*
G01Y114300D02*
X57050D01*
G01X59650D02*
X59942Y114342D01*
X60275Y114467D01*
X60483Y114675D01*
X60567Y114967D01*
X60483Y115258D01*
X60233Y115508D01*
X59858Y115633D01*
X59442D01*
X59192Y115717D01*
X58983Y115925D01*
X58900Y116217D01*
X59025Y116508D01*
X59317Y116717D01*
X59650Y116800D01*
X59983Y116717D01*
X60275Y116508D01*
X60400Y116217D01*
X60317Y115925D01*
X60108Y115717D01*
X59858Y115633D01*
X59442D01*
X59067Y115508D01*
X58817Y115258D01*
X58733Y114967D01*
X58817Y114675D01*
X59025Y114467D01*
X59358Y114342D01*
X59650Y114300D01*
G01X61833Y114675D02*
X62083Y114467D01*
X62375Y114342D01*
X62750Y114300D01*
X63125Y114383D01*
X63417Y114550D01*
X63625Y114842D01*
X63667Y115175D01*
X63583Y115508D01*
X63375Y115717D01*
X63083Y115883D01*
X62792Y115925D01*
X62500Y115883D01*
X62125Y115717D01*
X62250Y116800D01*
X63375D01*
G01X66009Y340409D02*
X95409D01*
Y311909D01*
X125409D01*
Y136909D01*
X95409D01*
Y108409D01*
X66009D01*
Y340409D01*
G01X72800Y99000D02*
X90400D01*
G01X72800Y107000D02*
Y99000D01*
G01X90400Y107000D02*
X72800D01*
G01X57900Y140717D02*
X55400D01*
Y141758D01*
X55525Y142092D01*
X55692Y142300D01*
X56025Y142383D01*
X56358Y142300D01*
X56567Y142050D01*
X56692Y141758D01*
Y140717D01*
G01Y141758D02*
X57900Y142383D01*
G01X57400Y143733D02*
X57692Y143983D01*
X57858Y144317D01*
X57900Y144692D01*
X57858Y145025D01*
X57650Y145358D01*
X57400Y145567D01*
X57150Y145608D01*
X56858Y145525D01*
X56650Y145233D01*
X56567Y144942D01*
Y144567D01*
G01Y144942D02*
X56442Y145192D01*
X56233Y145400D01*
X55983Y145483D01*
X55733Y145400D01*
X55525Y145192D01*
X55400Y144817D01*
X55442Y144442D01*
X55608Y144067D01*
G01X56858Y146958D02*
X56567Y147250D01*
X56400Y147500D01*
X56317Y147833D01*
X56400Y148125D01*
X56567Y148333D01*
X56817Y148500D01*
X57108Y148542D01*
X57358Y148500D01*
X57608Y148333D01*
X57817Y148083D01*
X57900Y147792D01*
X57817Y147458D01*
X57567Y147167D01*
X57192Y147000D01*
X56775Y146958D01*
X56233Y147042D01*
X55942Y147167D01*
X55650Y147375D01*
X55442Y147667D01*
X55400Y147958D01*
X55483Y148250D01*
X55692Y148458D01*
G01X55400Y150850D02*
X55483Y150517D01*
X55692Y150267D01*
X55942Y150100D01*
X56275Y149975D01*
X56650Y149933D01*
X57025Y149975D01*
X57358Y150100D01*
X57608Y150267D01*
X57817Y150517D01*
X57900Y150850D01*
X57817Y151183D01*
X57608Y151433D01*
X57358Y151600D01*
X57025Y151725D01*
X56650Y151767D01*
X56275Y151725D01*
X55942Y151600D01*
X55692Y151433D01*
X55483Y151183D01*
X55400Y150850D01*
G01X54900Y157300D02*
Y153300D01*
X62300D01*
G01Y169300D02*
Y173300D01*
X54900D01*
G01Y165300D02*
Y161300D01*
X62300D01*
G01X54900Y181300D02*
Y177300D01*
X62300D01*
G01X61900Y140717D02*
X59400D01*
Y141758D01*
X59525Y142092D01*
X59692Y142300D01*
X60025Y142383D01*
X60358Y142300D01*
X60567Y142050D01*
X60692Y141758D01*
Y140717D01*
G01Y141758D02*
X61900Y142383D01*
G01X61400Y143733D02*
X61692Y143983D01*
X61858Y144317D01*
X61900Y144692D01*
X61858Y145025D01*
X61650Y145358D01*
X61400Y145567D01*
X61150Y145608D01*
X60858Y145525D01*
X60650Y145233D01*
X60567Y144942D01*
Y144567D01*
G01Y144942D02*
X60442Y145192D01*
X60233Y145400D01*
X59983Y145483D01*
X59733Y145400D01*
X59525Y145192D01*
X59400Y144817D01*
X59442Y144442D01*
X59608Y144067D01*
G01X61525Y146833D02*
X61733Y147083D01*
X61858Y147375D01*
X61900Y147750D01*
X61817Y148125D01*
X61650Y148417D01*
X61358Y148625D01*
X61025Y148667D01*
X60692Y148583D01*
X60483Y148375D01*
X60317Y148083D01*
X60275Y147792D01*
X60317Y147500D01*
X60483Y147125D01*
X59400Y147250D01*
Y148375D01*
G01X61900Y150767D02*
X61358Y150850D01*
X60900Y150975D01*
X60483Y151142D01*
X60025Y151350D01*
X59400Y151683D01*
Y150017D01*
G01X62300Y181300D02*
Y185300D01*
X54900D01*
G01X62300Y165300D02*
Y169300D01*
X54900D01*
G01Y161300D02*
Y157300D01*
X62300D01*
G01X54900Y177300D02*
Y173300D01*
X62300D01*
G01X58600Y189600D02*
X62600D01*
Y197000D01*
G01X58600D02*
X54600D01*
Y189600D01*
G01X62300Y185300D02*
Y189300D01*
X54900D01*
G01X59400Y213300D02*
X55400D01*
Y205900D01*
G01X52517Y229500D02*
Y232000D01*
X53558D01*
X53892Y231875D01*
X54100Y231708D01*
X54183Y231375D01*
X54100Y231042D01*
X53850Y230833D01*
X53558Y230708D01*
X52517D01*
G01X53558D02*
X54183Y229500D01*
G01X55533Y230000D02*
X55783Y229708D01*
X56117Y229542D01*
X56492Y229500D01*
X56825Y229542D01*
X57158Y229750D01*
X57367Y230000D01*
X57408Y230250D01*
X57325Y230542D01*
X57033Y230750D01*
X56742Y230833D01*
X56367D01*
G01X56742D02*
X56992Y230958D01*
X57200Y231167D01*
X57283Y231417D01*
X57200Y231667D01*
X56992Y231875D01*
X56617Y232000D01*
X56242Y231958D01*
X55867Y231792D01*
G01X58758Y230542D02*
X59050Y230833D01*
X59300Y231000D01*
X59633Y231083D01*
X59925Y231000D01*
X60133Y230833D01*
X60300Y230583D01*
X60342Y230292D01*
X60300Y230042D01*
X60133Y229792D01*
X59883Y229583D01*
X59592Y229500D01*
X59258Y229583D01*
X58967Y229833D01*
X58800Y230208D01*
X58758Y230625D01*
X58842Y231167D01*
X58967Y231458D01*
X59175Y231750D01*
X59467Y231958D01*
X59758Y232000D01*
X60050Y231917D01*
X60258Y231708D01*
G01X62650Y229500D02*
Y232000D01*
X62150Y231500D01*
G01Y229500D02*
X63150D01*
G01X63200Y219000D02*
Y223000D01*
X55800D01*
G01X46500Y222017D02*
X44000D01*
Y223058D01*
X44125Y223392D01*
X44292Y223600D01*
X44625Y223683D01*
X44958Y223600D01*
X45167Y223350D01*
X45292Y223058D01*
Y222017D01*
G01Y223058D02*
X46500Y223683D01*
G01X46000Y225033D02*
X46292Y225283D01*
X46458Y225617D01*
X46500Y225992D01*
X46458Y226325D01*
X46250Y226658D01*
X46000Y226867D01*
X45750Y226908D01*
X45458Y226825D01*
X45250Y226533D01*
X45167Y226242D01*
Y225867D01*
G01Y226242D02*
X45042Y226492D01*
X44833Y226700D01*
X44583Y226783D01*
X44333Y226700D01*
X44125Y226492D01*
X44000Y226117D01*
X44042Y225742D01*
X44208Y225367D01*
G01X45458Y228258D02*
X45167Y228550D01*
X45000Y228800D01*
X44917Y229133D01*
X45000Y229425D01*
X45167Y229633D01*
X45417Y229800D01*
X45708Y229842D01*
X45958Y229800D01*
X46208Y229633D01*
X46417Y229383D01*
X46500Y229092D01*
X46417Y228758D01*
X46167Y228467D01*
X45792Y228300D01*
X45375Y228258D01*
X44833Y228342D01*
X44542Y228467D01*
X44250Y228675D01*
X44042Y228967D01*
X44000Y229258D01*
X44083Y229550D01*
X44292Y229758D01*
G01X44417Y231358D02*
X44167Y231608D01*
X44042Y231900D01*
X44000Y232233D01*
X44083Y232650D01*
X44292Y232942D01*
X44542Y233025D01*
X44792Y232983D01*
X45000Y232817D01*
X45417Y231983D01*
X45708Y231608D01*
X46125Y231358D01*
X46500Y231275D01*
Y233025D01*
G01X58900Y242000D02*
X54900D01*
Y234600D01*
G01X36708Y234817D02*
X36583Y234567D01*
X36500Y234275D01*
Y233942D01*
X36625Y233567D01*
X36833Y233275D01*
X37083Y233067D01*
X37500Y232900D01*
X37875Y232858D01*
X38250Y232942D01*
X38500Y233067D01*
X38750Y233317D01*
X38917Y233608D01*
X39000Y233900D01*
Y234192D01*
X38917Y234483D01*
X38792Y234733D01*
X38625Y234942D01*
G01X38500Y236083D02*
X38792Y236333D01*
X38958Y236667D01*
X39000Y237042D01*
X38958Y237375D01*
X38750Y237708D01*
X38500Y237917D01*
X38250Y237958D01*
X37958Y237875D01*
X37750Y237583D01*
X37667Y237292D01*
Y236917D01*
G01Y237292D02*
X37542Y237542D01*
X37333Y237750D01*
X37083Y237833D01*
X36833Y237750D01*
X36625Y237542D01*
X36500Y237167D01*
X36542Y236792D01*
X36708Y236417D01*
G01X36917Y239308D02*
X36667Y239558D01*
X36542Y239850D01*
X36500Y240183D01*
X36583Y240600D01*
X36792Y240892D01*
X37042Y240975D01*
X37292Y240933D01*
X37500Y240767D01*
X37917Y239933D01*
X38208Y239558D01*
X38625Y239308D01*
X39000Y239225D01*
Y240975D01*
G01X40708Y235317D02*
X40583Y235067D01*
X40500Y234775D01*
Y234442D01*
X40625Y234067D01*
X40833Y233775D01*
X41083Y233567D01*
X41500Y233400D01*
X41875Y233358D01*
X42250Y233442D01*
X42500Y233567D01*
X42750Y233817D01*
X42917Y234108D01*
X43000Y234400D01*
Y234692D01*
X42917Y234983D01*
X42792Y235233D01*
X42625Y235442D01*
G01X42500Y236583D02*
X42792Y236833D01*
X42958Y237167D01*
X43000Y237542D01*
X42958Y237875D01*
X42750Y238208D01*
X42500Y238417D01*
X42250Y238458D01*
X41958Y238375D01*
X41750Y238083D01*
X41667Y237792D01*
Y237417D01*
G01Y237792D02*
X41542Y238042D01*
X41333Y238250D01*
X41083Y238333D01*
X40833Y238250D01*
X40625Y238042D01*
X40500Y237667D01*
X40542Y237292D01*
X40708Y236917D01*
G01X43000Y240600D02*
X40500D01*
X41000Y240100D01*
G01X43000D02*
Y241100D01*
G01X43867Y202400D02*
Y204900D01*
X44908D01*
X45242Y204775D01*
X45450Y204608D01*
X45533Y204275D01*
X45450Y203942D01*
X45200Y203733D01*
X44908Y203608D01*
X43867D01*
G01X44908D02*
X45533Y202400D01*
G01X47008Y203442D02*
X47300Y203733D01*
X47550Y203900D01*
X47883Y203983D01*
X48175Y203900D01*
X48383Y203733D01*
X48550Y203483D01*
X48592Y203192D01*
X48550Y202942D01*
X48383Y202692D01*
X48133Y202483D01*
X47842Y202400D01*
X47508Y202483D01*
X47217Y202733D01*
X47050Y203108D01*
X47008Y203525D01*
X47092Y204067D01*
X47217Y204358D01*
X47425Y204650D01*
X47717Y204858D01*
X48008Y204900D01*
X48300Y204817D01*
X48508Y204608D01*
G01X49983Y202900D02*
X50233Y202608D01*
X50567Y202442D01*
X50942Y202400D01*
X51275Y202442D01*
X51608Y202650D01*
X51817Y202900D01*
X51858Y203150D01*
X51775Y203442D01*
X51483Y203650D01*
X51192Y203733D01*
X50817D01*
G01X51192D02*
X51442Y203858D01*
X51650Y204067D01*
X51733Y204317D01*
X51650Y204567D01*
X51442Y204775D01*
X51067Y204900D01*
X50692Y204858D01*
X50317Y204692D01*
G01X51900Y215400D02*
Y219400D01*
X44500D01*
G01X43867Y197900D02*
Y200400D01*
X44908D01*
X45242Y200275D01*
X45450Y200108D01*
X45533Y199775D01*
X45450Y199442D01*
X45200Y199233D01*
X44908Y199108D01*
X43867D01*
G01X44908D02*
X45533Y197900D01*
G01X47008Y198942D02*
X47300Y199233D01*
X47550Y199400D01*
X47883Y199483D01*
X48175Y199400D01*
X48383Y199233D01*
X48550Y198983D01*
X48592Y198692D01*
X48550Y198442D01*
X48383Y198192D01*
X48133Y197983D01*
X47842Y197900D01*
X47508Y197983D01*
X47217Y198233D01*
X47050Y198608D01*
X47008Y199025D01*
X47092Y199567D01*
X47217Y199858D01*
X47425Y200150D01*
X47717Y200358D01*
X48008Y200400D01*
X48300Y200317D01*
X48508Y200108D01*
G01X50108Y199983D02*
X50358Y200233D01*
X50650Y200358D01*
X50983Y200400D01*
X51400Y200317D01*
X51692Y200108D01*
X51775Y199858D01*
X51733Y199608D01*
X51567Y199400D01*
X50733Y198983D01*
X50358Y198692D01*
X50108Y198275D01*
X50025Y197900D01*
X51775D01*
G01X44500Y215400D02*
Y211400D01*
X51900D01*
G01X50500Y222017D02*
X48000D01*
Y223058D01*
X48125Y223392D01*
X48292Y223600D01*
X48625Y223683D01*
X48958Y223600D01*
X49167Y223350D01*
X49292Y223058D01*
Y222017D01*
G01Y223058D02*
X50500Y223683D01*
G01X50000Y225033D02*
X50292Y225283D01*
X50458Y225617D01*
X50500Y225992D01*
X50458Y226325D01*
X50250Y226658D01*
X50000Y226867D01*
X49750Y226908D01*
X49458Y226825D01*
X49250Y226533D01*
X49167Y226242D01*
Y225867D01*
G01Y226242D02*
X49042Y226492D01*
X48833Y226700D01*
X48583Y226783D01*
X48333Y226700D01*
X48125Y226492D01*
X48000Y226117D01*
X48042Y225742D01*
X48208Y225367D01*
G01X50125Y228133D02*
X50333Y228383D01*
X50458Y228675D01*
X50500Y229050D01*
X50417Y229425D01*
X50250Y229717D01*
X49958Y229925D01*
X49625Y229967D01*
X49292Y229883D01*
X49083Y229675D01*
X48917Y229383D01*
X48875Y229092D01*
X48917Y228800D01*
X49083Y228425D01*
X48000Y228550D01*
Y229675D01*
G01X50208Y231442D02*
X50417Y231733D01*
X50500Y232067D01*
X50417Y232400D01*
X50167Y232692D01*
X49792Y232900D01*
X49417Y232983D01*
X48958D01*
X48583Y232900D01*
X48250Y232692D01*
X48083Y232442D01*
X48000Y232150D01*
X48083Y231817D01*
X48250Y231567D01*
X48500Y231400D01*
X48833Y231317D01*
X49125Y231400D01*
X49417Y231608D01*
X49583Y231858D01*
X49625Y232150D01*
X49542Y232483D01*
X49333Y232733D01*
X48958Y232983D01*
G01X59000Y234600D02*
X63000D01*
Y242000D01*
G01X52517Y225500D02*
Y228000D01*
X53558D01*
X53892Y227875D01*
X54100Y227708D01*
X54183Y227375D01*
X54100Y227042D01*
X53850Y226833D01*
X53558Y226708D01*
X52517D01*
G01X53558D02*
X54183Y225500D01*
G01X55533Y226000D02*
X55783Y225708D01*
X56117Y225542D01*
X56492Y225500D01*
X56825Y225542D01*
X57158Y225750D01*
X57367Y226000D01*
X57408Y226250D01*
X57325Y226542D01*
X57033Y226750D01*
X56742Y226833D01*
X56367D01*
G01X56742D02*
X56992Y226958D01*
X57200Y227167D01*
X57283Y227417D01*
X57200Y227667D01*
X56992Y227875D01*
X56617Y228000D01*
X56242Y227958D01*
X55867Y227792D01*
G01X58633Y225875D02*
X58883Y225667D01*
X59175Y225542D01*
X59550Y225500D01*
X59925Y225583D01*
X60217Y225750D01*
X60425Y226042D01*
X60467Y226375D01*
X60383Y226708D01*
X60175Y226917D01*
X59883Y227083D01*
X59592Y227125D01*
X59300Y227083D01*
X58925Y226917D01*
X59050Y228000D01*
X60175D01*
G01X62650Y225500D02*
X62942Y225542D01*
X63275Y225667D01*
X63483Y225875D01*
X63567Y226167D01*
X63483Y226458D01*
X63233Y226708D01*
X62858Y226833D01*
X62442D01*
X62192Y226917D01*
X61983Y227125D01*
X61900Y227417D01*
X62025Y227708D01*
X62317Y227917D01*
X62650Y228000D01*
X62983Y227917D01*
X63275Y227708D01*
X63400Y227417D01*
X63317Y227125D01*
X63108Y226917D01*
X62858Y226833D01*
X62442D01*
X62067Y226708D01*
X61817Y226458D01*
X61733Y226167D01*
X61817Y225875D01*
X62025Y225667D01*
X62358Y225542D01*
X62650Y225500D01*
G01X55800Y219000D02*
Y215000D01*
X63200D01*
G01X59600Y205900D02*
X63600D01*
Y213300D01*
G01X54900Y201300D02*
Y197300D01*
X62300D01*
G01X48500Y265517D02*
X46000D01*
Y266558D01*
X46125Y266892D01*
X46292Y267100D01*
X46625Y267183D01*
X46958Y267100D01*
X47167Y266850D01*
X47292Y266558D01*
Y265517D01*
G01Y266558D02*
X48500Y267183D01*
G01Y269450D02*
X46000D01*
X46500Y268950D01*
G01X48500D02*
Y269950D01*
G01X48125Y271633D02*
X48333Y271883D01*
X48458Y272175D01*
X48500Y272550D01*
X48417Y272925D01*
X48250Y273217D01*
X47958Y273425D01*
X47625Y273467D01*
X47292Y273383D01*
X47083Y273175D01*
X46917Y272883D01*
X46875Y272592D01*
X46917Y272300D01*
X47083Y271925D01*
X46000Y272050D01*
Y273175D01*
G01X48500Y275650D02*
X46000D01*
X46500Y275150D01*
G01X48500D02*
Y276150D01*
G01X52300Y257900D02*
X56300D01*
Y265300D01*
G01X52500Y265517D02*
X50000D01*
Y266558D01*
X50125Y266892D01*
X50292Y267100D01*
X50625Y267183D01*
X50958Y267100D01*
X51167Y266850D01*
X51292Y266558D01*
Y265517D01*
G01Y266558D02*
X52500Y267183D01*
G01Y269450D02*
X50000D01*
X50500Y268950D01*
G01X52500D02*
Y269950D01*
G01X52125Y271633D02*
X52333Y271883D01*
X52458Y272175D01*
X52500Y272550D01*
X52417Y272925D01*
X52250Y273217D01*
X51958Y273425D01*
X51625Y273467D01*
X51292Y273383D01*
X51083Y273175D01*
X50917Y272883D01*
X50875Y272592D01*
X50917Y272300D01*
X51083Y271925D01*
X50000Y272050D01*
Y273175D01*
G01Y275650D02*
X50083Y275317D01*
X50292Y275067D01*
X50542Y274900D01*
X50875Y274775D01*
X51250Y274733D01*
X51625Y274775D01*
X51958Y274900D01*
X52208Y275067D01*
X52417Y275317D01*
X52500Y275650D01*
X52417Y275983D01*
X52208Y276233D01*
X51958Y276400D01*
X51625Y276525D01*
X51250Y276567D01*
X50875Y276525D01*
X50542Y276400D01*
X50292Y276233D01*
X50083Y275983D01*
X50000Y275650D01*
G01X56300Y257900D02*
X60300D01*
Y265300D01*
G01X57817Y272792D02*
X57567Y272917D01*
X57275Y273000D01*
X56942D01*
X56567Y272875D01*
X56275Y272667D01*
X56067Y272417D01*
X55900Y272000D01*
X55858Y271625D01*
X55942Y271250D01*
X56067Y271000D01*
X56317Y270750D01*
X56608Y270583D01*
X56900Y270500D01*
X57192D01*
X57483Y270583D01*
X57733Y270708D01*
X57942Y270875D01*
G01X59083D02*
X59333Y270667D01*
X59625Y270542D01*
X60000Y270500D01*
X60375Y270583D01*
X60667Y270750D01*
X60875Y271042D01*
X60917Y271375D01*
X60833Y271708D01*
X60625Y271917D01*
X60333Y272083D01*
X60042Y272125D01*
X59750Y272083D01*
X59375Y271917D01*
X59500Y273000D01*
X60625D01*
G01X63017Y270500D02*
X63100Y271042D01*
X63225Y271500D01*
X63392Y271917D01*
X63600Y272375D01*
X63933Y273000D01*
X62267D01*
G01X43817Y258292D02*
X43567Y258417D01*
X43275Y258500D01*
X42942D01*
X42567Y258375D01*
X42275Y258167D01*
X42067Y257917D01*
X41900Y257500D01*
X41858Y257125D01*
X41942Y256750D01*
X42067Y256500D01*
X42317Y256250D01*
X42608Y256083D01*
X42900Y256000D01*
X43192D01*
X43483Y256083D01*
X43733Y256208D01*
X43942Y256375D01*
G01X45083D02*
X45333Y256167D01*
X45625Y256042D01*
X46000Y256000D01*
X46375Y256083D01*
X46667Y256250D01*
X46875Y256542D01*
X46917Y256875D01*
X46833Y257208D01*
X46625Y257417D01*
X46333Y257583D01*
X46042Y257625D01*
X45750Y257583D01*
X45375Y257417D01*
X45500Y258500D01*
X46625D01*
G01X48308Y257042D02*
X48600Y257333D01*
X48850Y257500D01*
X49183Y257583D01*
X49475Y257500D01*
X49683Y257333D01*
X49850Y257083D01*
X49892Y256792D01*
X49850Y256542D01*
X49683Y256292D01*
X49433Y256083D01*
X49142Y256000D01*
X48808Y256083D01*
X48517Y256333D01*
X48350Y256708D01*
X48308Y257125D01*
X48392Y257667D01*
X48517Y257958D01*
X48725Y258250D01*
X49017Y258458D01*
X49308Y258500D01*
X49600Y258417D01*
X49808Y258208D01*
G01X32517Y267000D02*
Y269500D01*
X33558D01*
X33892Y269375D01*
X34100Y269208D01*
X34183Y268875D01*
X34100Y268542D01*
X33850Y268333D01*
X33558Y268208D01*
X32517D01*
G01X33558D02*
X34183Y267000D01*
G01X36450D02*
Y269500D01*
X35950Y269000D01*
G01Y267000D02*
X36950D01*
G01X39550D02*
Y269500D01*
X39050Y269000D01*
G01Y267000D02*
X40050D01*
G01X42650D02*
Y269500D01*
X42150Y269000D01*
G01Y267000D02*
X43150D01*
G01X38082Y262217D02*
Y266217D01*
X30682D01*
G01X35200Y251500D02*
X39200D01*
Y258900D01*
G01X34700D02*
X30700D01*
Y251500D01*
G01X58500Y243067D02*
X56000D01*
Y244108D01*
X56125Y244442D01*
X56292Y244650D01*
X56625Y244733D01*
X56958Y244650D01*
X57167Y244400D01*
X57292Y244108D01*
Y243067D01*
G01Y244108D02*
X58500Y244733D01*
G01X57458Y246208D02*
X57167Y246500D01*
X57000Y246750D01*
X56917Y247083D01*
X57000Y247375D01*
X57167Y247583D01*
X57417Y247750D01*
X57708Y247792D01*
X57958Y247750D01*
X58208Y247583D01*
X58417Y247333D01*
X58500Y247042D01*
X58417Y246708D01*
X58167Y246417D01*
X57792Y246250D01*
X57375Y246208D01*
X56833Y246292D01*
X56542Y246417D01*
X56250Y246625D01*
X56042Y246917D01*
X56000Y247208D01*
X56083Y247500D01*
X56292Y247708D01*
G01X58500Y250100D02*
X56000D01*
X56500Y249600D01*
G01X58500D02*
Y250600D01*
G01X60600Y243800D02*
X64600D01*
Y251200D01*
G01X55567Y274500D02*
Y277000D01*
X56608D01*
X56942Y276875D01*
X57150Y276708D01*
X57233Y276375D01*
X57150Y276042D01*
X56900Y275833D01*
X56608Y275708D01*
X55567D01*
G01X56608D02*
X57233Y274500D01*
G01X58708Y275542D02*
X59000Y275833D01*
X59250Y276000D01*
X59583Y276083D01*
X59875Y276000D01*
X60083Y275833D01*
X60250Y275583D01*
X60292Y275292D01*
X60250Y275042D01*
X60083Y274792D01*
X59833Y274583D01*
X59542Y274500D01*
X59208Y274583D01*
X58917Y274833D01*
X58750Y275208D01*
X58708Y275625D01*
X58792Y276167D01*
X58917Y276458D01*
X59125Y276750D01*
X59417Y276958D01*
X59708Y277000D01*
X60000Y276917D01*
X60208Y276708D01*
G01X62600Y277000D02*
X62267Y276917D01*
X62017Y276708D01*
X61850Y276458D01*
X61725Y276125D01*
X61683Y275750D01*
X61725Y275375D01*
X61850Y275042D01*
X62017Y274792D01*
X62267Y274583D01*
X62600Y274500D01*
X62933Y274583D01*
X63183Y274792D01*
X63350Y275042D01*
X63475Y275375D01*
X63517Y275750D01*
X63475Y276125D01*
X63350Y276458D01*
X63183Y276708D01*
X62933Y276917D01*
X62600Y277000D01*
G01X65000Y269700D02*
X61000D01*
Y262300D01*
G01X52517Y284500D02*
Y287000D01*
X53558D01*
X53892Y286875D01*
X54100Y286708D01*
X54183Y286375D01*
X54100Y286042D01*
X53850Y285833D01*
X53558Y285708D01*
X52517D01*
G01X53558D02*
X54183Y284500D01*
G01X56450D02*
Y287000D01*
X55950Y286500D01*
G01Y284500D02*
X56950D01*
G01X58758Y285542D02*
X59050Y285833D01*
X59300Y286000D01*
X59633Y286083D01*
X59925Y286000D01*
X60133Y285833D01*
X60300Y285583D01*
X60342Y285292D01*
X60300Y285042D01*
X60133Y284792D01*
X59883Y284583D01*
X59592Y284500D01*
X59258Y284583D01*
X58967Y284833D01*
X58800Y285208D01*
X58758Y285625D01*
X58842Y286167D01*
X58967Y286458D01*
X59175Y286750D01*
X59467Y286958D01*
X59758Y287000D01*
X60050Y286917D01*
X60258Y286708D01*
G01X62567Y284500D02*
X62650Y285042D01*
X62775Y285500D01*
X62942Y285917D01*
X63150Y286375D01*
X63483Y287000D01*
X61817D01*
G01X62300Y278000D02*
Y282000D01*
X54900D01*
G01X30800Y274300D02*
Y270300D01*
X38200D01*
G01X30096Y251803D02*
Y265803D01*
G01X37267Y336100D02*
Y338600D01*
X38308D01*
X38642Y338475D01*
X38850Y338308D01*
X38933Y337975D01*
X38850Y337642D01*
X38600Y337433D01*
X38308Y337308D01*
X37267D01*
G01X38308D02*
X38933Y336100D01*
G01X40283Y336600D02*
X40533Y336308D01*
X40867Y336142D01*
X41242Y336100D01*
X41575Y336142D01*
X41908Y336350D01*
X42117Y336600D01*
X42158Y336850D01*
X42075Y337142D01*
X41783Y337350D01*
X41492Y337433D01*
X41117D01*
G01X41492D02*
X41742Y337558D01*
X41950Y337767D01*
X42033Y338017D01*
X41950Y338267D01*
X41742Y338475D01*
X41367Y338600D01*
X40992Y338558D01*
X40617Y338392D01*
G01X44300Y338600D02*
X43967Y338517D01*
X43717Y338308D01*
X43550Y338058D01*
X43425Y337725D01*
X43383Y337350D01*
X43425Y336975D01*
X43550Y336642D01*
X43717Y336392D01*
X43967Y336183D01*
X44300Y336100D01*
X44633Y336183D01*
X44883Y336392D01*
X45050Y336642D01*
X45175Y336975D01*
X45217Y337350D01*
X45175Y337725D01*
X45050Y338058D01*
X44883Y338308D01*
X44633Y338517D01*
X44300Y338600D01*
G01X41200Y349200D02*
X37200D01*
Y341800D01*
G01X40000Y307450D02*
X39958Y307117D01*
X39792Y306825D01*
X39542Y306575D01*
X39250Y306408D01*
X38917Y306325D01*
X38583D01*
X38250Y306408D01*
X37958Y306575D01*
X37708Y306825D01*
X37542Y307117D01*
X37500Y307450D01*
X37542Y307783D01*
X37708Y308075D01*
X37958Y308325D01*
X38250Y308492D01*
X38583Y308575D01*
X38917D01*
X39250Y308492D01*
X39542Y308325D01*
X39792Y308075D01*
X39958Y307783D01*
X40000Y307450D01*
G01X39333Y307783D02*
X40000Y308283D01*
G01Y311050D02*
X37500D01*
X39292Y309508D01*
Y311592D01*
G01X35300Y302100D02*
Y316100D01*
G01X80317Y345292D02*
X80067Y345417D01*
X79775Y345500D01*
X79442D01*
X79067Y345375D01*
X78775Y345167D01*
X78567Y344917D01*
X78400Y344500D01*
X78358Y344125D01*
X78442Y343750D01*
X78567Y343500D01*
X78817Y343250D01*
X79108Y343083D01*
X79400Y343000D01*
X79692D01*
X79983Y343083D01*
X80233Y343208D01*
X80442Y343375D01*
G01X81542Y343000D02*
Y345500D01*
X83458Y343000D01*
Y345500D01*
G01X84892Y343292D02*
X85183Y343083D01*
X85517Y343000D01*
X85850Y343083D01*
X86142Y343333D01*
X86350Y343708D01*
X86433Y344083D01*
Y344542D01*
X86350Y344917D01*
X86142Y345250D01*
X85892Y345417D01*
X85600Y345500D01*
X85267Y345417D01*
X85017Y345250D01*
X84850Y345000D01*
X84767Y344667D01*
X84850Y344375D01*
X85058Y344083D01*
X85308Y343917D01*
X85600Y343875D01*
X85933Y343958D01*
X86183Y344167D01*
X86433Y344542D01*
G01X37500Y352017D02*
X40000D01*
Y353683D01*
G01Y356783D02*
Y355117D01*
X37500D01*
Y356783D01*
G01X38708Y356117D02*
Y355117D01*
G01X40000Y358133D02*
X37500D01*
Y358967D01*
X37625Y359300D01*
X37792Y359550D01*
X38042Y359758D01*
X38333Y359925D01*
X38750Y359967D01*
X39167Y359925D01*
X39458Y359758D01*
X39708Y359550D01*
X39875Y359300D01*
X40000Y358967D01*
Y358133D01*
G01X39625Y361233D02*
X39833Y361483D01*
X39958Y361775D01*
X40000Y362150D01*
X39917Y362525D01*
X39750Y362817D01*
X39458Y363025D01*
X39125Y363067D01*
X38792Y362983D01*
X38583Y362775D01*
X38417Y362483D01*
X38375Y362192D01*
X38417Y361900D01*
X38583Y361525D01*
X37500Y361650D01*
Y362775D01*
G01X74300Y389500D02*
X85500D01*
G01X74300Y407500D02*
Y389500D01*
G01X33400Y381500D02*
Y379000D01*
G01X32442Y381500D02*
X34358D01*
G01X37417Y381292D02*
X37167Y381417D01*
X36875Y381500D01*
X36542D01*
X36167Y381375D01*
X35875Y381167D01*
X35667Y380917D01*
X35500Y380500D01*
X35458Y380125D01*
X35542Y379750D01*
X35667Y379500D01*
X35917Y379250D01*
X36208Y379083D01*
X36500Y379000D01*
X36792D01*
X37083Y379083D01*
X37333Y379208D01*
X37542Y379375D01*
G01X39600Y379000D02*
Y381500D01*
X39100Y381000D01*
G01Y379000D02*
X40100D01*
G01X54500Y388800D02*
Y406800D01*
G01X43300Y388800D02*
X54500D01*
G01X71983Y376500D02*
Y379000D01*
X72817D01*
X73150Y378875D01*
X73400Y378708D01*
X73608Y378458D01*
X73775Y378167D01*
X73817Y377750D01*
X73775Y377333D01*
X73608Y377042D01*
X73400Y376792D01*
X73150Y376625D01*
X72817Y376500D01*
X71983D01*
G01X76000D02*
Y379000D01*
X75500Y378500D01*
G01Y376500D02*
X76500D01*
G01X78183Y376875D02*
X78433Y376667D01*
X78725Y376542D01*
X79100Y376500D01*
X79475Y376583D01*
X79767Y376750D01*
X79975Y377042D01*
X80017Y377375D01*
X79933Y377708D01*
X79725Y377917D01*
X79433Y378083D01*
X79142Y378125D01*
X78850Y378083D01*
X78475Y377917D01*
X78600Y379000D01*
X79725D01*
G01X64400Y374400D02*
X104600D01*
G01X64400Y349400D02*
Y374400D01*
G01X104600Y349400D02*
X64400D01*
G01X49467Y435000D02*
Y437500D01*
X50467D01*
X50800Y437375D01*
X51050Y437083D01*
X51133Y436750D01*
X51050Y436417D01*
X50842Y436167D01*
X50467Y436042D01*
X49467D01*
G01X52567Y435000D02*
Y437500D01*
X53608D01*
X53942Y437375D01*
X54150Y437208D01*
X54233Y436875D01*
X54150Y436542D01*
X53900Y436333D01*
X53608Y436208D01*
X52567D01*
G01X53608D02*
X54233Y435000D01*
G01X56500D02*
Y437500D01*
X56000Y437000D01*
G01Y435000D02*
X57000D01*
G01X59600D02*
Y437500D01*
X59100Y437000D01*
G01Y435000D02*
X60100D01*
G01X62700D02*
X62992Y435042D01*
X63325Y435167D01*
X63533Y435375D01*
X63617Y435667D01*
X63533Y435958D01*
X63283Y436208D01*
X62908Y436333D01*
X62492D01*
X62242Y436417D01*
X62033Y436625D01*
X61950Y436917D01*
X62075Y437208D01*
X62367Y437417D01*
X62700Y437500D01*
X63033Y437417D01*
X63325Y437208D01*
X63450Y436917D01*
X63367Y436625D01*
X63158Y436417D01*
X62908Y436333D01*
X62492D01*
X62117Y436208D01*
X61867Y435958D01*
X61783Y435667D01*
X61867Y435375D01*
X62075Y435167D01*
X62408Y435042D01*
X62700Y435000D01*
G01X68800Y433300D02*
Y429300D01*
X76200D01*
G01X53017Y443000D02*
Y445500D01*
X54017D01*
X54350Y445375D01*
X54600Y445083D01*
X54683Y444750D01*
X54600Y444417D01*
X54392Y444167D01*
X54017Y444042D01*
X53017D01*
G01X56950Y443000D02*
X56617Y443042D01*
X56325Y443208D01*
X56075Y443458D01*
X55908Y443750D01*
X55825Y444083D01*
Y444417D01*
X55908Y444750D01*
X56075Y445042D01*
X56325Y445292D01*
X56617Y445458D01*
X56950Y445500D01*
X57283Y445458D01*
X57575Y445292D01*
X57825Y445042D01*
X57992Y444750D01*
X58075Y444417D01*
Y444083D01*
X57992Y443750D01*
X57825Y443458D01*
X57575Y443208D01*
X57283Y443042D01*
X56950Y443000D01*
G01X57283Y443667D02*
X57783Y443000D01*
G01X60050D02*
Y445500D01*
X59550Y445000D01*
G01Y443000D02*
X60550D01*
G01X63150D02*
Y445500D01*
X62650Y445000D01*
G01Y443000D02*
X63650D01*
G01X65650Y435800D02*
X87350D01*
G01X65650Y465800D02*
Y435800D01*
G01X85500Y407500D02*
X74300D01*
G01Y410000D02*
X85500D01*
G01X74300Y428000D02*
Y410000D01*
G01X85500Y428000D02*
X74300D01*
G01X32700Y436800D02*
Y434300D01*
G01X31742Y436800D02*
X33658D01*
G01X36717Y436592D02*
X36467Y436717D01*
X36175Y436800D01*
X35842D01*
X35467Y436675D01*
X35175Y436467D01*
X34967Y436217D01*
X34800Y435800D01*
X34758Y435425D01*
X34842Y435050D01*
X34967Y434800D01*
X35217Y434550D01*
X35508Y434383D01*
X35800Y434300D01*
X36092D01*
X36383Y434383D01*
X36633Y434508D01*
X36842Y434675D01*
G01X38108Y436383D02*
X38358Y436633D01*
X38650Y436758D01*
X38983Y436800D01*
X39400Y436717D01*
X39692Y436508D01*
X39775Y436258D01*
X39733Y436008D01*
X39567Y435800D01*
X38733Y435383D01*
X38358Y435092D01*
X38108Y434675D01*
X38025Y434300D01*
X39775D01*
G01X54500Y427300D02*
X43300D01*
G01X54500Y409300D02*
Y427300D01*
G01X43300Y409300D02*
X54500D01*
G01Y406800D02*
X43300D01*
G01X87350Y465800D02*
X65650D01*
G01X64250Y497500D02*
X79750D01*
Y467500D01*
X64250D01*
Y497500D01*
G01X68000Y543350D02*
X70500D01*
G01X68000Y542392D02*
Y544308D01*
G01X70500Y545617D02*
X68000D01*
Y546617D01*
X68125Y546950D01*
X68417Y547200D01*
X68750Y547283D01*
X69083Y547200D01*
X69333Y546992D01*
X69458Y546617D01*
Y545617D01*
G01X68417Y548758D02*
X68167Y549008D01*
X68042Y549300D01*
X68000Y549633D01*
X68083Y550050D01*
X68292Y550342D01*
X68542Y550425D01*
X68792Y550383D01*
X69000Y550217D01*
X69417Y549383D01*
X69708Y549008D01*
X70125Y548758D01*
X70500Y548675D01*
Y550425D01*
G01X70000Y551733D02*
X70292Y551983D01*
X70458Y552317D01*
X70500Y552692D01*
X70458Y553025D01*
X70250Y553358D01*
X70000Y553567D01*
X69750Y553608D01*
X69458Y553525D01*
X69250Y553233D01*
X69167Y552942D01*
Y552567D01*
G01Y552942D02*
X69042Y553192D01*
X68833Y553400D01*
X68583Y553483D01*
X68333Y553400D01*
X68125Y553192D01*
X68000Y552817D01*
X68042Y552442D01*
X68208Y552067D01*
G01X66500Y544967D02*
X64000D01*
Y545967D01*
X64125Y546300D01*
X64417Y546550D01*
X64750Y546633D01*
X65083Y546550D01*
X65333Y546342D01*
X65458Y545967D01*
Y544967D01*
G01X66500Y548067D02*
X64000D01*
Y549108D01*
X64125Y549442D01*
X64292Y549650D01*
X64625Y549733D01*
X64958Y549650D01*
X65167Y549400D01*
X65292Y549108D01*
Y548067D01*
G01Y549108D02*
X66500Y549733D01*
G01Y552000D02*
X64000D01*
X64500Y551500D01*
G01X66500D02*
Y552500D01*
G01X64000Y555100D02*
X64083Y554767D01*
X64292Y554517D01*
X64542Y554350D01*
X64875Y554225D01*
X65250Y554183D01*
X65625Y554225D01*
X65958Y554350D01*
X66208Y554517D01*
X66417Y554767D01*
X66500Y555100D01*
X66417Y555433D01*
X66208Y555683D01*
X65958Y555850D01*
X65625Y555975D01*
X65250Y556017D01*
X64875Y555975D01*
X64542Y555850D01*
X64292Y555683D01*
X64083Y555433D01*
X64000Y555100D01*
G01X65458Y557408D02*
X65167Y557700D01*
X65000Y557950D01*
X64917Y558283D01*
X65000Y558575D01*
X65167Y558783D01*
X65417Y558950D01*
X65708Y558992D01*
X65958Y558950D01*
X66208Y558783D01*
X66417Y558533D01*
X66500Y558242D01*
X66417Y557908D01*
X66167Y557617D01*
X65792Y557450D01*
X65375Y557408D01*
X64833Y557492D01*
X64542Y557617D01*
X64250Y557825D01*
X64042Y558117D01*
X64000Y558408D01*
X64083Y558700D01*
X64292Y558908D01*
G01X69500Y524467D02*
X67000D01*
Y525467D01*
X67125Y525800D01*
X67417Y526050D01*
X67750Y526133D01*
X68083Y526050D01*
X68333Y525842D01*
X68458Y525467D01*
Y524467D01*
G01X69500Y527567D02*
X67000D01*
Y528608D01*
X67125Y528942D01*
X67292Y529150D01*
X67625Y529233D01*
X67958Y529150D01*
X68167Y528900D01*
X68292Y528608D01*
Y527567D01*
G01Y528608D02*
X69500Y529233D01*
G01Y531500D02*
X67000D01*
X67500Y531000D01*
G01X69500D02*
Y532000D01*
G01X67000Y534600D02*
X67083Y534267D01*
X67292Y534017D01*
X67542Y533850D01*
X67875Y533725D01*
X68250Y533683D01*
X68625Y533725D01*
X68958Y533850D01*
X69208Y534017D01*
X69417Y534267D01*
X69500Y534600D01*
X69417Y534933D01*
X69208Y535183D01*
X68958Y535350D01*
X68625Y535475D01*
X68250Y535517D01*
X67875Y535475D01*
X67542Y535350D01*
X67292Y535183D01*
X67083Y534933D01*
X67000Y534600D01*
G01X69500Y538200D02*
X67000D01*
X68792Y536658D01*
Y538742D01*
G01X71700Y537900D02*
X75700D01*
Y545300D01*
G01X74000Y524017D02*
X71500D01*
Y525017D01*
X71625Y525350D01*
X71917Y525600D01*
X72250Y525683D01*
X72583Y525600D01*
X72833Y525392D01*
X72958Y525017D01*
Y524017D01*
G01X74000Y527117D02*
X71500D01*
Y528158D01*
X71625Y528492D01*
X71792Y528700D01*
X72125Y528783D01*
X72458Y528700D01*
X72667Y528450D01*
X72792Y528158D01*
Y527117D01*
G01Y528158D02*
X74000Y528783D01*
G01X73708Y530342D02*
X73917Y530633D01*
X74000Y530967D01*
X73917Y531300D01*
X73667Y531592D01*
X73292Y531800D01*
X72917Y531883D01*
X72458D01*
X72083Y531800D01*
X71750Y531592D01*
X71583Y531342D01*
X71500Y531050D01*
X71583Y530717D01*
X71750Y530467D01*
X72000Y530300D01*
X72333Y530217D01*
X72625Y530300D01*
X72917Y530508D01*
X73083Y530758D01*
X73125Y531050D01*
X73042Y531383D01*
X72833Y531633D01*
X72458Y531883D01*
G01X73625Y533233D02*
X73833Y533483D01*
X73958Y533775D01*
X74000Y534150D01*
X73917Y534525D01*
X73750Y534817D01*
X73458Y535025D01*
X73125Y535067D01*
X72792Y534983D01*
X72583Y534775D01*
X72417Y534483D01*
X72375Y534192D01*
X72417Y533900D01*
X72583Y533525D01*
X71500Y533650D01*
Y534775D01*
G01X83400Y535900D02*
X79400D01*
Y528500D01*
G01X66017Y502500D02*
Y505000D01*
X67017D01*
X67350Y504875D01*
X67600Y504583D01*
X67683Y504250D01*
X67600Y503917D01*
X67392Y503667D01*
X67017Y503542D01*
X66017D01*
G01X69117Y502500D02*
Y505000D01*
X70158D01*
X70492Y504875D01*
X70700Y504708D01*
X70783Y504375D01*
X70700Y504042D01*
X70450Y503833D01*
X70158Y503708D01*
X69117D01*
G01X70158D02*
X70783Y502500D01*
G01X72258Y503542D02*
X72550Y503833D01*
X72800Y504000D01*
X73133Y504083D01*
X73425Y504000D01*
X73633Y503833D01*
X73800Y503583D01*
X73842Y503292D01*
X73800Y503042D01*
X73633Y502792D01*
X73383Y502583D01*
X73092Y502500D01*
X72758Y502583D01*
X72467Y502833D01*
X72300Y503208D01*
X72258Y503625D01*
X72342Y504167D01*
X72467Y504458D01*
X72675Y504750D01*
X72967Y504958D01*
X73258Y505000D01*
X73550Y504917D01*
X73758Y504708D01*
G01X76150Y505000D02*
X75817Y504917D01*
X75567Y504708D01*
X75400Y504458D01*
X75275Y504125D01*
X75233Y503750D01*
X75275Y503375D01*
X75400Y503042D01*
X75567Y502792D01*
X75817Y502583D01*
X76150Y502500D01*
X76483Y502583D01*
X76733Y502792D01*
X76900Y503042D01*
X77025Y503375D01*
X77067Y503750D01*
X77025Y504125D01*
X76900Y504458D01*
X76733Y504708D01*
X76483Y504917D01*
X76150Y505000D01*
G01X66967Y561200D02*
Y563700D01*
X67967D01*
X68300Y563575D01*
X68550Y563283D01*
X68633Y562950D01*
X68550Y562617D01*
X68342Y562367D01*
X67967Y562242D01*
X66967D01*
G01X69983Y563700D02*
Y561908D01*
X70150Y561533D01*
X70483Y561283D01*
X70900Y561200D01*
X71317Y561283D01*
X71650Y561533D01*
X71817Y561908D01*
Y563700D01*
G01X73208Y562242D02*
X73500Y562533D01*
X73750Y562700D01*
X74083Y562783D01*
X74375Y562700D01*
X74583Y562533D01*
X74750Y562283D01*
X74792Y561992D01*
X74750Y561742D01*
X74583Y561492D01*
X74333Y561283D01*
X74042Y561200D01*
X73708Y561283D01*
X73417Y561533D01*
X73250Y561908D01*
X73208Y562325D01*
X73292Y562867D01*
X73417Y563158D01*
X73625Y563450D01*
X73917Y563658D01*
X74208Y563700D01*
X74500Y563617D01*
X74708Y563408D01*
G01X56000Y572533D02*
X53500D01*
Y573367D01*
X53625Y573700D01*
X53792Y573950D01*
X54042Y574158D01*
X54333Y574325D01*
X54750Y574367D01*
X55167Y574325D01*
X55458Y574158D01*
X55708Y573950D01*
X55875Y573700D01*
X56000Y573367D01*
Y572533D01*
G01Y577050D02*
X53500D01*
X55292Y575508D01*
Y577592D01*
G01X54500Y580000D02*
X75500D01*
G01D02*
Y588000D01*
G01D02*
X54500D01*
G01D02*
Y580000D01*
G01X39500Y595533D02*
X37000D01*
Y596367D01*
X37125Y596700D01*
X37292Y596950D01*
X37542Y597158D01*
X37833Y597325D01*
X38250Y597367D01*
X38667Y597325D01*
X38958Y597158D01*
X39208Y596950D01*
X39375Y596700D01*
X39500Y596367D01*
Y595533D01*
G01X37417Y598758D02*
X37167Y599008D01*
X37042Y599300D01*
X37000Y599633D01*
X37083Y600050D01*
X37292Y600342D01*
X37542Y600425D01*
X37792Y600383D01*
X38000Y600217D01*
X38417Y599383D01*
X38708Y599008D01*
X39125Y598758D01*
X39500Y598675D01*
Y600425D01*
G01X62200Y597000D02*
X41200D01*
G01D02*
Y589000D01*
G01D02*
X62200D01*
G01D02*
Y597000D01*
G01X66567Y595000D02*
Y597500D01*
X67608D01*
X67942Y597375D01*
X68150Y597208D01*
X68233Y596875D01*
X68150Y596542D01*
X67900Y596333D01*
X67608Y596208D01*
X66567D01*
G01X67608D02*
X68233Y595000D01*
G01X70417D02*
X70500Y595542D01*
X70625Y596000D01*
X70792Y596417D01*
X71000Y596875D01*
X71333Y597500D01*
X69667D01*
G01X72808Y597083D02*
X73058Y597333D01*
X73350Y597458D01*
X73683Y597500D01*
X74100Y597417D01*
X74392Y597208D01*
X74475Y596958D01*
X74433Y596708D01*
X74267Y596500D01*
X73433Y596083D01*
X73058Y595792D01*
X72808Y595375D01*
X72725Y595000D01*
X74475D01*
G01X45000Y565567D02*
X42500D01*
Y566608D01*
X42625Y566942D01*
X42792Y567150D01*
X43125Y567233D01*
X43458Y567150D01*
X43667Y566900D01*
X43792Y566608D01*
Y565567D01*
G01Y566608D02*
X45000Y567233D01*
G01Y569417D02*
X44458Y569500D01*
X44000Y569625D01*
X43583Y569792D01*
X43125Y570000D01*
X42500Y570333D01*
Y568667D01*
G01Y572600D02*
X42583Y572267D01*
X42792Y572017D01*
X43042Y571850D01*
X43375Y571725D01*
X43750Y571683D01*
X44125Y571725D01*
X44458Y571850D01*
X44708Y572017D01*
X44917Y572267D01*
X45000Y572600D01*
X44917Y572933D01*
X44708Y573183D01*
X44458Y573350D01*
X44125Y573475D01*
X43750Y573517D01*
X43375Y573475D01*
X43042Y573350D01*
X42792Y573183D01*
X42583Y572933D01*
X42500Y572600D01*
G01X58500Y557017D02*
X56000D01*
Y558017D01*
X56125Y558350D01*
X56417Y558600D01*
X56750Y558683D01*
X57083Y558600D01*
X57333Y558392D01*
X57458Y558017D01*
Y557017D01*
G01X56208Y561867D02*
X56083Y561617D01*
X56000Y561325D01*
Y560992D01*
X56125Y560617D01*
X56333Y560325D01*
X56583Y560117D01*
X57000Y559950D01*
X57375Y559908D01*
X57750Y559992D01*
X58000Y560117D01*
X58250Y560367D01*
X58417Y560658D01*
X58500Y560950D01*
Y561242D01*
X58417Y561533D01*
X58292Y561783D01*
X58125Y561992D01*
G01X58208Y563342D02*
X58417Y563633D01*
X58500Y563967D01*
X58417Y564300D01*
X58167Y564592D01*
X57792Y564800D01*
X57417Y564883D01*
X56958D01*
X56583Y564800D01*
X56250Y564592D01*
X56083Y564342D01*
X56000Y564050D01*
X56083Y563717D01*
X56250Y563467D01*
X56500Y563300D01*
X56833Y563217D01*
X57125Y563300D01*
X57417Y563508D01*
X57583Y563758D01*
X57625Y564050D01*
X57542Y564383D01*
X57333Y564633D01*
X56958Y564883D01*
G01X58500Y567150D02*
X56000D01*
X56500Y566650D01*
G01X58500D02*
Y567650D01*
G01X62500Y555967D02*
X60000D01*
Y556967D01*
X60125Y557300D01*
X60417Y557550D01*
X60750Y557633D01*
X61083Y557550D01*
X61333Y557342D01*
X61458Y556967D01*
Y555967D01*
G01X62500Y559067D02*
X60000D01*
Y560108D01*
X60125Y560442D01*
X60292Y560650D01*
X60625Y560733D01*
X60958Y560650D01*
X61167Y560400D01*
X61292Y560108D01*
Y559067D01*
G01Y560108D02*
X62500Y560733D01*
G01Y563000D02*
X60000D01*
X60500Y562500D01*
G01X62500D02*
Y563500D01*
G01Y566100D02*
X60000D01*
X60500Y565600D01*
G01X62500D02*
Y566600D01*
G01Y569700D02*
X60000D01*
X61792Y568158D01*
Y570242D01*
G01X76600Y569100D02*
X80600D01*
Y576500D01*
G01X48467Y551500D02*
Y554000D01*
X49467D01*
X49800Y553875D01*
X50050Y553583D01*
X50133Y553250D01*
X50050Y552917D01*
X49842Y552667D01*
X49467Y552542D01*
X48467D01*
G01X51567Y551500D02*
Y554000D01*
X52608D01*
X52942Y553875D01*
X53150Y553708D01*
X53233Y553375D01*
X53150Y553042D01*
X52900Y552833D01*
X52608Y552708D01*
X51567D01*
G01X52608D02*
X53233Y551500D01*
G01X55500D02*
Y554000D01*
X55000Y553500D01*
G01Y551500D02*
X56000D01*
G01X58600D02*
Y554000D01*
X58100Y553500D01*
G01Y551500D02*
X59100D01*
G01X61700Y554000D02*
X61367Y553917D01*
X61117Y553708D01*
X60950Y553458D01*
X60825Y553125D01*
X60783Y552750D01*
X60825Y552375D01*
X60950Y552042D01*
X61117Y551792D01*
X61367Y551583D01*
X61700Y551500D01*
X62033Y551583D01*
X62283Y551792D01*
X62450Y552042D01*
X62575Y552375D01*
X62617Y552750D01*
X62575Y553125D01*
X62450Y553458D01*
X62283Y553708D01*
X62033Y553917D01*
X61700Y554000D01*
G01X71900Y553400D02*
X75900D01*
Y560800D01*
G01X79600Y577467D02*
X77100D01*
Y578508D01*
X77225Y578842D01*
X77392Y579050D01*
X77725Y579133D01*
X78058Y579050D01*
X78267Y578800D01*
X78392Y578508D01*
Y577467D01*
G01Y578508D02*
X79600Y579133D01*
G01Y581317D02*
X79058Y581400D01*
X78600Y581525D01*
X78183Y581692D01*
X77725Y581900D01*
X77100Y582233D01*
Y580567D01*
G01X78558Y583708D02*
X78267Y584000D01*
X78100Y584250D01*
X78017Y584583D01*
X78100Y584875D01*
X78267Y585083D01*
X78517Y585250D01*
X78808Y585292D01*
X79058Y585250D01*
X79308Y585083D01*
X79517Y584833D01*
X79600Y584542D01*
X79517Y584208D01*
X79267Y583917D01*
X78892Y583750D01*
X78475Y583708D01*
X77933Y583792D01*
X77642Y583917D01*
X77350Y584125D01*
X77142Y584417D01*
X77100Y584708D01*
X77183Y585000D01*
X77392Y585208D01*
G01X80400Y593000D02*
X76400D01*
Y585600D01*
G01X51500Y580067D02*
X49000D01*
Y581108D01*
X49125Y581442D01*
X49292Y581650D01*
X49625Y581733D01*
X49958Y581650D01*
X50167Y581400D01*
X50292Y581108D01*
Y580067D01*
G01Y581108D02*
X51500Y581733D01*
G01Y583917D02*
X50958Y584000D01*
X50500Y584125D01*
X50083Y584292D01*
X49625Y584500D01*
X49000Y584833D01*
Y583167D01*
G01X51500Y587600D02*
X49000D01*
X50792Y586058D01*
Y588142D01*
G01X51600Y578900D02*
X47600D01*
Y571500D01*
G01X46767Y564700D02*
Y567200D01*
X47808D01*
X48142Y567075D01*
X48350Y566908D01*
X48433Y566575D01*
X48350Y566242D01*
X48100Y566033D01*
X47808Y565908D01*
X46767D01*
G01X47808D02*
X48433Y564700D01*
G01X49908Y565742D02*
X50200Y566033D01*
X50450Y566200D01*
X50783Y566283D01*
X51075Y566200D01*
X51283Y566033D01*
X51450Y565783D01*
X51492Y565492D01*
X51450Y565242D01*
X51283Y564992D01*
X51033Y564783D01*
X50742Y564700D01*
X50408Y564783D01*
X50117Y565033D01*
X49950Y565408D01*
X49908Y565825D01*
X49992Y566367D01*
X50117Y566658D01*
X50325Y566950D01*
X50617Y567158D01*
X50908Y567200D01*
X51200Y567117D01*
X51408Y566908D01*
G01X53800Y564700D02*
X54092Y564742D01*
X54425Y564867D01*
X54633Y565075D01*
X54717Y565367D01*
X54633Y565658D01*
X54383Y565908D01*
X54008Y566033D01*
X53592D01*
X53342Y566117D01*
X53133Y566325D01*
X53050Y566617D01*
X53175Y566908D01*
X53467Y567117D01*
X53800Y567200D01*
X54133Y567117D01*
X54425Y566908D01*
X54550Y566617D01*
X54467Y566325D01*
X54258Y566117D01*
X54008Y566033D01*
X53592D01*
X53217Y565908D01*
X52967Y565658D01*
X52883Y565367D01*
X52967Y565075D01*
X53175Y564867D01*
X53508Y564742D01*
X53800Y564700D01*
G01X59000Y575200D02*
Y571200D01*
X66400D01*
G01X40000Y584567D02*
X37500D01*
Y585608D01*
X37625Y585942D01*
X37792Y586150D01*
X38125Y586233D01*
X38458Y586150D01*
X38667Y585900D01*
X38792Y585608D01*
Y584567D01*
G01Y585608D02*
X40000Y586233D01*
G01X38958Y587708D02*
X38667Y588000D01*
X38500Y588250D01*
X38417Y588583D01*
X38500Y588875D01*
X38667Y589083D01*
X38917Y589250D01*
X39208Y589292D01*
X39458Y589250D01*
X39708Y589083D01*
X39917Y588833D01*
X40000Y588542D01*
X39917Y588208D01*
X39667Y587917D01*
X39292Y587750D01*
X38875Y587708D01*
X38333Y587792D01*
X38042Y587917D01*
X37750Y588125D01*
X37542Y588417D01*
X37500Y588708D01*
X37583Y589000D01*
X37792Y589208D01*
G01X38958Y590808D02*
X38667Y591100D01*
X38500Y591350D01*
X38417Y591683D01*
X38500Y591975D01*
X38667Y592183D01*
X38917Y592350D01*
X39208Y592392D01*
X39458Y592350D01*
X39708Y592183D01*
X39917Y591933D01*
X40000Y591642D01*
X39917Y591308D01*
X39667Y591017D01*
X39292Y590850D01*
X38875Y590808D01*
X38333Y590892D01*
X38042Y591017D01*
X37750Y591225D01*
X37542Y591517D01*
X37500Y591808D01*
X37583Y592100D01*
X37792Y592308D01*
G01X37000Y575900D02*
X41000D01*
Y583300D01*
G01X47817Y559292D02*
X47567Y559417D01*
X47275Y559500D01*
X46942D01*
X46567Y559375D01*
X46275Y559167D01*
X46067Y558917D01*
X45900Y558500D01*
X45858Y558125D01*
X45942Y557750D01*
X46067Y557500D01*
X46317Y557250D01*
X46608Y557083D01*
X46900Y557000D01*
X47192D01*
X47483Y557083D01*
X47733Y557208D01*
X47942Y557375D01*
G01X49083Y557500D02*
X49333Y557208D01*
X49667Y557042D01*
X50042Y557000D01*
X50375Y557042D01*
X50708Y557250D01*
X50917Y557500D01*
X50958Y557750D01*
X50875Y558042D01*
X50583Y558250D01*
X50292Y558333D01*
X49917D01*
G01X50292D02*
X50542Y558458D01*
X50750Y558667D01*
X50833Y558917D01*
X50750Y559167D01*
X50542Y559375D01*
X50167Y559500D01*
X49792Y559458D01*
X49417Y559292D01*
G01X53100Y559500D02*
X52767Y559417D01*
X52517Y559208D01*
X52350Y558958D01*
X52225Y558625D01*
X52183Y558250D01*
X52225Y557875D01*
X52350Y557542D01*
X52517Y557292D01*
X52767Y557083D01*
X53100Y557000D01*
X53433Y557083D01*
X53683Y557292D01*
X53850Y557542D01*
X53975Y557875D01*
X54017Y558250D01*
X53975Y558625D01*
X53850Y558958D01*
X53683Y559208D01*
X53433Y559417D01*
X53100Y559500D01*
G01X33208Y589817D02*
X33083Y589567D01*
X33000Y589275D01*
Y588942D01*
X33125Y588567D01*
X33333Y588275D01*
X33583Y588067D01*
X34000Y587900D01*
X34375Y587858D01*
X34750Y587942D01*
X35000Y588067D01*
X35250Y588317D01*
X35417Y588608D01*
X35500Y588900D01*
Y589192D01*
X35417Y589483D01*
X35292Y589733D01*
X35125Y589942D01*
G01X33417Y591208D02*
X33167Y591458D01*
X33042Y591750D01*
X33000Y592083D01*
X33083Y592500D01*
X33292Y592792D01*
X33542Y592875D01*
X33792Y592833D01*
X34000Y592667D01*
X34417Y591833D01*
X34708Y591458D01*
X35125Y591208D01*
X35500Y591125D01*
Y592875D01*
G01Y595100D02*
X35458Y595392D01*
X35333Y595725D01*
X35125Y595933D01*
X34833Y596017D01*
X34542Y595933D01*
X34292Y595683D01*
X34167Y595308D01*
Y594892D01*
X34083Y594642D01*
X33875Y594433D01*
X33583Y594350D01*
X33292Y594475D01*
X33083Y594767D01*
X33000Y595100D01*
X33083Y595433D01*
X33292Y595725D01*
X33583Y595850D01*
X33875Y595767D01*
X34083Y595558D01*
X34167Y595308D01*
Y594892D01*
X34292Y594517D01*
X34542Y594267D01*
X34833Y594183D01*
X35125Y594267D01*
X35333Y594475D01*
X35458Y594808D01*
X35500Y595100D01*
G01X54658Y633000D02*
Y635500D01*
X56242D01*
G01X55658Y634292D02*
X54658D01*
G01X57758Y635083D02*
X58008Y635333D01*
X58300Y635458D01*
X58633Y635500D01*
X59050Y635417D01*
X59342Y635208D01*
X59425Y634958D01*
X59383Y634708D01*
X59217Y634500D01*
X58383Y634083D01*
X58008Y633792D01*
X57758Y633375D01*
X57675Y633000D01*
X59425D01*
G01X84903Y600702D02*
X61903D01*
G01Y639502D02*
X84903D01*
G01X61903Y600702D02*
Y639502D01*
G01X51317Y649792D02*
X51067Y649917D01*
X50775Y650000D01*
X50442D01*
X50067Y649875D01*
X49775Y649667D01*
X49567Y649417D01*
X49400Y649000D01*
X49358Y648625D01*
X49442Y648250D01*
X49567Y648000D01*
X49817Y647750D01*
X50108Y647583D01*
X50400Y647500D01*
X50692D01*
X50983Y647583D01*
X51233Y647708D01*
X51442Y647875D01*
G01X52583Y648000D02*
X52833Y647708D01*
X53167Y647542D01*
X53542Y647500D01*
X53875Y647542D01*
X54208Y647750D01*
X54417Y648000D01*
X54458Y648250D01*
X54375Y648542D01*
X54083Y648750D01*
X53792Y648833D01*
X53417D01*
G01X53792D02*
X54042Y648958D01*
X54250Y649167D01*
X54333Y649417D01*
X54250Y649667D01*
X54042Y649875D01*
X53667Y650000D01*
X53292Y649958D01*
X52917Y649792D01*
G01X55683Y648000D02*
X55933Y647708D01*
X56267Y647542D01*
X56642Y647500D01*
X56975Y647542D01*
X57308Y647750D01*
X57517Y648000D01*
X57558Y648250D01*
X57475Y648542D01*
X57183Y648750D01*
X56892Y648833D01*
X56517D01*
G01X56892D02*
X57142Y648958D01*
X57350Y649167D01*
X57433Y649417D01*
X57350Y649667D01*
X57142Y649875D01*
X56767Y650000D01*
X56392Y649958D01*
X56017Y649792D01*
G01X66017Y650500D02*
Y653000D01*
X67058D01*
X67392Y652875D01*
X67600Y652708D01*
X67683Y652375D01*
X67600Y652042D01*
X67350Y651833D01*
X67058Y651708D01*
X66017D01*
G01X67058D02*
X67683Y650500D01*
G01X69950D02*
Y653000D01*
X69450Y652500D01*
G01Y650500D02*
X70450D01*
G01X72258Y651542D02*
X72550Y651833D01*
X72800Y652000D01*
X73133Y652083D01*
X73425Y652000D01*
X73633Y651833D01*
X73800Y651583D01*
X73842Y651292D01*
X73800Y651042D01*
X73633Y650792D01*
X73383Y650583D01*
X73092Y650500D01*
X72758Y650583D01*
X72467Y650833D01*
X72300Y651208D01*
X72258Y651625D01*
X72342Y652167D01*
X72467Y652458D01*
X72675Y652750D01*
X72967Y652958D01*
X73258Y653000D01*
X73550Y652917D01*
X73758Y652708D01*
G01X76650Y650500D02*
Y653000D01*
X75108Y651208D01*
X77192D01*
G01X64000Y643017D02*
X61500D01*
Y644058D01*
X61625Y644392D01*
X61792Y644600D01*
X62125Y644683D01*
X62458Y644600D01*
X62667Y644350D01*
X62792Y644058D01*
Y643017D01*
G01Y644058D02*
X64000Y644683D01*
G01Y646950D02*
X61500D01*
X62000Y646450D01*
G01X64000D02*
Y647450D01*
G01X62958Y649258D02*
X62667Y649550D01*
X62500Y649800D01*
X62417Y650133D01*
X62500Y650425D01*
X62667Y650633D01*
X62917Y650800D01*
X63208Y650842D01*
X63458Y650800D01*
X63708Y650633D01*
X63917Y650383D01*
X64000Y650092D01*
X63917Y649758D01*
X63667Y649467D01*
X63292Y649300D01*
X62875Y649258D01*
X62333Y649342D01*
X62042Y649467D01*
X61750Y649675D01*
X61542Y649967D01*
X61500Y650258D01*
X61583Y650550D01*
X61792Y650758D01*
G01X63500Y652233D02*
X63792Y652483D01*
X63958Y652817D01*
X64000Y653192D01*
X63958Y653525D01*
X63750Y653858D01*
X63500Y654067D01*
X63250Y654108D01*
X62958Y654025D01*
X62750Y653733D01*
X62667Y653442D01*
Y653067D01*
G01Y653442D02*
X62542Y653692D01*
X62333Y653900D01*
X62083Y653983D01*
X61833Y653900D01*
X61625Y653692D01*
X61500Y653317D01*
X61542Y652942D01*
X61708Y652567D01*
G01X81500Y642517D02*
X79000D01*
Y643558D01*
X79125Y643892D01*
X79292Y644100D01*
X79625Y644183D01*
X79958Y644100D01*
X80167Y643850D01*
X80292Y643558D01*
Y642517D01*
G01Y643558D02*
X81500Y644183D01*
G01Y646450D02*
X79000D01*
X79500Y645950D01*
G01X81500D02*
Y646950D01*
G01X80458Y648758D02*
X80167Y649050D01*
X80000Y649300D01*
X79917Y649633D01*
X80000Y649925D01*
X80167Y650133D01*
X80417Y650300D01*
X80708Y650342D01*
X80958Y650300D01*
X81208Y650133D01*
X81417Y649883D01*
X81500Y649592D01*
X81417Y649258D01*
X81167Y648967D01*
X80792Y648800D01*
X80375Y648758D01*
X79833Y648842D01*
X79542Y648967D01*
X79250Y649175D01*
X79042Y649467D01*
X79000Y649758D01*
X79083Y650050D01*
X79292Y650258D01*
G01X79417Y651858D02*
X79167Y652108D01*
X79042Y652400D01*
X79000Y652733D01*
X79083Y653150D01*
X79292Y653442D01*
X79542Y653525D01*
X79792Y653483D01*
X80000Y653317D01*
X80417Y652483D01*
X80708Y652108D01*
X81125Y651858D01*
X81500Y651775D01*
Y653525D01*
G01X49500Y613517D02*
X47000D01*
Y614558D01*
X47125Y614892D01*
X47292Y615100D01*
X47625Y615183D01*
X47958Y615100D01*
X48167Y614850D01*
X48292Y614558D01*
Y613517D01*
G01Y614558D02*
X49500Y615183D01*
G01Y617450D02*
X47000D01*
X47500Y616950D01*
G01X49500D02*
Y617950D01*
G01Y620550D02*
X49458Y620842D01*
X49333Y621175D01*
X49125Y621383D01*
X48833Y621467D01*
X48542Y621383D01*
X48292Y621133D01*
X48167Y620758D01*
Y620342D01*
X48083Y620092D01*
X47875Y619883D01*
X47583Y619800D01*
X47292Y619925D01*
X47083Y620217D01*
X47000Y620550D01*
X47083Y620883D01*
X47292Y621175D01*
X47583Y621300D01*
X47875Y621217D01*
X48083Y621008D01*
X48167Y620758D01*
Y620342D01*
X48292Y619967D01*
X48542Y619717D01*
X48833Y619633D01*
X49125Y619717D01*
X49333Y619925D01*
X49458Y620258D01*
X49500Y620550D01*
G01Y623650D02*
X47000D01*
X47500Y623150D01*
G01X49500D02*
Y624150D01*
G01X60000Y610700D02*
Y628300D01*
G01X52000Y610700D02*
X60000D01*
G01X52000Y628300D02*
Y610700D01*
G01X60000Y628300D02*
X52000D01*
G01X50700Y676000D02*
X39500D01*
G01X50700Y658000D02*
Y676000D01*
G01X39500Y658000D02*
X50700D01*
G01X72500Y663533D02*
X74292D01*
X74667Y663700D01*
X74917Y664033D01*
X75000Y664450D01*
X74917Y664867D01*
X74667Y665200D01*
X74292Y665367D01*
X72500D01*
G01X74500Y666633D02*
X74792Y666883D01*
X74958Y667217D01*
X75000Y667592D01*
X74958Y667925D01*
X74750Y668258D01*
X74500Y668467D01*
X74250Y668508D01*
X73958Y668425D01*
X73750Y668133D01*
X73667Y667842D01*
Y667467D01*
G01Y667842D02*
X73542Y668092D01*
X73333Y668300D01*
X73083Y668383D01*
X72833Y668300D01*
X72625Y668092D01*
X72500Y667717D01*
X72542Y667342D01*
X72708Y666967D01*
G01X74435Y684556D02*
Y671156D01*
G01X64435Y684556D02*
X74435D01*
G01X64435Y671156D02*
Y684556D01*
G01X74435Y671156D02*
X64435D01*
G01X48983Y698500D02*
Y696708D01*
X49150Y696333D01*
X49483Y696083D01*
X49900Y696000D01*
X50317Y696083D01*
X50650Y696333D01*
X50817Y696708D01*
Y698500D01*
G01X53000Y696000D02*
Y698500D01*
X52500Y698000D01*
G01Y696000D02*
X53500D01*
G01X56100D02*
Y698500D01*
X55600Y698000D01*
G01Y696000D02*
X56600D01*
G01X61700Y683000D02*
X48300D01*
G01X61700Y693000D02*
Y683000D01*
G01X48300Y693000D02*
X61700D01*
G01X48300Y683000D02*
Y693000D01*
G01X33983Y698000D02*
Y696208D01*
X34150Y695833D01*
X34483Y695583D01*
X34900Y695500D01*
X35317Y695583D01*
X35650Y695833D01*
X35817Y696208D01*
Y698000D01*
G01X38000Y695500D02*
Y698000D01*
X37500Y697500D01*
G01Y695500D02*
X38500D01*
G01X41100Y698000D02*
X40767Y697917D01*
X40517Y697708D01*
X40350Y697458D01*
X40225Y697125D01*
X40183Y696750D01*
X40225Y696375D01*
X40350Y696042D01*
X40517Y695792D01*
X40767Y695583D01*
X41100Y695500D01*
X41433Y695583D01*
X41683Y695792D01*
X41850Y696042D01*
X41975Y696375D01*
X42017Y696750D01*
X41975Y697125D01*
X41850Y697458D01*
X41683Y697708D01*
X41433Y697917D01*
X41100Y698000D01*
G01X46200Y683000D02*
X32800D01*
G01X46200Y693000D02*
Y683000D01*
G01X32800Y693000D02*
X46200D01*
G01X32800Y683000D02*
Y693000D01*
G01X51317Y653792D02*
X51067Y653917D01*
X50775Y654000D01*
X50442D01*
X50067Y653875D01*
X49775Y653667D01*
X49567Y653417D01*
X49400Y653000D01*
X49358Y652625D01*
X49442Y652250D01*
X49567Y652000D01*
X49817Y651750D01*
X50108Y651583D01*
X50400Y651500D01*
X50692D01*
X50983Y651583D01*
X51233Y651708D01*
X51442Y651875D01*
G01X52583Y652000D02*
X52833Y651708D01*
X53167Y651542D01*
X53542Y651500D01*
X53875Y651542D01*
X54208Y651750D01*
X54417Y652000D01*
X54458Y652250D01*
X54375Y652542D01*
X54083Y652750D01*
X53792Y652833D01*
X53417D01*
G01X53792D02*
X54042Y652958D01*
X54250Y653167D01*
X54333Y653417D01*
X54250Y653667D01*
X54042Y653875D01*
X53667Y654000D01*
X53292Y653958D01*
X52917Y653792D01*
G01X57100Y651500D02*
Y654000D01*
X55558Y652208D01*
X57642D01*
G01X59867Y699792D02*
X59617Y699917D01*
X59325Y700000D01*
X58992D01*
X58617Y699875D01*
X58325Y699667D01*
X58117Y699417D01*
X57950Y699000D01*
X57908Y698625D01*
X57992Y698250D01*
X58117Y698000D01*
X58367Y697750D01*
X58658Y697583D01*
X58950Y697500D01*
X59242D01*
X59533Y697583D01*
X59783Y697708D01*
X59992Y697875D01*
G01X61342Y697792D02*
X61633Y697583D01*
X61967Y697500D01*
X62300Y697583D01*
X62592Y697833D01*
X62800Y698208D01*
X62883Y698583D01*
Y699042D01*
X62800Y699417D01*
X62592Y699750D01*
X62342Y699917D01*
X62050Y700000D01*
X61717Y699917D01*
X61467Y699750D01*
X61300Y699500D01*
X61217Y699167D01*
X61300Y698875D01*
X61508Y698583D01*
X61758Y698417D01*
X62050Y698375D01*
X62383Y698458D01*
X62633Y698667D01*
X62883Y699042D01*
G01X67317Y699792D02*
X67067Y699917D01*
X66775Y700000D01*
X66442D01*
X66067Y699875D01*
X65775Y699667D01*
X65567Y699417D01*
X65400Y699000D01*
X65358Y698625D01*
X65442Y698250D01*
X65567Y698000D01*
X65817Y697750D01*
X66108Y697583D01*
X66400Y697500D01*
X66692D01*
X66983Y697583D01*
X67233Y697708D01*
X67442Y697875D01*
G01X69500Y697500D02*
Y700000D01*
X69000Y699500D01*
G01Y697500D02*
X70000D01*
G01X72600Y700000D02*
X72267Y699917D01*
X72017Y699708D01*
X71850Y699458D01*
X71725Y699125D01*
X71683Y698750D01*
X71725Y698375D01*
X71850Y698042D01*
X72017Y697792D01*
X72267Y697583D01*
X72600Y697500D01*
X72933Y697583D01*
X73183Y697792D01*
X73350Y698042D01*
X73475Y698375D01*
X73517Y698750D01*
X73475Y699125D01*
X73350Y699458D01*
X73183Y699708D01*
X72933Y699917D01*
X72600Y700000D01*
G01X77067Y676500D02*
Y679000D01*
X78108D01*
X78442Y678875D01*
X78650Y678708D01*
X78733Y678375D01*
X78650Y678042D01*
X78400Y677833D01*
X78108Y677708D01*
X77067D01*
G01X78108D02*
X78733Y676500D01*
G01X80208Y678583D02*
X80458Y678833D01*
X80750Y678958D01*
X81083Y679000D01*
X81500Y678917D01*
X81792Y678708D01*
X81875Y678458D01*
X81833Y678208D01*
X81667Y678000D01*
X80833Y677583D01*
X80458Y677292D01*
X80208Y676875D01*
X80125Y676500D01*
X81875D01*
G01X84600D02*
Y679000D01*
X83058Y677208D01*
X85142D01*
G01X83944Y692635D02*
Y696635D01*
X76544D01*
G01X77067Y672500D02*
Y675000D01*
X78108D01*
X78442Y674875D01*
X78650Y674708D01*
X78733Y674375D01*
X78650Y674042D01*
X78400Y673833D01*
X78108Y673708D01*
X77067D01*
G01X78108D02*
X78733Y672500D01*
G01X80208Y674583D02*
X80458Y674833D01*
X80750Y674958D01*
X81083Y675000D01*
X81500Y674917D01*
X81792Y674708D01*
X81875Y674458D01*
X81833Y674208D01*
X81667Y674000D01*
X80833Y673583D01*
X80458Y673292D01*
X80208Y672875D01*
X80125Y672500D01*
X81875D01*
G01X83183Y673000D02*
X83433Y672708D01*
X83767Y672542D01*
X84142Y672500D01*
X84475Y672542D01*
X84808Y672750D01*
X85017Y673000D01*
X85058Y673250D01*
X84975Y673542D01*
X84683Y673750D01*
X84392Y673833D01*
X84017D01*
G01X84392D02*
X84642Y673958D01*
X84850Y674167D01*
X84933Y674417D01*
X84850Y674667D01*
X84642Y674875D01*
X84267Y675000D01*
X83892Y674958D01*
X83517Y674792D01*
G01X76556Y692465D02*
Y688465D01*
X83956D01*
G01X77067Y669000D02*
Y671500D01*
X78108D01*
X78442Y671375D01*
X78650Y671208D01*
X78733Y670875D01*
X78650Y670542D01*
X78400Y670333D01*
X78108Y670208D01*
X77067D01*
G01X78108D02*
X78733Y669000D01*
G01X80208Y671083D02*
X80458Y671333D01*
X80750Y671458D01*
X81083Y671500D01*
X81500Y671417D01*
X81792Y671208D01*
X81875Y670958D01*
X81833Y670708D01*
X81667Y670500D01*
X80833Y670083D01*
X80458Y669792D01*
X80208Y669375D01*
X80125Y669000D01*
X81875D01*
G01X83308Y671083D02*
X83558Y671333D01*
X83850Y671458D01*
X84183Y671500D01*
X84600Y671417D01*
X84892Y671208D01*
X84975Y670958D01*
X84933Y670708D01*
X84767Y670500D01*
X83933Y670083D01*
X83558Y669792D01*
X83308Y669375D01*
X83225Y669000D01*
X84975D01*
G01X78700Y688400D02*
Y684400D01*
X86100D01*
G01X80067Y661500D02*
Y664000D01*
X81108D01*
X81442Y663875D01*
X81650Y663708D01*
X81733Y663375D01*
X81650Y663042D01*
X81400Y662833D01*
X81108Y662708D01*
X80067D01*
G01X81108D02*
X81733Y661500D01*
G01X83208Y663583D02*
X83458Y663833D01*
X83750Y663958D01*
X84083Y664000D01*
X84500Y663917D01*
X84792Y663708D01*
X84875Y663458D01*
X84833Y663208D01*
X84667Y663000D01*
X83833Y662583D01*
X83458Y662292D01*
X83208Y661875D01*
X83125Y661500D01*
X84875D01*
G01X87100D02*
Y664000D01*
X86600Y663500D01*
G01Y661500D02*
X87600D01*
G01X80067Y658000D02*
Y660500D01*
X81108D01*
X81442Y660375D01*
X81650Y660208D01*
X81733Y659875D01*
X81650Y659542D01*
X81400Y659333D01*
X81108Y659208D01*
X80067D01*
G01X81108D02*
X81733Y658000D01*
G01X83208Y660083D02*
X83458Y660333D01*
X83750Y660458D01*
X84083Y660500D01*
X84500Y660417D01*
X84792Y660208D01*
X84875Y659958D01*
X84833Y659708D01*
X84667Y659500D01*
X83833Y659083D01*
X83458Y658792D01*
X83208Y658375D01*
X83125Y658000D01*
X84875D01*
G01X87100Y660500D02*
X86767Y660417D01*
X86517Y660208D01*
X86350Y659958D01*
X86225Y659625D01*
X86183Y659250D01*
X86225Y658875D01*
X86350Y658542D01*
X86517Y658292D01*
X86767Y658083D01*
X87100Y658000D01*
X87433Y658083D01*
X87683Y658292D01*
X87850Y658542D01*
X87975Y658875D01*
X88017Y659250D01*
X87975Y659625D01*
X87850Y659958D01*
X87683Y660208D01*
X87433Y660417D01*
X87100Y660500D01*
G01X75200Y700500D02*
X79200D01*
Y707900D01*
G01X61567Y666000D02*
Y668500D01*
X62608D01*
X62942Y668375D01*
X63150Y668208D01*
X63233Y667875D01*
X63150Y667542D01*
X62900Y667333D01*
X62608Y667208D01*
X61567D01*
G01X62608D02*
X63233Y666000D01*
G01X64583Y666375D02*
X64833Y666167D01*
X65125Y666042D01*
X65500Y666000D01*
X65875Y666083D01*
X66167Y666250D01*
X66375Y666542D01*
X66417Y666875D01*
X66333Y667208D01*
X66125Y667417D01*
X65833Y667583D01*
X65542Y667625D01*
X65250Y667583D01*
X64875Y667417D01*
X65000Y668500D01*
X66125D01*
G01X67808Y668083D02*
X68058Y668333D01*
X68350Y668458D01*
X68683Y668500D01*
X69100Y668417D01*
X69392Y668208D01*
X69475Y667958D01*
X69433Y667708D01*
X69267Y667500D01*
X68433Y667083D01*
X68058Y666792D01*
X67808Y666375D01*
X67725Y666000D01*
X69475D01*
G01X63400Y678800D02*
X59400D01*
Y671400D01*
G01X54500Y670567D02*
X52000D01*
Y671608D01*
X52125Y671942D01*
X52292Y672150D01*
X52625Y672233D01*
X52958Y672150D01*
X53167Y671900D01*
X53292Y671608D01*
Y670567D01*
G01Y671608D02*
X54500Y672233D01*
G01Y675000D02*
X52000D01*
X53792Y673458D01*
Y675542D01*
G01X54208Y676892D02*
X54417Y677183D01*
X54500Y677517D01*
X54417Y677850D01*
X54167Y678142D01*
X53792Y678350D01*
X53417Y678433D01*
X52958D01*
X52583Y678350D01*
X52250Y678142D01*
X52083Y677892D01*
X52000Y677600D01*
X52083Y677267D01*
X52250Y677017D01*
X52500Y676850D01*
X52833Y676767D01*
X53125Y676850D01*
X53417Y677058D01*
X53583Y677308D01*
X53625Y677600D01*
X53542Y677933D01*
X53333Y678183D01*
X52958Y678433D01*
G01X59400Y678800D02*
X55400D01*
Y671400D01*
G01X77017Y665500D02*
Y668000D01*
X78058D01*
X78392Y667875D01*
X78600Y667708D01*
X78683Y667375D01*
X78600Y667042D01*
X78350Y666833D01*
X78058Y666708D01*
X77017D01*
G01X78058D02*
X78683Y665500D01*
G01X80950D02*
Y668000D01*
X80450Y667500D01*
G01Y665500D02*
X81450D01*
G01X84050D02*
X84342Y665542D01*
X84675Y665667D01*
X84883Y665875D01*
X84967Y666167D01*
X84883Y666458D01*
X84633Y666708D01*
X84258Y666833D01*
X83842D01*
X83592Y666917D01*
X83383Y667125D01*
X83300Y667417D01*
X83425Y667708D01*
X83717Y667917D01*
X84050Y668000D01*
X84383Y667917D01*
X84675Y667708D01*
X84800Y667417D01*
X84717Y667125D01*
X84508Y666917D01*
X84258Y666833D01*
X83842D01*
X83467Y666708D01*
X83217Y666458D01*
X83133Y666167D01*
X83217Y665875D01*
X83425Y665667D01*
X83758Y665542D01*
X84050Y665500D01*
G01X86233Y666000D02*
X86483Y665708D01*
X86817Y665542D01*
X87192Y665500D01*
X87525Y665542D01*
X87858Y665750D01*
X88067Y666000D01*
X88108Y666250D01*
X88025Y666542D01*
X87733Y666750D01*
X87442Y666833D01*
X87067D01*
G01X87442D02*
X87692Y666958D01*
X87900Y667167D01*
X87983Y667417D01*
X87900Y667667D01*
X87692Y667875D01*
X87317Y668000D01*
X86942Y667958D01*
X86567Y667792D01*
G01X85400Y680200D02*
Y684200D01*
X78000D01*
G01X63500Y750658D02*
X61000D01*
Y752242D01*
G01X62208Y751658D02*
Y750658D01*
G01X63000Y753633D02*
X63292Y753883D01*
X63458Y754217D01*
X63500Y754592D01*
X63458Y754925D01*
X63250Y755258D01*
X63000Y755467D01*
X62750Y755508D01*
X62458Y755425D01*
X62250Y755133D01*
X62167Y754842D01*
Y754467D01*
G01Y754842D02*
X62042Y755092D01*
X61833Y755300D01*
X61583Y755383D01*
X61333Y755300D01*
X61125Y755092D01*
X61000Y754717D01*
X61042Y754342D01*
X61208Y753967D01*
G01X66602Y746397D02*
Y769397D01*
G01X105402Y746397D02*
X66602D01*
G01X99000Y719400D02*
X78000D01*
G01D02*
Y711400D01*
G01D02*
X99000D01*
G01X98500Y744400D02*
X77500D01*
G01D02*
Y736400D01*
G01D02*
X98500D01*
G01X63000Y702567D02*
X60500D01*
Y703608D01*
X60625Y703942D01*
X60792Y704150D01*
X61125Y704233D01*
X61458Y704150D01*
X61667Y703900D01*
X61792Y703608D01*
Y702567D01*
G01Y703608D02*
X63000Y704233D01*
G01Y706500D02*
X62958Y706792D01*
X62833Y707125D01*
X62625Y707333D01*
X62333Y707417D01*
X62042Y707333D01*
X61792Y707083D01*
X61667Y706708D01*
Y706292D01*
X61583Y706042D01*
X61375Y705833D01*
X61083Y705750D01*
X60792Y705875D01*
X60583Y706167D01*
X60500Y706500D01*
X60583Y706833D01*
X60792Y707125D01*
X61083Y707250D01*
X61375Y707167D01*
X61583Y706958D01*
X61667Y706708D01*
Y706292D01*
X61792Y705917D01*
X62042Y705667D01*
X62333Y705583D01*
X62625Y705667D01*
X62833Y705875D01*
X62958Y706208D01*
X63000Y706500D01*
G01Y709517D02*
X62458Y709600D01*
X62000Y709725D01*
X61583Y709892D01*
X61125Y710100D01*
X60500Y710433D01*
Y708767D01*
G01X51708Y705817D02*
X51583Y705567D01*
X51500Y705275D01*
Y704942D01*
X51625Y704567D01*
X51833Y704275D01*
X52083Y704067D01*
X52500Y703900D01*
X52875Y703858D01*
X53250Y703942D01*
X53500Y704067D01*
X53750Y704317D01*
X53917Y704608D01*
X54000Y704900D01*
Y705192D01*
X53917Y705483D01*
X53792Y705733D01*
X53625Y705942D01*
G01Y707083D02*
X53833Y707333D01*
X53958Y707625D01*
X54000Y708000D01*
X53917Y708375D01*
X53750Y708667D01*
X53458Y708875D01*
X53125Y708917D01*
X52792Y708833D01*
X52583Y708625D01*
X52417Y708333D01*
X52375Y708042D01*
X52417Y707750D01*
X52583Y707375D01*
X51500Y707500D01*
Y708625D01*
G01X53625Y710183D02*
X53833Y710433D01*
X53958Y710725D01*
X54000Y711100D01*
X53917Y711475D01*
X53750Y711767D01*
X53458Y711975D01*
X53125Y712017D01*
X52792Y711933D01*
X52583Y711725D01*
X52417Y711433D01*
X52375Y711142D01*
X52417Y710850D01*
X52583Y710475D01*
X51500Y710600D01*
Y711725D01*
G01X47408Y705817D02*
X47283Y705567D01*
X47200Y705275D01*
Y704942D01*
X47325Y704567D01*
X47533Y704275D01*
X47783Y704067D01*
X48200Y703900D01*
X48575Y703858D01*
X48950Y703942D01*
X49200Y704067D01*
X49450Y704317D01*
X49617Y704608D01*
X49700Y704900D01*
Y705192D01*
X49617Y705483D01*
X49492Y705733D01*
X49325Y705942D01*
G01Y707083D02*
X49533Y707333D01*
X49658Y707625D01*
X49700Y708000D01*
X49617Y708375D01*
X49450Y708667D01*
X49158Y708875D01*
X48825Y708917D01*
X48492Y708833D01*
X48283Y708625D01*
X48117Y708333D01*
X48075Y708042D01*
X48117Y707750D01*
X48283Y707375D01*
X47200Y707500D01*
Y708625D01*
G01X49700Y711600D02*
X47200D01*
X48992Y710058D01*
Y712142D01*
G01X58500Y702567D02*
X56000D01*
Y703608D01*
X56125Y703942D01*
X56292Y704150D01*
X56625Y704233D01*
X56958Y704150D01*
X57167Y703900D01*
X57292Y703608D01*
Y702567D01*
G01Y703608D02*
X58500Y704233D01*
G01X58208Y705792D02*
X58417Y706083D01*
X58500Y706417D01*
X58417Y706750D01*
X58167Y707042D01*
X57792Y707250D01*
X57417Y707333D01*
X56958D01*
X56583Y707250D01*
X56250Y707042D01*
X56083Y706792D01*
X56000Y706500D01*
X56083Y706167D01*
X56250Y705917D01*
X56500Y705750D01*
X56833Y705667D01*
X57125Y705750D01*
X57417Y705958D01*
X57583Y706208D01*
X57625Y706500D01*
X57542Y706833D01*
X57333Y707083D01*
X56958Y707333D01*
G01X58500Y709600D02*
X56000D01*
X56500Y709100D01*
G01X58500D02*
Y710100D01*
G01X75000Y725400D02*
X79000D01*
Y732800D01*
G01X53167Y728800D02*
Y731300D01*
X54208D01*
X54542Y731175D01*
X54750Y731008D01*
X54833Y730675D01*
X54750Y730342D01*
X54500Y730133D01*
X54208Y730008D01*
X53167D01*
G01X54208D02*
X54833Y728800D01*
G01X57017D02*
X57100Y729342D01*
X57225Y729800D01*
X57392Y730217D01*
X57600Y730675D01*
X57933Y731300D01*
X56267D01*
G01X59492Y729092D02*
X59783Y728883D01*
X60117Y728800D01*
X60450Y728883D01*
X60742Y729133D01*
X60950Y729508D01*
X61033Y729883D01*
Y730342D01*
X60950Y730717D01*
X60742Y731050D01*
X60492Y731217D01*
X60200Y731300D01*
X59867Y731217D01*
X59617Y731050D01*
X59450Y730800D01*
X59367Y730467D01*
X59450Y730175D01*
X59658Y729883D01*
X59908Y729717D01*
X60200Y729675D01*
X60533Y729758D01*
X60783Y729967D01*
X61033Y730342D01*
G01X70700Y728000D02*
Y732000D01*
X63300D01*
G01X70208Y737317D02*
X70083Y737067D01*
X70000Y736775D01*
Y736442D01*
X70125Y736067D01*
X70333Y735775D01*
X70583Y735567D01*
X71000Y735400D01*
X71375Y735358D01*
X71750Y735442D01*
X72000Y735567D01*
X72250Y735817D01*
X72417Y736108D01*
X72500Y736400D01*
Y736692D01*
X72417Y736983D01*
X72292Y737233D01*
X72125Y737442D01*
G01X72000Y738583D02*
X72292Y738833D01*
X72458Y739167D01*
X72500Y739542D01*
X72458Y739875D01*
X72250Y740208D01*
X72000Y740417D01*
X71750Y740458D01*
X71458Y740375D01*
X71250Y740083D01*
X71167Y739792D01*
Y739417D01*
G01Y739792D02*
X71042Y740042D01*
X70833Y740250D01*
X70583Y740333D01*
X70333Y740250D01*
X70125Y740042D01*
X70000Y739667D01*
X70042Y739292D01*
X70208Y738917D01*
G01X72500Y742517D02*
X71958Y742600D01*
X71500Y742725D01*
X71083Y742892D01*
X70625Y743100D01*
X70000Y743433D01*
Y741767D01*
G01X74317Y724292D02*
X74067Y724417D01*
X73775Y724500D01*
X73442D01*
X73067Y724375D01*
X72775Y724167D01*
X72567Y723917D01*
X72400Y723500D01*
X72358Y723125D01*
X72442Y722750D01*
X72567Y722500D01*
X72817Y722250D01*
X73108Y722083D01*
X73400Y722000D01*
X73692D01*
X73983Y722083D01*
X74233Y722208D01*
X74442Y722375D01*
G01X75583Y722500D02*
X75833Y722208D01*
X76167Y722042D01*
X76542Y722000D01*
X76875Y722042D01*
X77208Y722250D01*
X77417Y722500D01*
X77458Y722750D01*
X77375Y723042D01*
X77083Y723250D01*
X76792Y723333D01*
X76417D01*
G01X76792D02*
X77042Y723458D01*
X77250Y723667D01*
X77333Y723917D01*
X77250Y724167D01*
X77042Y724375D01*
X76667Y724500D01*
X76292Y724458D01*
X75917Y724292D01*
G01X78808Y723042D02*
X79100Y723333D01*
X79350Y723500D01*
X79683Y723583D01*
X79975Y723500D01*
X80183Y723333D01*
X80350Y723083D01*
X80392Y722792D01*
X80350Y722542D01*
X80183Y722292D01*
X79933Y722083D01*
X79642Y722000D01*
X79308Y722083D01*
X79017Y722333D01*
X78850Y722708D01*
X78808Y723125D01*
X78892Y723667D01*
X79017Y723958D01*
X79225Y724250D01*
X79517Y724458D01*
X79808Y724500D01*
X80100Y724417D01*
X80308Y724208D01*
G01X66602Y769397D02*
X105402D01*
G01X61500Y793350D02*
X64000D01*
G01X61500Y792392D02*
Y794308D01*
G01X61708Y797367D02*
X61583Y797117D01*
X61500Y796825D01*
Y796492D01*
X61625Y796117D01*
X61833Y795825D01*
X62083Y795617D01*
X62500Y795450D01*
X62875Y795408D01*
X63250Y795492D01*
X63500Y795617D01*
X63750Y795867D01*
X63917Y796158D01*
X64000Y796450D01*
Y796742D01*
X63917Y797033D01*
X63792Y797283D01*
X63625Y797492D01*
G01X64000Y799550D02*
X61500D01*
X62000Y799050D01*
G01X64000D02*
Y800050D01*
G01X63625Y801733D02*
X63833Y801983D01*
X63958Y802275D01*
X64000Y802650D01*
X63917Y803025D01*
X63750Y803317D01*
X63458Y803525D01*
X63125Y803567D01*
X62792Y803483D01*
X62583Y803275D01*
X62417Y802983D01*
X62375Y802692D01*
X62417Y802400D01*
X62583Y802025D01*
X61500Y802150D01*
Y803275D01*
G01X66800Y789400D02*
Y807400D01*
G01X78000Y789400D02*
X66800D01*
G01X30708Y765817D02*
X30583Y765567D01*
X30500Y765275D01*
Y764942D01*
X30625Y764567D01*
X30833Y764275D01*
X31083Y764067D01*
X31500Y763900D01*
X31875Y763858D01*
X32250Y763942D01*
X32500Y764067D01*
X32750Y764317D01*
X32917Y764608D01*
X33000Y764900D01*
Y765192D01*
X32917Y765483D01*
X32792Y765733D01*
X32625Y765942D01*
G01X33000Y767042D02*
X30500D01*
X33000Y768958D01*
X30500D01*
G01X33000Y771600D02*
X30500D01*
X32292Y770058D01*
Y772142D01*
G01X77400Y772700D02*
X95000D01*
G01X77400Y780700D02*
Y772700D01*
G01X95000Y780700D02*
X77400D01*
G01X66800Y807400D02*
X78000D01*
G01X69017Y847000D02*
Y849500D01*
X70058D01*
X70392Y849375D01*
X70600Y849208D01*
X70683Y848875D01*
X70600Y848542D01*
X70350Y848333D01*
X70058Y848208D01*
X69017D01*
G01X70058D02*
X70683Y847000D01*
G01X72950D02*
Y849500D01*
X72450Y849000D01*
G01Y847000D02*
X73450D01*
G01X75133Y847500D02*
X75383Y847208D01*
X75717Y847042D01*
X76092Y847000D01*
X76425Y847042D01*
X76758Y847250D01*
X76967Y847500D01*
X77008Y847750D01*
X76925Y848042D01*
X76633Y848250D01*
X76342Y848333D01*
X75967D01*
G01X76342D02*
X76592Y848458D01*
X76800Y848667D01*
X76883Y848917D01*
X76800Y849167D01*
X76592Y849375D01*
X76217Y849500D01*
X75842Y849458D01*
X75467Y849292D01*
G01X79150Y847000D02*
Y849500D01*
X78650Y849000D01*
G01Y847000D02*
X79650D01*
G01X69017Y843000D02*
Y845500D01*
X70058D01*
X70392Y845375D01*
X70600Y845208D01*
X70683Y844875D01*
X70600Y844542D01*
X70350Y844333D01*
X70058Y844208D01*
X69017D01*
G01X70058D02*
X70683Y843000D01*
G01X72950D02*
Y845500D01*
X72450Y845000D01*
G01Y843000D02*
X73450D01*
G01X75133Y843500D02*
X75383Y843208D01*
X75717Y843042D01*
X76092Y843000D01*
X76425Y843042D01*
X76758Y843250D01*
X76967Y843500D01*
X77008Y843750D01*
X76925Y844042D01*
X76633Y844250D01*
X76342Y844333D01*
X75967D01*
G01X76342D02*
X76592Y844458D01*
X76800Y844667D01*
X76883Y844917D01*
X76800Y845167D01*
X76592Y845375D01*
X76217Y845500D01*
X75842Y845458D01*
X75467Y845292D01*
G01X79150Y845500D02*
X78817Y845417D01*
X78567Y845208D01*
X78400Y844958D01*
X78275Y844625D01*
X78233Y844250D01*
X78275Y843875D01*
X78400Y843542D01*
X78567Y843292D01*
X78817Y843083D01*
X79150Y843000D01*
X79483Y843083D01*
X79733Y843292D01*
X79900Y843542D01*
X80025Y843875D01*
X80067Y844250D01*
X80025Y844625D01*
X79900Y844958D01*
X79733Y845208D01*
X79483Y845417D01*
X79150Y845500D01*
G01X69017Y851000D02*
Y853500D01*
X70058D01*
X70392Y853375D01*
X70600Y853208D01*
X70683Y852875D01*
X70600Y852542D01*
X70350Y852333D01*
X70058Y852208D01*
X69017D01*
G01X70058D02*
X70683Y851000D01*
G01X72950D02*
Y853500D01*
X72450Y853000D01*
G01Y851000D02*
X73450D01*
G01X75133Y851500D02*
X75383Y851208D01*
X75717Y851042D01*
X76092Y851000D01*
X76425Y851042D01*
X76758Y851250D01*
X76967Y851500D01*
X77008Y851750D01*
X76925Y852042D01*
X76633Y852250D01*
X76342Y852333D01*
X75967D01*
G01X76342D02*
X76592Y852458D01*
X76800Y852667D01*
X76883Y852917D01*
X76800Y853167D01*
X76592Y853375D01*
X76217Y853500D01*
X75842Y853458D01*
X75467Y853292D01*
G01X78358Y853083D02*
X78608Y853333D01*
X78900Y853458D01*
X79233Y853500D01*
X79650Y853417D01*
X79942Y853208D01*
X80025Y852958D01*
X79983Y852708D01*
X79817Y852500D01*
X78983Y852083D01*
X78608Y851792D01*
X78358Y851375D01*
X78275Y851000D01*
X80025D01*
G01X69017Y855000D02*
Y857500D01*
X70058D01*
X70392Y857375D01*
X70600Y857208D01*
X70683Y856875D01*
X70600Y856542D01*
X70350Y856333D01*
X70058Y856208D01*
X69017D01*
G01X70058D02*
X70683Y855000D01*
G01X72950D02*
Y857500D01*
X72450Y857000D01*
G01Y855000D02*
X73450D01*
G01X75133Y855500D02*
X75383Y855208D01*
X75717Y855042D01*
X76092Y855000D01*
X76425Y855042D01*
X76758Y855250D01*
X76967Y855500D01*
X77008Y855750D01*
X76925Y856042D01*
X76633Y856250D01*
X76342Y856333D01*
X75967D01*
G01X76342D02*
X76592Y856458D01*
X76800Y856667D01*
X76883Y856917D01*
X76800Y857167D01*
X76592Y857375D01*
X76217Y857500D01*
X75842Y857458D01*
X75467Y857292D01*
G01X78233Y855500D02*
X78483Y855208D01*
X78817Y855042D01*
X79192Y855000D01*
X79525Y855042D01*
X79858Y855250D01*
X80067Y855500D01*
X80108Y855750D01*
X80025Y856042D01*
X79733Y856250D01*
X79442Y856333D01*
X79067D01*
G01X79442D02*
X79692Y856458D01*
X79900Y856667D01*
X79983Y856917D01*
X79900Y857167D01*
X79692Y857375D01*
X79317Y857500D01*
X78942Y857458D01*
X78567Y857292D01*
G01X69017Y863000D02*
Y865500D01*
X70058D01*
X70392Y865375D01*
X70600Y865208D01*
X70683Y864875D01*
X70600Y864542D01*
X70350Y864333D01*
X70058Y864208D01*
X69017D01*
G01X70058D02*
X70683Y863000D01*
G01X72950D02*
Y865500D01*
X72450Y865000D01*
G01Y863000D02*
X73450D01*
G01X75133Y863500D02*
X75383Y863208D01*
X75717Y863042D01*
X76092Y863000D01*
X76425Y863042D01*
X76758Y863250D01*
X76967Y863500D01*
X77008Y863750D01*
X76925Y864042D01*
X76633Y864250D01*
X76342Y864333D01*
X75967D01*
G01X76342D02*
X76592Y864458D01*
X76800Y864667D01*
X76883Y864917D01*
X76800Y865167D01*
X76592Y865375D01*
X76217Y865500D01*
X75842Y865458D01*
X75467Y865292D01*
G01X78233Y863375D02*
X78483Y863167D01*
X78775Y863042D01*
X79150Y863000D01*
X79525Y863083D01*
X79817Y863250D01*
X80025Y863542D01*
X80067Y863875D01*
X79983Y864208D01*
X79775Y864417D01*
X79483Y864583D01*
X79192Y864625D01*
X78900Y864583D01*
X78525Y864417D01*
X78650Y865500D01*
X79775D01*
G01X69017Y859000D02*
Y861500D01*
X70058D01*
X70392Y861375D01*
X70600Y861208D01*
X70683Y860875D01*
X70600Y860542D01*
X70350Y860333D01*
X70058Y860208D01*
X69017D01*
G01X70058D02*
X70683Y859000D01*
G01X72950D02*
Y861500D01*
X72450Y861000D01*
G01Y859000D02*
X73450D01*
G01X75133Y859500D02*
X75383Y859208D01*
X75717Y859042D01*
X76092Y859000D01*
X76425Y859042D01*
X76758Y859250D01*
X76967Y859500D01*
X77008Y859750D01*
X76925Y860042D01*
X76633Y860250D01*
X76342Y860333D01*
X75967D01*
G01X76342D02*
X76592Y860458D01*
X76800Y860667D01*
X76883Y860917D01*
X76800Y861167D01*
X76592Y861375D01*
X76217Y861500D01*
X75842Y861458D01*
X75467Y861292D01*
G01X79650Y859000D02*
Y861500D01*
X78108Y859708D01*
X80192D01*
G01X70500Y906117D02*
X68000D01*
Y907158D01*
X68125Y907492D01*
X68292Y907700D01*
X68625Y907783D01*
X68958Y907700D01*
X69167Y907450D01*
X69292Y907158D01*
Y906117D01*
G01Y907158D02*
X70500Y907783D01*
G01Y910050D02*
X68000D01*
X68500Y909550D01*
G01X70500D02*
Y910550D01*
G01Y913150D02*
X68000D01*
X68500Y912650D01*
G01X70500D02*
Y913650D01*
G01X70125Y915333D02*
X70333Y915583D01*
X70458Y915875D01*
X70500Y916250D01*
X70417Y916625D01*
X70250Y916917D01*
X69958Y917125D01*
X69625Y917167D01*
X69292Y917083D01*
X69083Y916875D01*
X68917Y916583D01*
X68875Y916292D01*
X68917Y916000D01*
X69083Y915625D01*
X68000Y915750D01*
Y916875D01*
G01X32167Y894100D02*
Y896600D01*
X33208D01*
X33542Y896475D01*
X33750Y896308D01*
X33833Y895975D01*
X33750Y895642D01*
X33500Y895433D01*
X33208Y895308D01*
X32167D01*
G01X33208D02*
X33833Y894100D01*
G01X35183Y894600D02*
X35433Y894308D01*
X35767Y894142D01*
X36142Y894100D01*
X36475Y894142D01*
X36808Y894350D01*
X37017Y894600D01*
X37058Y894850D01*
X36975Y895142D01*
X36683Y895350D01*
X36392Y895433D01*
X36017D01*
G01X36392D02*
X36642Y895558D01*
X36850Y895767D01*
X36933Y896017D01*
X36850Y896267D01*
X36642Y896475D01*
X36267Y896600D01*
X35892Y896558D01*
X35517Y896392D01*
G01X38283Y894600D02*
X38533Y894308D01*
X38867Y894142D01*
X39242Y894100D01*
X39575Y894142D01*
X39908Y894350D01*
X40117Y894600D01*
X40158Y894850D01*
X40075Y895142D01*
X39783Y895350D01*
X39492Y895433D01*
X39117D01*
G01X39492D02*
X39742Y895558D01*
X39950Y895767D01*
X40033Y896017D01*
X39950Y896267D01*
X39742Y896475D01*
X39367Y896600D01*
X38992Y896558D01*
X38617Y896392D01*
G01X41400Y890700D02*
X45400D01*
Y898100D01*
G01X46000Y905450D02*
X45958Y905117D01*
X45792Y904825D01*
X45542Y904575D01*
X45250Y904408D01*
X44917Y904325D01*
X44583D01*
X44250Y904408D01*
X43958Y904575D01*
X43708Y904825D01*
X43542Y905117D01*
X43500Y905450D01*
X43542Y905783D01*
X43708Y906075D01*
X43958Y906325D01*
X44250Y906492D01*
X44583Y906575D01*
X44917D01*
X45250Y906492D01*
X45542Y906325D01*
X45792Y906075D01*
X45958Y905783D01*
X46000Y905450D01*
G01X45333Y905783D02*
X46000Y906283D01*
G01X45625Y907633D02*
X45833Y907883D01*
X45958Y908175D01*
X46000Y908550D01*
X45917Y908925D01*
X45750Y909217D01*
X45458Y909425D01*
X45125Y909467D01*
X44792Y909383D01*
X44583Y909175D01*
X44417Y908883D01*
X44375Y908592D01*
X44417Y908300D01*
X44583Y907925D01*
X43500Y908050D01*
Y909175D01*
G01X61317Y899118D02*
Y913118D01*
G01X48317Y899118D02*
X61317D01*
G01X48317Y913118D02*
Y899118D01*
G01X33217Y880300D02*
Y882800D01*
X34258D01*
X34592Y882675D01*
X34800Y882508D01*
X34883Y882175D01*
X34800Y881842D01*
X34550Y881633D01*
X34258Y881508D01*
X33217D01*
G01X34258D02*
X34883Y880300D01*
G01X37150D02*
Y882800D01*
X36650Y882300D01*
G01Y880300D02*
X37650D01*
G01X39458Y882383D02*
X39708Y882633D01*
X40000Y882758D01*
X40333Y882800D01*
X40750Y882717D01*
X41042Y882508D01*
X41125Y882258D01*
X41083Y882008D01*
X40917Y881800D01*
X40083Y881383D01*
X39708Y881092D01*
X39458Y880675D01*
X39375Y880300D01*
X41125D01*
G01X43850D02*
Y882800D01*
X42308Y881008D01*
X44392D01*
G01X53900Y880500D02*
X45900D01*
Y898100D01*
X53900D01*
Y880500D01*
G01X66100Y914800D02*
X62100D01*
Y907400D01*
G01X43567Y919500D02*
Y922000D01*
X44608D01*
X44942Y921875D01*
X45150Y921708D01*
X45233Y921375D01*
X45150Y921042D01*
X44900Y920833D01*
X44608Y920708D01*
X43567D01*
G01X44608D02*
X45233Y919500D01*
G01X46583Y920000D02*
X46833Y919708D01*
X47167Y919542D01*
X47542Y919500D01*
X47875Y919542D01*
X48208Y919750D01*
X48417Y920000D01*
X48458Y920250D01*
X48375Y920542D01*
X48083Y920750D01*
X47792Y920833D01*
X47417D01*
G01X47792D02*
X48042Y920958D01*
X48250Y921167D01*
X48333Y921417D01*
X48250Y921667D01*
X48042Y921875D01*
X47667Y922000D01*
X47292Y921958D01*
X46917Y921792D01*
G01X51100Y919500D02*
Y922000D01*
X49558Y920208D01*
X51642D01*
G01X43400Y918400D02*
Y914400D01*
X50800D01*
G01X61317Y913118D02*
X48317D01*
G01X70567Y931000D02*
Y933500D01*
X71567D01*
X71900Y933375D01*
X72150Y933083D01*
X72233Y932750D01*
X72150Y932417D01*
X71942Y932167D01*
X71567Y932042D01*
X70567D01*
G01X73667Y933500D02*
Y931000D01*
X75333D01*
G01X77517D02*
X77600Y931542D01*
X77725Y932000D01*
X77892Y932417D01*
X78100Y932875D01*
X78433Y933500D01*
X76767D01*
G01X90650Y943036D02*
X84014Y936400D01*
X66586D01*
X59950Y943036D01*
Y956164D01*
X66586Y962800D01*
X84014D01*
X90650Y956164D01*
Y943036D01*
G01X56300Y1015800D02*
Y1007800D01*
G01D02*
X77300D01*
G01D02*
Y1015800D01*
G01X80400Y968550D02*
X85000D01*
G01X80400Y983050D02*
Y968550D01*
G01X85000Y983050D02*
X80400D01*
G01X70017Y991000D02*
Y993500D01*
X71017D01*
X71350Y993375D01*
X71600Y993083D01*
X71683Y992750D01*
X71600Y992417D01*
X71392Y992167D01*
X71017Y992042D01*
X70017D01*
G01X73117Y991000D02*
Y993500D01*
X74158D01*
X74492Y993375D01*
X74700Y993208D01*
X74783Y992875D01*
X74700Y992542D01*
X74450Y992333D01*
X74158Y992208D01*
X73117D01*
G01X74158D02*
X74783Y991000D01*
G01X76133Y991375D02*
X76383Y991167D01*
X76675Y991042D01*
X77050Y991000D01*
X77425Y991083D01*
X77717Y991250D01*
X77925Y991542D01*
X77967Y991875D01*
X77883Y992208D01*
X77675Y992417D01*
X77383Y992583D01*
X77092Y992625D01*
X76800Y992583D01*
X76425Y992417D01*
X76550Y993500D01*
X77675D01*
G01X79233Y991500D02*
X79483Y991208D01*
X79817Y991042D01*
X80192Y991000D01*
X80525Y991042D01*
X80858Y991250D01*
X81067Y991500D01*
X81108Y991750D01*
X81025Y992042D01*
X80733Y992250D01*
X80442Y992333D01*
X80067D01*
G01X80442D02*
X80692Y992458D01*
X80900Y992667D01*
X80983Y992917D01*
X80900Y993167D01*
X80692Y993375D01*
X80317Y993500D01*
X79942Y993458D01*
X79567Y993292D01*
G01X53500Y977017D02*
X51000D01*
Y978017D01*
X51125Y978350D01*
X51417Y978600D01*
X51750Y978683D01*
X52083Y978600D01*
X52333Y978392D01*
X52458Y978017D01*
Y977017D01*
G01X53500Y980117D02*
X51000D01*
Y981158D01*
X51125Y981492D01*
X51292Y981700D01*
X51625Y981783D01*
X51958Y981700D01*
X52167Y981450D01*
X52292Y981158D01*
Y980117D01*
G01Y981158D02*
X53500Y981783D01*
G01X53125Y983133D02*
X53333Y983383D01*
X53458Y983675D01*
X53500Y984050D01*
X53417Y984425D01*
X53250Y984717D01*
X52958Y984925D01*
X52625Y984967D01*
X52292Y984883D01*
X52083Y984675D01*
X51917Y984383D01*
X51875Y984092D01*
X51917Y983800D01*
X52083Y983425D01*
X51000Y983550D01*
Y984675D01*
G01X51417Y986358D02*
X51167Y986608D01*
X51042Y986900D01*
X51000Y987233D01*
X51083Y987650D01*
X51292Y987942D01*
X51542Y988025D01*
X51792Y987983D01*
X52000Y987817D01*
X52417Y986983D01*
X52708Y986608D01*
X53125Y986358D01*
X53500Y986275D01*
Y988025D01*
G01X60000Y997567D02*
X57500D01*
Y998608D01*
X57625Y998942D01*
X57792Y999150D01*
X58125Y999233D01*
X58458Y999150D01*
X58667Y998900D01*
X58792Y998608D01*
Y997567D01*
G01Y998608D02*
X60000Y999233D01*
G01Y1001500D02*
X59958Y1001792D01*
X59833Y1002125D01*
X59625Y1002333D01*
X59333Y1002417D01*
X59042Y1002333D01*
X58792Y1002083D01*
X58667Y1001708D01*
Y1001292D01*
X58583Y1001042D01*
X58375Y1000833D01*
X58083Y1000750D01*
X57792Y1000875D01*
X57583Y1001167D01*
X57500Y1001500D01*
X57583Y1001833D01*
X57792Y1002125D01*
X58083Y1002250D01*
X58375Y1002167D01*
X58583Y1001958D01*
X58667Y1001708D01*
Y1001292D01*
X58792Y1000917D01*
X59042Y1000667D01*
X59333Y1000583D01*
X59625Y1000667D01*
X59833Y1000875D01*
X59958Y1001208D01*
X60000Y1001500D01*
G01X58958Y1003808D02*
X58667Y1004100D01*
X58500Y1004350D01*
X58417Y1004683D01*
X58500Y1004975D01*
X58667Y1005183D01*
X58917Y1005350D01*
X59208Y1005392D01*
X59458Y1005350D01*
X59708Y1005183D01*
X59917Y1004933D01*
X60000Y1004642D01*
X59917Y1004308D01*
X59667Y1004017D01*
X59292Y1003850D01*
X58875Y1003808D01*
X58333Y1003892D01*
X58042Y1004017D01*
X57750Y1004225D01*
X57542Y1004517D01*
X57500Y1004808D01*
X57583Y1005100D01*
X57792Y1005308D01*
G01X49300Y977117D02*
X46800D01*
Y978117D01*
X46925Y978450D01*
X47217Y978700D01*
X47550Y978783D01*
X47883Y978700D01*
X48133Y978492D01*
X48258Y978117D01*
Y977117D01*
G01X47008Y981967D02*
X46883Y981717D01*
X46800Y981425D01*
Y981092D01*
X46925Y980717D01*
X47133Y980425D01*
X47383Y980217D01*
X47800Y980050D01*
X48175Y980008D01*
X48550Y980092D01*
X48800Y980217D01*
X49050Y980467D01*
X49217Y980758D01*
X49300Y981050D01*
Y981342D01*
X49217Y981633D01*
X49092Y981883D01*
X48925Y982092D01*
G01X49300Y984650D02*
X46800D01*
X48592Y983108D01*
Y985192D01*
G01X46800Y987250D02*
X46883Y986917D01*
X47092Y986667D01*
X47342Y986500D01*
X47675Y986375D01*
X48050Y986333D01*
X48425Y986375D01*
X48758Y986500D01*
X49008Y986667D01*
X49217Y986917D01*
X49300Y987250D01*
X49217Y987583D01*
X49008Y987833D01*
X48758Y988000D01*
X48425Y988125D01*
X48050Y988167D01*
X47675Y988125D01*
X47342Y988000D01*
X47092Y987833D01*
X46883Y987583D01*
X46800Y987250D01*
G01X59800Y984400D02*
Y989900D01*
X67800D01*
Y984300D01*
G01X59800Y972300D02*
Y977800D01*
G01Y972300D02*
X67800D01*
Y977800D01*
G01X75467Y998300D02*
Y1000800D01*
X76508D01*
X76842Y1000675D01*
X77050Y1000508D01*
X77133Y1000175D01*
X77050Y999842D01*
X76800Y999633D01*
X76508Y999508D01*
X75467D01*
G01X76508D02*
X77133Y998300D01*
G01X78692Y998592D02*
X78983Y998383D01*
X79317Y998300D01*
X79650Y998383D01*
X79942Y998633D01*
X80150Y999008D01*
X80233Y999383D01*
Y999842D01*
X80150Y1000217D01*
X79942Y1000550D01*
X79692Y1000717D01*
X79400Y1000800D01*
X79067Y1000717D01*
X78817Y1000550D01*
X78650Y1000300D01*
X78567Y999967D01*
X78650Y999675D01*
X78858Y999383D01*
X79108Y999217D01*
X79400Y999175D01*
X79733Y999258D01*
X79983Y999467D01*
X80233Y999842D01*
G01X82500Y1000800D02*
X82167Y1000717D01*
X81917Y1000508D01*
X81750Y1000258D01*
X81625Y999925D01*
X81583Y999550D01*
X81625Y999175D01*
X81750Y998842D01*
X81917Y998592D01*
X82167Y998383D01*
X82500Y998300D01*
X82833Y998383D01*
X83083Y998592D01*
X83250Y998842D01*
X83375Y999175D01*
X83417Y999550D01*
X83375Y999925D01*
X83250Y1000258D01*
X83083Y1000508D01*
X82833Y1000717D01*
X82500Y1000800D01*
G01X66700Y1001800D02*
Y997800D01*
X74100D01*
G01X75467Y1002800D02*
Y1005300D01*
X76508D01*
X76842Y1005175D01*
X77050Y1005008D01*
X77133Y1004675D01*
X77050Y1004342D01*
X76800Y1004133D01*
X76508Y1004008D01*
X75467D01*
G01X76508D02*
X77133Y1002800D01*
G01X79400D02*
X79692Y1002842D01*
X80025Y1002967D01*
X80233Y1003175D01*
X80317Y1003467D01*
X80233Y1003758D01*
X79983Y1004008D01*
X79608Y1004133D01*
X79192D01*
X78942Y1004217D01*
X78733Y1004425D01*
X78650Y1004717D01*
X78775Y1005008D01*
X79067Y1005217D01*
X79400Y1005300D01*
X79733Y1005217D01*
X80025Y1005008D01*
X80150Y1004717D01*
X80067Y1004425D01*
X79858Y1004217D01*
X79608Y1004133D01*
X79192D01*
X78817Y1004008D01*
X78567Y1003758D01*
X78483Y1003467D01*
X78567Y1003175D01*
X78775Y1002967D01*
X79108Y1002842D01*
X79400Y1002800D01*
G01X81708Y1004883D02*
X81958Y1005133D01*
X82250Y1005258D01*
X82583Y1005300D01*
X83000Y1005217D01*
X83292Y1005008D01*
X83375Y1004758D01*
X83333Y1004508D01*
X83167Y1004300D01*
X82333Y1003883D01*
X81958Y1003592D01*
X81708Y1003175D01*
X81625Y1002800D01*
X83375D01*
G01X74100Y1002300D02*
Y1006300D01*
X66700D01*
G01X46017Y964000D02*
Y966500D01*
X47017D01*
X47350Y966375D01*
X47600Y966083D01*
X47683Y965750D01*
X47600Y965417D01*
X47392Y965167D01*
X47017Y965042D01*
X46017D01*
G01X50867Y966292D02*
X50617Y966417D01*
X50325Y966500D01*
X49992D01*
X49617Y966375D01*
X49325Y966167D01*
X49117Y965917D01*
X48950Y965500D01*
X48908Y965125D01*
X48992Y964750D01*
X49117Y964500D01*
X49367Y964250D01*
X49658Y964083D01*
X49950Y964000D01*
X50242D01*
X50533Y964083D01*
X50783Y964208D01*
X50992Y964375D01*
G01X53550Y964000D02*
Y966500D01*
X52008Y964708D01*
X54092D01*
G01X56150Y964000D02*
Y966500D01*
X55650Y966000D01*
G01Y964000D02*
X56650D01*
G01X48208Y1008817D02*
X48083Y1008567D01*
X48000Y1008275D01*
Y1007942D01*
X48125Y1007567D01*
X48333Y1007275D01*
X48583Y1007067D01*
X49000Y1006900D01*
X49375Y1006858D01*
X49750Y1006942D01*
X50000Y1007067D01*
X50250Y1007317D01*
X50417Y1007608D01*
X50500Y1007900D01*
Y1008192D01*
X50417Y1008483D01*
X50292Y1008733D01*
X50125Y1008942D01*
G01X50000Y1010083D02*
X50292Y1010333D01*
X50458Y1010667D01*
X50500Y1011042D01*
X50458Y1011375D01*
X50250Y1011708D01*
X50000Y1011917D01*
X49750Y1011958D01*
X49458Y1011875D01*
X49250Y1011583D01*
X49167Y1011292D01*
Y1010917D01*
G01Y1011292D02*
X49042Y1011542D01*
X48833Y1011750D01*
X48583Y1011833D01*
X48333Y1011750D01*
X48125Y1011542D01*
X48000Y1011167D01*
X48042Y1010792D01*
X48208Y1010417D01*
G01X50500Y1014100D02*
X50458Y1014392D01*
X50333Y1014725D01*
X50125Y1014933D01*
X49833Y1015017D01*
X49542Y1014933D01*
X49292Y1014683D01*
X49167Y1014308D01*
Y1013892D01*
X49083Y1013642D01*
X48875Y1013433D01*
X48583Y1013350D01*
X48292Y1013475D01*
X48083Y1013767D01*
X48000Y1014100D01*
X48083Y1014433D01*
X48292Y1014725D01*
X48583Y1014850D01*
X48875Y1014767D01*
X49083Y1014558D01*
X49167Y1014308D01*
Y1013892D01*
X49292Y1013517D01*
X49542Y1013267D01*
X49833Y1013183D01*
X50125Y1013267D01*
X50333Y1013475D01*
X50458Y1013808D01*
X50500Y1014100D01*
G01X58000Y984517D02*
X55500D01*
Y985517D01*
X55625Y985850D01*
X55917Y986100D01*
X56250Y986183D01*
X56583Y986100D01*
X56833Y985892D01*
X56958Y985517D01*
Y984517D01*
G01X58000Y987617D02*
X55500D01*
Y988658D01*
X55625Y988992D01*
X55792Y989200D01*
X56125Y989283D01*
X56458Y989200D01*
X56667Y988950D01*
X56792Y988658D01*
Y987617D01*
G01Y988658D02*
X58000Y989283D01*
G01X57625Y990633D02*
X57833Y990883D01*
X57958Y991175D01*
X58000Y991550D01*
X57917Y991925D01*
X57750Y992217D01*
X57458Y992425D01*
X57125Y992467D01*
X56792Y992383D01*
X56583Y992175D01*
X56417Y991883D01*
X56375Y991592D01*
X56417Y991300D01*
X56583Y990925D01*
X55500Y991050D01*
Y992175D01*
G01X58000Y994567D02*
X57458Y994650D01*
X57000Y994775D01*
X56583Y994942D01*
X56125Y995150D01*
X55500Y995483D01*
Y993817D01*
G01X59700Y982500D02*
X54500D01*
Y971700D01*
G01X55500Y1044158D02*
X53000D01*
Y1045742D01*
G01X54208Y1045158D02*
Y1044158D01*
G01X55500Y1048550D02*
X53000D01*
X54792Y1047008D01*
Y1049092D01*
G01X57700Y1038600D02*
Y1061600D01*
G01X96500Y1038600D02*
X57700D01*
G01X77300Y1015800D02*
X56300D01*
G01X81600Y1036100D02*
X60600D01*
G01D02*
Y1028100D01*
G01D02*
X81600D01*
G01X49067Y1024500D02*
Y1027000D01*
X50108D01*
X50442Y1026875D01*
X50650Y1026708D01*
X50733Y1026375D01*
X50650Y1026042D01*
X50400Y1025833D01*
X50108Y1025708D01*
X49067D01*
G01X50108D02*
X50733Y1024500D01*
G01X53000D02*
X53292Y1024542D01*
X53625Y1024667D01*
X53833Y1024875D01*
X53917Y1025167D01*
X53833Y1025458D01*
X53583Y1025708D01*
X53208Y1025833D01*
X52792D01*
X52542Y1025917D01*
X52333Y1026125D01*
X52250Y1026417D01*
X52375Y1026708D01*
X52667Y1026917D01*
X53000Y1027000D01*
X53333Y1026917D01*
X53625Y1026708D01*
X53750Y1026417D01*
X53667Y1026125D01*
X53458Y1025917D01*
X53208Y1025833D01*
X52792D01*
X52417Y1025708D01*
X52167Y1025458D01*
X52083Y1025167D01*
X52167Y1024875D01*
X52375Y1024667D01*
X52708Y1024542D01*
X53000Y1024500D01*
G01X56600D02*
Y1027000D01*
X55058Y1025208D01*
X57142D01*
G01X48567Y1019000D02*
Y1021500D01*
X49608D01*
X49942Y1021375D01*
X50150Y1021208D01*
X50233Y1020875D01*
X50150Y1020542D01*
X49900Y1020333D01*
X49608Y1020208D01*
X48567D01*
G01X49608D02*
X50233Y1019000D01*
G01X52500D02*
X52792Y1019042D01*
X53125Y1019167D01*
X53333Y1019375D01*
X53417Y1019667D01*
X53333Y1019958D01*
X53083Y1020208D01*
X52708Y1020333D01*
X52292D01*
X52042Y1020417D01*
X51833Y1020625D01*
X51750Y1020917D01*
X51875Y1021208D01*
X52167Y1021417D01*
X52500Y1021500D01*
X52833Y1021417D01*
X53125Y1021208D01*
X53250Y1020917D01*
X53167Y1020625D01*
X52958Y1020417D01*
X52708Y1020333D01*
X52292D01*
X51917Y1020208D01*
X51667Y1019958D01*
X51583Y1019667D01*
X51667Y1019375D01*
X51875Y1019167D01*
X52208Y1019042D01*
X52500Y1019000D01*
G01X55600D02*
X55892Y1019042D01*
X56225Y1019167D01*
X56433Y1019375D01*
X56517Y1019667D01*
X56433Y1019958D01*
X56183Y1020208D01*
X55808Y1020333D01*
X55392D01*
X55142Y1020417D01*
X54933Y1020625D01*
X54850Y1020917D01*
X54975Y1021208D01*
X55267Y1021417D01*
X55600Y1021500D01*
X55933Y1021417D01*
X56225Y1021208D01*
X56350Y1020917D01*
X56267Y1020625D01*
X56058Y1020417D01*
X55808Y1020333D01*
X55392D01*
X55017Y1020208D01*
X54767Y1019958D01*
X54683Y1019667D01*
X54767Y1019375D01*
X54975Y1019167D01*
X55308Y1019042D01*
X55600Y1019000D01*
G01X65000Y1018600D02*
Y1022600D01*
X57600D01*
G01X80067Y1023500D02*
Y1026000D01*
X81108D01*
X81442Y1025875D01*
X81650Y1025708D01*
X81733Y1025375D01*
X81650Y1025042D01*
X81400Y1024833D01*
X81108Y1024708D01*
X80067D01*
G01X81108D02*
X81733Y1023500D01*
G01X84000D02*
X84292Y1023542D01*
X84625Y1023667D01*
X84833Y1023875D01*
X84917Y1024167D01*
X84833Y1024458D01*
X84583Y1024708D01*
X84208Y1024833D01*
X83792D01*
X83542Y1024917D01*
X83333Y1025125D01*
X83250Y1025417D01*
X83375Y1025708D01*
X83667Y1025917D01*
X84000Y1026000D01*
X84333Y1025917D01*
X84625Y1025708D01*
X84750Y1025417D01*
X84667Y1025125D01*
X84458Y1024917D01*
X84208Y1024833D01*
X83792D01*
X83417Y1024708D01*
X83167Y1024458D01*
X83083Y1024167D01*
X83167Y1023875D01*
X83375Y1023667D01*
X83708Y1023542D01*
X84000Y1023500D01*
G01X87100Y1026000D02*
X86767Y1025917D01*
X86517Y1025708D01*
X86350Y1025458D01*
X86225Y1025125D01*
X86183Y1024750D01*
X86225Y1024375D01*
X86350Y1024042D01*
X86517Y1023792D01*
X86767Y1023583D01*
X87100Y1023500D01*
X87433Y1023583D01*
X87683Y1023792D01*
X87850Y1024042D01*
X87975Y1024375D01*
X88017Y1024750D01*
X87975Y1025125D01*
X87850Y1025458D01*
X87683Y1025708D01*
X87433Y1025917D01*
X87100Y1026000D01*
G01X77700Y1023400D02*
Y1027400D01*
X70300D01*
G01X80567Y1019000D02*
Y1021500D01*
X81608D01*
X81942Y1021375D01*
X82150Y1021208D01*
X82233Y1020875D01*
X82150Y1020542D01*
X81900Y1020333D01*
X81608Y1020208D01*
X80567D01*
G01X81608D02*
X82233Y1019000D01*
G01X84417D02*
X84500Y1019542D01*
X84625Y1020000D01*
X84792Y1020417D01*
X85000Y1020875D01*
X85333Y1021500D01*
X83667D01*
G01X87600Y1019000D02*
X87892Y1019042D01*
X88225Y1019167D01*
X88433Y1019375D01*
X88517Y1019667D01*
X88433Y1019958D01*
X88183Y1020208D01*
X87808Y1020333D01*
X87392D01*
X87142Y1020417D01*
X86933Y1020625D01*
X86850Y1020917D01*
X86975Y1021208D01*
X87267Y1021417D01*
X87600Y1021500D01*
X87933Y1021417D01*
X88225Y1021208D01*
X88350Y1020917D01*
X88267Y1020625D01*
X88058Y1020417D01*
X87808Y1020333D01*
X87392D01*
X87017Y1020208D01*
X86767Y1019958D01*
X86683Y1019667D01*
X86767Y1019375D01*
X86975Y1019167D01*
X87308Y1019042D01*
X87600Y1019000D01*
G01X77800Y1018900D02*
Y1022900D01*
X70400D01*
G01X52708Y1030817D02*
X52583Y1030567D01*
X52500Y1030275D01*
Y1029942D01*
X52625Y1029567D01*
X52833Y1029275D01*
X53083Y1029067D01*
X53500Y1028900D01*
X53875Y1028858D01*
X54250Y1028942D01*
X54500Y1029067D01*
X54750Y1029317D01*
X54917Y1029608D01*
X55000Y1029900D01*
Y1030192D01*
X54917Y1030483D01*
X54792Y1030733D01*
X54625Y1030942D01*
G01X54500Y1032083D02*
X54792Y1032333D01*
X54958Y1032667D01*
X55000Y1033042D01*
X54958Y1033375D01*
X54750Y1033708D01*
X54500Y1033917D01*
X54250Y1033958D01*
X53958Y1033875D01*
X53750Y1033583D01*
X53667Y1033292D01*
Y1032917D01*
G01Y1033292D02*
X53542Y1033542D01*
X53333Y1033750D01*
X53083Y1033833D01*
X52833Y1033750D01*
X52625Y1033542D01*
X52500Y1033167D01*
X52542Y1032792D01*
X52708Y1032417D01*
G01X54625Y1035183D02*
X54833Y1035433D01*
X54958Y1035725D01*
X55000Y1036100D01*
X54917Y1036475D01*
X54750Y1036767D01*
X54458Y1036975D01*
X54125Y1037017D01*
X53792Y1036933D01*
X53583Y1036725D01*
X53417Y1036433D01*
X53375Y1036142D01*
X53417Y1035850D01*
X53583Y1035475D01*
X52500Y1035600D01*
Y1036725D01*
G01X34617Y1014800D02*
Y1017300D01*
X35658D01*
X35992Y1017175D01*
X36200Y1017008D01*
X36283Y1016675D01*
X36200Y1016342D01*
X35950Y1016133D01*
X35658Y1016008D01*
X34617D01*
G01X35658D02*
X36283Y1014800D01*
G01X38550D02*
Y1017300D01*
X38050Y1016800D01*
G01Y1014800D02*
X39050D01*
G01X40858Y1016883D02*
X41108Y1017133D01*
X41400Y1017258D01*
X41733Y1017300D01*
X42150Y1017217D01*
X42442Y1017008D01*
X42525Y1016758D01*
X42483Y1016508D01*
X42317Y1016300D01*
X41483Y1015883D01*
X41108Y1015592D01*
X40858Y1015175D01*
X40775Y1014800D01*
X42525D01*
G01X43833Y1015175D02*
X44083Y1014967D01*
X44375Y1014842D01*
X44750Y1014800D01*
X45125Y1014883D01*
X45417Y1015050D01*
X45625Y1015342D01*
X45667Y1015675D01*
X45583Y1016008D01*
X45375Y1016217D01*
X45083Y1016383D01*
X44792Y1016425D01*
X44500Y1016383D01*
X44125Y1016217D01*
X44250Y1017300D01*
X45375D01*
G01X43000Y1019200D02*
X35000D01*
Y1036800D01*
X43000D01*
Y1019200D01*
G01X57700Y1061600D02*
X96500D01*
G01X74350Y1105000D02*
Y1102500D01*
G01X73392Y1105000D02*
X75308D01*
G01X78367Y1104792D02*
X78117Y1104917D01*
X77825Y1105000D01*
X77492D01*
X77117Y1104875D01*
X76825Y1104667D01*
X76617Y1104417D01*
X76450Y1104000D01*
X76408Y1103625D01*
X76492Y1103250D01*
X76617Y1103000D01*
X76867Y1102750D01*
X77158Y1102583D01*
X77450Y1102500D01*
X77742D01*
X78033Y1102583D01*
X78283Y1102708D01*
X78492Y1102875D01*
G01X80550Y1102500D02*
Y1105000D01*
X80050Y1104500D01*
G01Y1102500D02*
X81050D01*
G01X82858Y1103542D02*
X83150Y1103833D01*
X83400Y1104000D01*
X83733Y1104083D01*
X84025Y1104000D01*
X84233Y1103833D01*
X84400Y1103583D01*
X84442Y1103292D01*
X84400Y1103042D01*
X84233Y1102792D01*
X83983Y1102583D01*
X83692Y1102500D01*
X83358Y1102583D01*
X83067Y1102833D01*
X82900Y1103208D01*
X82858Y1103625D01*
X82942Y1104167D01*
X83067Y1104458D01*
X83275Y1104750D01*
X83567Y1104958D01*
X83858Y1105000D01*
X84150Y1104917D01*
X84358Y1104708D01*
G01X56900Y1099600D02*
X68100D01*
G01X56900Y1081600D02*
Y1099600D01*
G01X68100Y1081600D02*
X56900D01*
G01X36517Y1099500D02*
Y1102000D01*
X37558D01*
X37892Y1101875D01*
X38100Y1101708D01*
X38183Y1101375D01*
X38100Y1101042D01*
X37850Y1100833D01*
X37558Y1100708D01*
X36517D01*
G01X37558D02*
X38183Y1099500D01*
G01X40450D02*
Y1102000D01*
X39950Y1101500D01*
G01Y1099500D02*
X40950D01*
G01X43550D02*
Y1102000D01*
X43050Y1101500D01*
G01Y1099500D02*
X44050D01*
G01X46567D02*
X46650Y1100042D01*
X46775Y1100500D01*
X46942Y1100917D01*
X47150Y1101375D01*
X47483Y1102000D01*
X45817D01*
G01X43400Y1094000D02*
Y1098000D01*
X36000D01*
G01X37067Y1082000D02*
Y1084500D01*
X38108D01*
X38442Y1084375D01*
X38650Y1084208D01*
X38733Y1083875D01*
X38650Y1083542D01*
X38400Y1083333D01*
X38108Y1083208D01*
X37067D01*
G01X38108D02*
X38733Y1082000D01*
G01X40083Y1082500D02*
X40333Y1082208D01*
X40667Y1082042D01*
X41042Y1082000D01*
X41375Y1082042D01*
X41708Y1082250D01*
X41917Y1082500D01*
X41958Y1082750D01*
X41875Y1083042D01*
X41583Y1083250D01*
X41292Y1083333D01*
X40917D01*
G01X41292D02*
X41542Y1083458D01*
X41750Y1083667D01*
X41833Y1083917D01*
X41750Y1084167D01*
X41542Y1084375D01*
X41167Y1084500D01*
X40792Y1084458D01*
X40417Y1084292D01*
G01X44100Y1082000D02*
X44392Y1082042D01*
X44725Y1082167D01*
X44933Y1082375D01*
X45017Y1082667D01*
X44933Y1082958D01*
X44683Y1083208D01*
X44308Y1083333D01*
X43892D01*
X43642Y1083417D01*
X43433Y1083625D01*
X43350Y1083917D01*
X43475Y1084208D01*
X43767Y1084417D01*
X44100Y1084500D01*
X44433Y1084417D01*
X44725Y1084208D01*
X44850Y1083917D01*
X44767Y1083625D01*
X44558Y1083417D01*
X44308Y1083333D01*
X43892D01*
X43517Y1083208D01*
X43267Y1082958D01*
X43183Y1082667D01*
X43267Y1082375D01*
X43475Y1082167D01*
X43808Y1082042D01*
X44100Y1082000D01*
G01X35118Y1086583D02*
Y1099583D01*
G01X63200Y1065700D02*
X80800D01*
G01X63200Y1073700D02*
Y1065700D01*
G01X80800Y1073700D02*
X63200D01*
G01X68033Y1115500D02*
Y1118000D01*
X68867D01*
X69200Y1117875D01*
X69450Y1117708D01*
X69658Y1117458D01*
X69825Y1117167D01*
X69867Y1116750D01*
X69825Y1116333D01*
X69658Y1116042D01*
X69450Y1115792D01*
X69200Y1115625D01*
X68867Y1115500D01*
X68033D01*
G01X71342Y1115792D02*
X71633Y1115583D01*
X71967Y1115500D01*
X72300Y1115583D01*
X72592Y1115833D01*
X72800Y1116208D01*
X72883Y1116583D01*
Y1117042D01*
X72800Y1117417D01*
X72592Y1117750D01*
X72342Y1117917D01*
X72050Y1118000D01*
X71717Y1117917D01*
X71467Y1117750D01*
X71300Y1117500D01*
X71217Y1117167D01*
X71300Y1116875D01*
X71508Y1116583D01*
X71758Y1116417D01*
X72050Y1116375D01*
X72383Y1116458D01*
X72633Y1116667D01*
X72883Y1117042D01*
G01X74202Y1121197D02*
Y1142197D01*
G01D02*
X66202D01*
G01D02*
Y1121197D01*
G01D02*
X74202D01*
G01X81000Y1143567D02*
X78500D01*
Y1144608D01*
X78625Y1144942D01*
X78792Y1145150D01*
X79125Y1145233D01*
X79458Y1145150D01*
X79667Y1144900D01*
X79792Y1144608D01*
Y1143567D01*
G01Y1144608D02*
X81000Y1145233D01*
G01X80708Y1146792D02*
X80917Y1147083D01*
X81000Y1147417D01*
X80917Y1147750D01*
X80667Y1148042D01*
X80292Y1148250D01*
X79917Y1148333D01*
X79458D01*
X79083Y1148250D01*
X78750Y1148042D01*
X78583Y1147792D01*
X78500Y1147500D01*
X78583Y1147167D01*
X78750Y1146917D01*
X79000Y1146750D01*
X79333Y1146667D01*
X79625Y1146750D01*
X79917Y1146958D01*
X80083Y1147208D01*
X80125Y1147500D01*
X80042Y1147833D01*
X79833Y1148083D01*
X79458Y1148333D01*
G01X80708Y1149892D02*
X80917Y1150183D01*
X81000Y1150517D01*
X80917Y1150850D01*
X80667Y1151142D01*
X80292Y1151350D01*
X79917Y1151433D01*
X79458D01*
X79083Y1151350D01*
X78750Y1151142D01*
X78583Y1150892D01*
X78500Y1150600D01*
X78583Y1150267D01*
X78750Y1150017D01*
X79000Y1149850D01*
X79333Y1149767D01*
X79625Y1149850D01*
X79917Y1150058D01*
X80083Y1150308D01*
X80125Y1150600D01*
X80042Y1150933D01*
X79833Y1151183D01*
X79458Y1151433D01*
G01X59500Y1128567D02*
X57000D01*
Y1129608D01*
X57125Y1129942D01*
X57292Y1130150D01*
X57625Y1130233D01*
X57958Y1130150D01*
X58167Y1129900D01*
X58292Y1129608D01*
Y1128567D01*
G01Y1129608D02*
X59500Y1130233D01*
G01X59208Y1131792D02*
X59417Y1132083D01*
X59500Y1132417D01*
X59417Y1132750D01*
X59167Y1133042D01*
X58792Y1133250D01*
X58417Y1133333D01*
X57958D01*
X57583Y1133250D01*
X57250Y1133042D01*
X57083Y1132792D01*
X57000Y1132500D01*
X57083Y1132167D01*
X57250Y1131917D01*
X57500Y1131750D01*
X57833Y1131667D01*
X58125Y1131750D01*
X58417Y1131958D01*
X58583Y1132208D01*
X58625Y1132500D01*
X58542Y1132833D01*
X58333Y1133083D01*
X57958Y1133333D01*
G01X59500Y1135600D02*
X59458Y1135892D01*
X59333Y1136225D01*
X59125Y1136433D01*
X58833Y1136517D01*
X58542Y1136433D01*
X58292Y1136183D01*
X58167Y1135808D01*
Y1135392D01*
X58083Y1135142D01*
X57875Y1134933D01*
X57583Y1134850D01*
X57292Y1134975D01*
X57083Y1135267D01*
X57000Y1135600D01*
X57083Y1135933D01*
X57292Y1136225D01*
X57583Y1136350D01*
X57875Y1136267D01*
X58083Y1136058D01*
X58167Y1135808D01*
Y1135392D01*
X58292Y1135017D01*
X58542Y1134767D01*
X58833Y1134683D01*
X59125Y1134767D01*
X59333Y1134975D01*
X59458Y1135308D01*
X59500Y1135600D01*
G01X78500Y1120567D02*
X76000D01*
Y1121608D01*
X76125Y1121942D01*
X76292Y1122150D01*
X76625Y1122233D01*
X76958Y1122150D01*
X77167Y1121900D01*
X77292Y1121608D01*
Y1120567D01*
G01Y1121608D02*
X78500Y1122233D01*
G01X78208Y1123792D02*
X78417Y1124083D01*
X78500Y1124417D01*
X78417Y1124750D01*
X78167Y1125042D01*
X77792Y1125250D01*
X77417Y1125333D01*
X76958D01*
X76583Y1125250D01*
X76250Y1125042D01*
X76083Y1124792D01*
X76000Y1124500D01*
X76083Y1124167D01*
X76250Y1123917D01*
X76500Y1123750D01*
X76833Y1123667D01*
X77125Y1123750D01*
X77417Y1123958D01*
X77583Y1124208D01*
X77625Y1124500D01*
X77542Y1124833D01*
X77333Y1125083D01*
X76958Y1125333D01*
G01X78500Y1128100D02*
X76000D01*
X77792Y1126558D01*
Y1128642D01*
G01X79398Y1120703D02*
X83398D01*
Y1128103D01*
G01X59500Y1118567D02*
X57000D01*
Y1119608D01*
X57125Y1119942D01*
X57292Y1120150D01*
X57625Y1120233D01*
X57958Y1120150D01*
X58167Y1119900D01*
X58292Y1119608D01*
Y1118567D01*
G01Y1119608D02*
X59500Y1120233D01*
G01X59208Y1121792D02*
X59417Y1122083D01*
X59500Y1122417D01*
X59417Y1122750D01*
X59167Y1123042D01*
X58792Y1123250D01*
X58417Y1123333D01*
X57958D01*
X57583Y1123250D01*
X57250Y1123042D01*
X57083Y1122792D01*
X57000Y1122500D01*
X57083Y1122167D01*
X57250Y1121917D01*
X57500Y1121750D01*
X57833Y1121667D01*
X58125Y1121750D01*
X58417Y1121958D01*
X58583Y1122208D01*
X58625Y1122500D01*
X58542Y1122833D01*
X58333Y1123083D01*
X57958Y1123333D01*
G01X59000Y1124683D02*
X59292Y1124933D01*
X59458Y1125267D01*
X59500Y1125642D01*
X59458Y1125975D01*
X59250Y1126308D01*
X59000Y1126517D01*
X58750Y1126558D01*
X58458Y1126475D01*
X58250Y1126183D01*
X58167Y1125892D01*
Y1125517D01*
G01Y1125892D02*
X58042Y1126142D01*
X57833Y1126350D01*
X57583Y1126433D01*
X57333Y1126350D01*
X57125Y1126142D01*
X57000Y1125767D01*
X57042Y1125392D01*
X57208Y1125017D01*
G01X61498Y1118403D02*
X65498D01*
Y1125803D01*
G01X77000Y1143517D02*
X74500D01*
Y1144558D01*
X74625Y1144892D01*
X74792Y1145100D01*
X75125Y1145183D01*
X75458Y1145100D01*
X75667Y1144850D01*
X75792Y1144558D01*
Y1143517D01*
G01Y1144558D02*
X77000Y1145183D01*
G01Y1147450D02*
X74500D01*
X75000Y1146950D01*
G01X77000D02*
Y1147950D01*
G01X74500Y1150550D02*
X74583Y1150217D01*
X74792Y1149967D01*
X75042Y1149800D01*
X75375Y1149675D01*
X75750Y1149633D01*
X76125Y1149675D01*
X76458Y1149800D01*
X76708Y1149967D01*
X76917Y1150217D01*
X77000Y1150550D01*
X76917Y1150883D01*
X76708Y1151133D01*
X76458Y1151300D01*
X76125Y1151425D01*
X75750Y1151467D01*
X75375Y1151425D01*
X75042Y1151300D01*
X74792Y1151133D01*
X74583Y1150883D01*
X74500Y1150550D01*
G01X76500Y1152733D02*
X76792Y1152983D01*
X76958Y1153317D01*
X77000Y1153692D01*
X76958Y1154025D01*
X76750Y1154358D01*
X76500Y1154567D01*
X76250Y1154608D01*
X75958Y1154525D01*
X75750Y1154233D01*
X75667Y1153942D01*
Y1153567D01*
G01Y1153942D02*
X75542Y1154192D01*
X75333Y1154400D01*
X75083Y1154483D01*
X74833Y1154400D01*
X74625Y1154192D01*
X74500Y1153817D01*
X74542Y1153442D01*
X74708Y1153067D01*
G01X79002Y1139897D02*
X75002D01*
Y1132497D01*
G01X59500Y1138517D02*
X57000D01*
Y1139558D01*
X57125Y1139892D01*
X57292Y1140100D01*
X57625Y1140183D01*
X57958Y1140100D01*
X58167Y1139850D01*
X58292Y1139558D01*
Y1138517D01*
G01Y1139558D02*
X59500Y1140183D01*
G01Y1142450D02*
X57000D01*
X57500Y1141950D01*
G01X59500D02*
Y1142950D01*
G01X57000Y1145550D02*
X57083Y1145217D01*
X57292Y1144967D01*
X57542Y1144800D01*
X57875Y1144675D01*
X58250Y1144633D01*
X58625Y1144675D01*
X58958Y1144800D01*
X59208Y1144967D01*
X59417Y1145217D01*
X59500Y1145550D01*
X59417Y1145883D01*
X59208Y1146133D01*
X58958Y1146300D01*
X58625Y1146425D01*
X58250Y1146467D01*
X57875Y1146425D01*
X57542Y1146300D01*
X57292Y1146133D01*
X57083Y1145883D01*
X57000Y1145550D01*
G01X57417Y1147858D02*
X57167Y1148108D01*
X57042Y1148400D01*
X57000Y1148733D01*
X57083Y1149150D01*
X57292Y1149442D01*
X57542Y1149525D01*
X57792Y1149483D01*
X58000Y1149317D01*
X58417Y1148483D01*
X58708Y1148108D01*
X59125Y1147858D01*
X59500Y1147775D01*
Y1149525D01*
G01X61198Y1136603D02*
X65198D01*
Y1144003D01*
G01X66317Y1149792D02*
X66067Y1149917D01*
X65775Y1150000D01*
X65442D01*
X65067Y1149875D01*
X64775Y1149667D01*
X64567Y1149417D01*
X64400Y1149000D01*
X64358Y1148625D01*
X64442Y1148250D01*
X64567Y1148000D01*
X64817Y1147750D01*
X65108Y1147583D01*
X65400Y1147500D01*
X65692D01*
X65983Y1147583D01*
X66233Y1147708D01*
X66442Y1147875D01*
G01X69000Y1147500D02*
Y1150000D01*
X67458Y1148208D01*
X69542D01*
G01X70683Y1148000D02*
X70933Y1147708D01*
X71267Y1147542D01*
X71642Y1147500D01*
X71975Y1147542D01*
X72308Y1147750D01*
X72517Y1148000D01*
X72558Y1148250D01*
X72475Y1148542D01*
X72183Y1148750D01*
X71892Y1148833D01*
X71517D01*
G01X71892D02*
X72142Y1148958D01*
X72350Y1149167D01*
X72433Y1149417D01*
X72350Y1149667D01*
X72142Y1149875D01*
X71767Y1150000D01*
X71392Y1149958D01*
X71017Y1149792D01*
G01X76567Y1174000D02*
Y1176500D01*
X77608D01*
X77942Y1176375D01*
X78150Y1176208D01*
X78233Y1175875D01*
X78150Y1175542D01*
X77900Y1175333D01*
X77608Y1175208D01*
X76567D01*
G01X77608D02*
X78233Y1174000D01*
G01X79792Y1174292D02*
X80083Y1174083D01*
X80417Y1174000D01*
X80750Y1174083D01*
X81042Y1174333D01*
X81250Y1174708D01*
X81333Y1175083D01*
Y1175542D01*
X81250Y1175917D01*
X81042Y1176250D01*
X80792Y1176417D01*
X80500Y1176500D01*
X80167Y1176417D01*
X79917Y1176250D01*
X79750Y1176000D01*
X79667Y1175667D01*
X79750Y1175375D01*
X79958Y1175083D01*
X80208Y1174917D01*
X80500Y1174875D01*
X80833Y1174958D01*
X81083Y1175167D01*
X81333Y1175542D01*
G01X82808Y1176083D02*
X83058Y1176333D01*
X83350Y1176458D01*
X83683Y1176500D01*
X84100Y1176417D01*
X84392Y1176208D01*
X84475Y1175958D01*
X84433Y1175708D01*
X84267Y1175500D01*
X83433Y1175083D01*
X83058Y1174792D01*
X82808Y1174375D01*
X82725Y1174000D01*
X84475D01*
G01X74200Y1173100D02*
Y1177100D01*
X66800D01*
G01X32208Y1203817D02*
X32083Y1203567D01*
X32000Y1203275D01*
Y1202942D01*
X32125Y1202567D01*
X32333Y1202275D01*
X32583Y1202067D01*
X33000Y1201900D01*
X33375Y1201858D01*
X33750Y1201942D01*
X34000Y1202067D01*
X34250Y1202317D01*
X34417Y1202608D01*
X34500Y1202900D01*
Y1203192D01*
X34417Y1203483D01*
X34292Y1203733D01*
X34125Y1203942D01*
G01X34500Y1205042D02*
X32000D01*
X34500Y1206958D01*
X32000D01*
G01X34000Y1208183D02*
X34292Y1208433D01*
X34458Y1208767D01*
X34500Y1209142D01*
X34458Y1209475D01*
X34250Y1209808D01*
X34000Y1210017D01*
X33750Y1210058D01*
X33458Y1209975D01*
X33250Y1209683D01*
X33167Y1209392D01*
Y1209017D01*
G01Y1209392D02*
X33042Y1209642D01*
X32833Y1209850D01*
X32583Y1209933D01*
X32333Y1209850D01*
X32125Y1209642D01*
X32000Y1209267D01*
X32042Y1208892D01*
X32208Y1208517D01*
G01X75000Y1279800D02*
X70000D01*
X73583Y1276717D01*
Y1280883D01*
G01X75000Y1284400D02*
X74917Y1284983D01*
X74667Y1285650D01*
X74250Y1286067D01*
X73667Y1286233D01*
X73083Y1286067D01*
X72583Y1285567D01*
X72333Y1284817D01*
Y1283983D01*
X72167Y1283483D01*
X71750Y1283067D01*
X71167Y1282900D01*
X70583Y1283150D01*
X70167Y1283733D01*
X70000Y1284400D01*
X70167Y1285067D01*
X70583Y1285650D01*
X71167Y1285900D01*
X71750Y1285733D01*
X72167Y1285317D01*
X72333Y1284817D01*
Y1283983D01*
X72583Y1283233D01*
X73083Y1282733D01*
X73667Y1282567D01*
X74250Y1282733D01*
X74667Y1283150D01*
X74917Y1283817D01*
X75000Y1284400D01*
G01X75167Y1290000D02*
X75083Y1289833D01*
X74917D01*
X74833Y1290000D01*
X74917Y1290167D01*
X75083D01*
X75167Y1290000D01*
G01X72917Y1294017D02*
X72333Y1294600D01*
X72000Y1295100D01*
X71833Y1295767D01*
X72000Y1296350D01*
X72333Y1296767D01*
X72833Y1297100D01*
X73417Y1297183D01*
X73917Y1297100D01*
X74417Y1296767D01*
X74833Y1296267D01*
X75000Y1295683D01*
X74833Y1295017D01*
X74333Y1294433D01*
X73583Y1294100D01*
X72750Y1294017D01*
X71667Y1294183D01*
X71083Y1294433D01*
X70500Y1294850D01*
X70083Y1295433D01*
X70000Y1296017D01*
X70167Y1296600D01*
X70583Y1297017D01*
G01X75000Y1302200D02*
X70000D01*
X73583Y1299117D01*
Y1303283D01*
G01X70000Y1304300D02*
X75000Y1305467D01*
X70000Y1306800D01*
X75000Y1308133D01*
X70000Y1309300D01*
G01Y1312400D02*
X70167Y1311733D01*
X70583Y1311233D01*
X71083Y1310900D01*
X71750Y1310650D01*
X72500Y1310567D01*
X73250Y1310650D01*
X73917Y1310900D01*
X74417Y1311233D01*
X74833Y1311733D01*
X75000Y1312400D01*
X74833Y1313067D01*
X74417Y1313567D01*
X73917Y1313900D01*
X73250Y1314150D01*
X72500Y1314233D01*
X71750Y1314150D01*
X71083Y1313900D01*
X70583Y1313567D01*
X70167Y1313067D01*
X70000Y1312400D01*
G01X75000Y1319000D02*
X70000D01*
X73583Y1315917D01*
Y1320083D01*
G01X75167Y1323600D02*
X75083Y1323433D01*
X74917D01*
X74833Y1323600D01*
X74917Y1323767D01*
X75083D01*
X75167Y1323600D01*
G01X70000Y1329200D02*
X70167Y1328533D01*
X70583Y1328033D01*
X71083Y1327700D01*
X71750Y1327450D01*
X72500Y1327367D01*
X73250Y1327450D01*
X73917Y1327700D01*
X74417Y1328033D01*
X74833Y1328533D01*
X75000Y1329200D01*
X74833Y1329867D01*
X74417Y1330367D01*
X73917Y1330700D01*
X73250Y1330950D01*
X72500Y1331033D01*
X71750Y1330950D01*
X71083Y1330700D01*
X70583Y1330367D01*
X70167Y1329867D01*
X70000Y1329200D01*
G01X75000Y1334800D02*
X70000D01*
X71000Y1333800D01*
G01X75000D02*
Y1335800D01*
G01Y1338233D02*
X70000D01*
X74167Y1340400D01*
X70000Y1342567D01*
X75000D01*
G01X52500Y1277467D02*
X47500D01*
G01Y1280633D02*
X50583Y1277467D01*
G01X52500Y1281133D02*
X49167Y1278883D01*
G01X52500Y1282983D02*
X47500D01*
X52500Y1286817D01*
X47500D01*
G01X52500Y1290500D02*
X52417Y1289833D01*
X52083Y1289250D01*
X51583Y1288750D01*
X51000Y1288417D01*
X50333Y1288250D01*
X49667D01*
X49000Y1288417D01*
X48417Y1288750D01*
X47917Y1289250D01*
X47583Y1289833D01*
X47500Y1290500D01*
X47583Y1291167D01*
X47917Y1291750D01*
X48417Y1292250D01*
X49000Y1292583D01*
X49667Y1292750D01*
X50333D01*
X51000Y1292583D01*
X51583Y1292250D01*
X52083Y1291750D01*
X52417Y1291167D01*
X52500Y1290500D01*
G01Y1294350D02*
X47500Y1297850D01*
G01Y1294350D02*
X52500Y1297850D01*
G01X54167Y1299200D02*
Y1304200D01*
G01X52500Y1305717D02*
X47500D01*
Y1308883D01*
G01X49917Y1307717D02*
Y1305717D01*
G01X52500Y1310817D02*
X47500Y1312900D01*
X52500Y1314983D01*
G01X50750Y1314233D02*
Y1311567D01*
G01X52500Y1316583D02*
X47500D01*
X52500Y1320417D01*
X47500D01*
G01X47917Y1331533D02*
X47667Y1331033D01*
X47500Y1330450D01*
Y1329783D01*
X47750Y1329033D01*
X48167Y1328450D01*
X48667Y1328033D01*
X49500Y1327700D01*
X50250Y1327617D01*
X51000Y1327783D01*
X51500Y1328033D01*
X52000Y1328533D01*
X52333Y1329117D01*
X52500Y1329700D01*
Y1330283D01*
X52333Y1330867D01*
X52083Y1331367D01*
X51750Y1331783D01*
G01X52500Y1335300D02*
X52417Y1334633D01*
X52083Y1334050D01*
X51583Y1333550D01*
X51000Y1333217D01*
X50333Y1333050D01*
X49667D01*
X49000Y1333217D01*
X48417Y1333550D01*
X47917Y1334050D01*
X47583Y1334633D01*
X47500Y1335300D01*
X47583Y1335967D01*
X47917Y1336550D01*
X48417Y1337050D01*
X49000Y1337383D01*
X49667Y1337550D01*
X50333D01*
X51000Y1337383D01*
X51583Y1337050D01*
X52083Y1336550D01*
X52417Y1335967D01*
X52500Y1335300D01*
G01Y1338983D02*
X47500D01*
X52500Y1342817D01*
X47500D01*
G01Y1346500D02*
X52500D01*
G01X47500Y1344583D02*
Y1348417D01*
G01X52500Y1350433D02*
X47500D01*
Y1352517D01*
X47750Y1353183D01*
X48083Y1353600D01*
X48750Y1353767D01*
X49417Y1353600D01*
X49833Y1353100D01*
X50083Y1352517D01*
Y1350433D01*
G01Y1352517D02*
X52500Y1353767D01*
G01Y1357700D02*
X52417Y1357033D01*
X52083Y1356450D01*
X51583Y1355950D01*
X51000Y1355617D01*
X50333Y1355450D01*
X49667D01*
X49000Y1355617D01*
X48417Y1355950D01*
X47917Y1356450D01*
X47583Y1357033D01*
X47500Y1357700D01*
X47583Y1358367D01*
X47917Y1358950D01*
X48417Y1359450D01*
X49000Y1359783D01*
X49667Y1359950D01*
X50333D01*
X51000Y1359783D01*
X51583Y1359450D01*
X52083Y1358950D01*
X52417Y1358367D01*
X52500Y1357700D01*
G01X47500Y1361633D02*
X52500D01*
Y1364967D01*
G01X49833Y1375167D02*
X49583Y1375500D01*
X49167Y1375750D01*
X48583Y1375917D01*
X48083Y1375750D01*
X47750Y1375417D01*
X47500Y1374833D01*
Y1372583D01*
X52500D01*
Y1375333D01*
X52167Y1375917D01*
X51667Y1376250D01*
X51083Y1376417D01*
X50500Y1376250D01*
X50000Y1375750D01*
X49833Y1375167D01*
Y1372583D01*
G01X52500Y1380100D02*
X52417Y1379433D01*
X52083Y1378850D01*
X51583Y1378350D01*
X51000Y1378017D01*
X50333Y1377850D01*
X49667D01*
X49000Y1378017D01*
X48417Y1378350D01*
X47917Y1378850D01*
X47583Y1379433D01*
X47500Y1380100D01*
X47583Y1380767D01*
X47917Y1381350D01*
X48417Y1381850D01*
X49000Y1382183D01*
X49667Y1382350D01*
X50333D01*
X51000Y1382183D01*
X51583Y1381850D01*
X52083Y1381350D01*
X52417Y1380767D01*
X52500Y1380100D01*
G01Y1383617D02*
X47500Y1385700D01*
X52500Y1387783D01*
G01X50750Y1387033D02*
Y1384367D01*
G01X52500Y1389633D02*
X47500D01*
Y1391717D01*
X47750Y1392383D01*
X48083Y1392800D01*
X48750Y1392967D01*
X49417Y1392800D01*
X49833Y1392300D01*
X50083Y1391717D01*
Y1389633D01*
G01Y1391717D02*
X52500Y1392967D01*
G01Y1395067D02*
X47500D01*
Y1396733D01*
X47750Y1397400D01*
X48083Y1397900D01*
X48583Y1398317D01*
X49167Y1398650D01*
X50000Y1398733D01*
X50833Y1398650D01*
X51417Y1398317D01*
X51917Y1397900D01*
X52250Y1397400D01*
X52500Y1396733D01*
Y1395067D01*
G01X64500Y1278300D02*
X59500D01*
X60500Y1277300D01*
G01X64500D02*
Y1279300D01*
G01X60333Y1282317D02*
X59833Y1282817D01*
X59583Y1283400D01*
X59500Y1284067D01*
X59667Y1284900D01*
X60083Y1285483D01*
X60583Y1285650D01*
X61083Y1285567D01*
X61500Y1285233D01*
X62333Y1283567D01*
X62917Y1282817D01*
X63750Y1282317D01*
X64500Y1282150D01*
Y1285650D01*
G01Y1290500D02*
X59500D01*
X63083Y1287417D01*
Y1291583D01*
G01X63500Y1293267D02*
X64083Y1293767D01*
X64417Y1294433D01*
X64500Y1295183D01*
X64417Y1295850D01*
X64000Y1296517D01*
X63500Y1296933D01*
X63000Y1297017D01*
X62417Y1296850D01*
X62000Y1296267D01*
X61833Y1295683D01*
Y1294933D01*
G01Y1295683D02*
X61583Y1296183D01*
X61167Y1296600D01*
X60667Y1296767D01*
X60167Y1296600D01*
X59750Y1296183D01*
X59500Y1295433D01*
X59583Y1294683D01*
X59917Y1293933D01*
G01X63500Y1298867D02*
X64083Y1299367D01*
X64417Y1300033D01*
X64500Y1300783D01*
X64417Y1301450D01*
X64000Y1302117D01*
X63500Y1302533D01*
X63000Y1302617D01*
X62417Y1302450D01*
X62000Y1301867D01*
X61833Y1301283D01*
Y1300533D01*
G01Y1301283D02*
X61583Y1301783D01*
X61167Y1302200D01*
X60667Y1302367D01*
X60167Y1302200D01*
X59750Y1301783D01*
X59500Y1301033D01*
X59583Y1300283D01*
X59917Y1299533D01*
G01X62833Y1305217D02*
Y1307383D01*
G01X64500Y1311900D02*
X59500D01*
X60500Y1310900D01*
G01X64500D02*
Y1312900D01*
G01Y1315333D02*
X59500D01*
X63667Y1317500D01*
X59500Y1319667D01*
X64500D01*
G01X75500Y1414567D02*
X73000D01*
Y1415567D01*
X73125Y1415900D01*
X73417Y1416150D01*
X73750Y1416233D01*
X74083Y1416150D01*
X74333Y1415942D01*
X74458Y1415567D01*
Y1414567D01*
G01X75500Y1417667D02*
X73000D01*
Y1418708D01*
X73125Y1419042D01*
X73292Y1419250D01*
X73625Y1419333D01*
X73958Y1419250D01*
X74167Y1419000D01*
X74292Y1418708D01*
Y1417667D01*
G01Y1418708D02*
X75500Y1419333D01*
G01X75125Y1420683D02*
X75333Y1420933D01*
X75458Y1421225D01*
X75500Y1421600D01*
X75417Y1421975D01*
X75250Y1422267D01*
X74958Y1422475D01*
X74625Y1422517D01*
X74292Y1422433D01*
X74083Y1422225D01*
X73917Y1421933D01*
X73875Y1421642D01*
X73917Y1421350D01*
X74083Y1420975D01*
X73000Y1421100D01*
Y1422225D01*
G01X79500Y1414567D02*
X77000D01*
Y1415567D01*
X77125Y1415900D01*
X77417Y1416150D01*
X77750Y1416233D01*
X78083Y1416150D01*
X78333Y1415942D01*
X78458Y1415567D01*
Y1414567D01*
G01X79500Y1417667D02*
X77000D01*
Y1418708D01*
X77125Y1419042D01*
X77292Y1419250D01*
X77625Y1419333D01*
X77958Y1419250D01*
X78167Y1419000D01*
X78292Y1418708D01*
Y1417667D01*
G01Y1418708D02*
X79500Y1419333D01*
G01Y1421600D02*
X77000D01*
X77500Y1421100D01*
G01X79500D02*
Y1422100D01*
G01Y1424700D02*
X77000D01*
X77500Y1424200D01*
G01X79500D02*
Y1425200D01*
G01X71817Y1407200D02*
Y1409700D01*
X72858D01*
X73192Y1409575D01*
X73400Y1409408D01*
X73483Y1409075D01*
X73400Y1408742D01*
X73150Y1408533D01*
X72858Y1408408D01*
X71817D01*
G01X72858D02*
X73483Y1407200D01*
G01X74833Y1407700D02*
X75083Y1407408D01*
X75417Y1407242D01*
X75792Y1407200D01*
X76125Y1407242D01*
X76458Y1407450D01*
X76667Y1407700D01*
X76708Y1407950D01*
X76625Y1408242D01*
X76333Y1408450D01*
X76042Y1408533D01*
X75667D01*
G01X76042D02*
X76292Y1408658D01*
X76500Y1408867D01*
X76583Y1409117D01*
X76500Y1409367D01*
X76292Y1409575D01*
X75917Y1409700D01*
X75542Y1409658D01*
X75167Y1409492D01*
G01X78058Y1408242D02*
X78350Y1408533D01*
X78600Y1408700D01*
X78933Y1408783D01*
X79225Y1408700D01*
X79433Y1408533D01*
X79600Y1408283D01*
X79642Y1407992D01*
X79600Y1407742D01*
X79433Y1407492D01*
X79183Y1407283D01*
X78892Y1407200D01*
X78558Y1407283D01*
X78267Y1407533D01*
X78100Y1407908D01*
X78058Y1408325D01*
X78142Y1408867D01*
X78267Y1409158D01*
X78475Y1409450D01*
X78767Y1409658D01*
X79058Y1409700D01*
X79350Y1409617D01*
X79558Y1409408D01*
G01X81867Y1407200D02*
X81950Y1407742D01*
X82075Y1408200D01*
X82242Y1408617D01*
X82450Y1409075D01*
X82783Y1409700D01*
X81117D01*
G01X78100Y1458967D02*
X75600D01*
Y1459967D01*
X75725Y1460300D01*
X76017Y1460550D01*
X76350Y1460633D01*
X76683Y1460550D01*
X76933Y1460342D01*
X77058Y1459967D01*
Y1458967D01*
G01X75808Y1463817D02*
X75683Y1463567D01*
X75600Y1463275D01*
Y1462942D01*
X75725Y1462567D01*
X75933Y1462275D01*
X76183Y1462067D01*
X76600Y1461900D01*
X76975Y1461858D01*
X77350Y1461942D01*
X77600Y1462067D01*
X77850Y1462317D01*
X78017Y1462608D01*
X78100Y1462900D01*
Y1463192D01*
X78017Y1463483D01*
X77892Y1463733D01*
X77725Y1463942D01*
G01X77808Y1465292D02*
X78017Y1465583D01*
X78100Y1465917D01*
X78017Y1466250D01*
X77767Y1466542D01*
X77392Y1466750D01*
X77017Y1466833D01*
X76558D01*
X76183Y1466750D01*
X75850Y1466542D01*
X75683Y1466292D01*
X75600Y1466000D01*
X75683Y1465667D01*
X75850Y1465417D01*
X76100Y1465250D01*
X76433Y1465167D01*
X76725Y1465250D01*
X77017Y1465458D01*
X77183Y1465708D01*
X77225Y1466000D01*
X77142Y1466333D01*
X76933Y1466583D01*
X76558Y1466833D01*
G01X72567Y1453900D02*
Y1456400D01*
X73567D01*
X73900Y1456275D01*
X74150Y1455983D01*
X74233Y1455650D01*
X74150Y1455317D01*
X73942Y1455067D01*
X73567Y1454942D01*
X72567D01*
G01X77417Y1456192D02*
X77167Y1456317D01*
X76875Y1456400D01*
X76542D01*
X76167Y1456275D01*
X75875Y1456067D01*
X75667Y1455817D01*
X75500Y1455400D01*
X75458Y1455025D01*
X75542Y1454650D01*
X75667Y1454400D01*
X75917Y1454150D01*
X76208Y1453983D01*
X76500Y1453900D01*
X76792D01*
X77083Y1453983D01*
X77333Y1454108D01*
X77542Y1454275D01*
G01X80100Y1453900D02*
Y1456400D01*
X78558Y1454608D01*
X80642D01*
G01X72017Y1449400D02*
Y1451900D01*
X73017D01*
X73350Y1451775D01*
X73600Y1451483D01*
X73683Y1451150D01*
X73600Y1450817D01*
X73392Y1450567D01*
X73017Y1450442D01*
X72017D01*
G01X75117Y1449400D02*
Y1451900D01*
X76158D01*
X76492Y1451775D01*
X76700Y1451608D01*
X76783Y1451275D01*
X76700Y1450942D01*
X76450Y1450733D01*
X76158Y1450608D01*
X75117D01*
G01X76158D02*
X76783Y1449400D01*
G01X78133Y1449900D02*
X78383Y1449608D01*
X78717Y1449442D01*
X79092Y1449400D01*
X79425Y1449442D01*
X79758Y1449650D01*
X79967Y1449900D01*
X80008Y1450150D01*
X79925Y1450442D01*
X79633Y1450650D01*
X79342Y1450733D01*
X78967D01*
G01X79342D02*
X79592Y1450858D01*
X79800Y1451067D01*
X79883Y1451317D01*
X79800Y1451567D01*
X79592Y1451775D01*
X79217Y1451900D01*
X78842Y1451858D01*
X78467Y1451692D01*
G01X81233Y1449775D02*
X81483Y1449567D01*
X81775Y1449442D01*
X82150Y1449400D01*
X82525Y1449483D01*
X82817Y1449650D01*
X83025Y1449942D01*
X83067Y1450275D01*
X82983Y1450608D01*
X82775Y1450817D01*
X82483Y1450983D01*
X82192Y1451025D01*
X81900Y1450983D01*
X81525Y1450817D01*
X81650Y1451900D01*
X82775D01*
G01X74200Y1458917D02*
X71700D01*
Y1459917D01*
X71825Y1460250D01*
X72117Y1460500D01*
X72450Y1460583D01*
X72783Y1460500D01*
X73033Y1460292D01*
X73158Y1459917D01*
Y1458917D01*
G01X74200Y1462017D02*
X71700D01*
Y1463058D01*
X71825Y1463392D01*
X71992Y1463600D01*
X72325Y1463683D01*
X72658Y1463600D01*
X72867Y1463350D01*
X72992Y1463058D01*
Y1462017D01*
G01Y1463058D02*
X74200Y1463683D01*
G01X73700Y1465033D02*
X73992Y1465283D01*
X74158Y1465617D01*
X74200Y1465992D01*
X74158Y1466325D01*
X73950Y1466658D01*
X73700Y1466867D01*
X73450Y1466908D01*
X73158Y1466825D01*
X72950Y1466533D01*
X72867Y1466242D01*
Y1465867D01*
G01Y1466242D02*
X72742Y1466492D01*
X72533Y1466700D01*
X72283Y1466783D01*
X72033Y1466700D01*
X71825Y1466492D01*
X71700Y1466117D01*
X71742Y1465742D01*
X71908Y1465367D01*
G01X73700Y1468133D02*
X73992Y1468383D01*
X74158Y1468717D01*
X74200Y1469092D01*
X74158Y1469425D01*
X73950Y1469758D01*
X73700Y1469967D01*
X73450Y1470008D01*
X73158Y1469925D01*
X72950Y1469633D01*
X72867Y1469342D01*
Y1468967D01*
G01Y1469342D02*
X72742Y1469592D01*
X72533Y1469800D01*
X72283Y1469883D01*
X72033Y1469800D01*
X71825Y1469592D01*
X71700Y1469217D01*
X71742Y1468842D01*
X71908Y1468467D01*
G01X75267Y1444800D02*
Y1447300D01*
X76267D01*
X76600Y1447175D01*
X76850Y1446883D01*
X76933Y1446550D01*
X76850Y1446217D01*
X76642Y1445967D01*
X76267Y1445842D01*
X75267D01*
G01X78367Y1444800D02*
Y1447300D01*
X79408D01*
X79742Y1447175D01*
X79950Y1447008D01*
X80033Y1446675D01*
X79950Y1446342D01*
X79700Y1446133D01*
X79408Y1446008D01*
X78367D01*
G01X79408D02*
X80033Y1444800D01*
G01X81383Y1445300D02*
X81633Y1445008D01*
X81967Y1444842D01*
X82342Y1444800D01*
X82675Y1444842D01*
X83008Y1445050D01*
X83217Y1445300D01*
X83258Y1445550D01*
X83175Y1445842D01*
X82883Y1446050D01*
X82592Y1446133D01*
X82217D01*
G01X82592D02*
X82842Y1446258D01*
X83050Y1446467D01*
X83133Y1446717D01*
X83050Y1446967D01*
X82842Y1447175D01*
X82467Y1447300D01*
X82092Y1447258D01*
X81717Y1447092D01*
G01X75267Y1437300D02*
Y1439800D01*
X76267D01*
X76600Y1439675D01*
X76850Y1439383D01*
X76933Y1439050D01*
X76850Y1438717D01*
X76642Y1438467D01*
X76267Y1438342D01*
X75267D01*
G01X78367Y1437300D02*
Y1439800D01*
X79408D01*
X79742Y1439675D01*
X79950Y1439508D01*
X80033Y1439175D01*
X79950Y1438842D01*
X79700Y1438633D01*
X79408Y1438508D01*
X78367D01*
G01X79408D02*
X80033Y1437300D01*
G01X82300D02*
Y1439800D01*
X81800Y1439300D01*
G01Y1437300D02*
X82800D01*
G01X75467Y1429700D02*
Y1432200D01*
X76467D01*
X76800Y1432075D01*
X77050Y1431783D01*
X77133Y1431450D01*
X77050Y1431117D01*
X76842Y1430867D01*
X76467Y1430742D01*
X75467D01*
G01X80317Y1431992D02*
X80067Y1432117D01*
X79775Y1432200D01*
X79442D01*
X79067Y1432075D01*
X78775Y1431867D01*
X78567Y1431617D01*
X78400Y1431200D01*
X78358Y1430825D01*
X78442Y1430450D01*
X78567Y1430200D01*
X78817Y1429950D01*
X79108Y1429783D01*
X79400Y1429700D01*
X79692D01*
X79983Y1429783D01*
X80233Y1429908D01*
X80442Y1430075D01*
G01X81583D02*
X81833Y1429867D01*
X82125Y1429742D01*
X82500Y1429700D01*
X82875Y1429783D01*
X83167Y1429950D01*
X83375Y1430242D01*
X83417Y1430575D01*
X83333Y1430908D01*
X83125Y1431117D01*
X82833Y1431283D01*
X82542Y1431325D01*
X82250Y1431283D01*
X81875Y1431117D01*
X82000Y1432200D01*
X83125D01*
G01X75267Y1433200D02*
Y1435700D01*
X76267D01*
X76600Y1435575D01*
X76850Y1435283D01*
X76933Y1434950D01*
X76850Y1434617D01*
X76642Y1434367D01*
X76267Y1434242D01*
X75267D01*
G01X80117Y1435492D02*
X79867Y1435617D01*
X79575Y1435700D01*
X79242D01*
X78867Y1435575D01*
X78575Y1435367D01*
X78367Y1435117D01*
X78200Y1434700D01*
X78158Y1434325D01*
X78242Y1433950D01*
X78367Y1433700D01*
X78617Y1433450D01*
X78908Y1433283D01*
X79200Y1433200D01*
X79492D01*
X79783Y1433283D01*
X80033Y1433408D01*
X80242Y1433575D01*
G01X81383Y1433700D02*
X81633Y1433408D01*
X81967Y1433242D01*
X82342Y1433200D01*
X82675Y1433242D01*
X83008Y1433450D01*
X83217Y1433700D01*
X83258Y1433950D01*
X83175Y1434242D01*
X82883Y1434450D01*
X82592Y1434533D01*
X82217D01*
G01X82592D02*
X82842Y1434658D01*
X83050Y1434867D01*
X83133Y1435117D01*
X83050Y1435367D01*
X82842Y1435575D01*
X82467Y1435700D01*
X82092Y1435658D01*
X81717Y1435492D01*
G01X76817Y1443492D02*
X76567Y1443617D01*
X76275Y1443700D01*
X75942D01*
X75567Y1443575D01*
X75275Y1443367D01*
X75067Y1443117D01*
X74900Y1442700D01*
X74858Y1442325D01*
X74942Y1441950D01*
X75067Y1441700D01*
X75317Y1441450D01*
X75608Y1441283D01*
X75900Y1441200D01*
X76192D01*
X76483Y1441283D01*
X76733Y1441408D01*
X76942Y1441575D01*
G01X78083D02*
X78333Y1441367D01*
X78625Y1441242D01*
X79000Y1441200D01*
X79375Y1441283D01*
X79667Y1441450D01*
X79875Y1441742D01*
X79917Y1442075D01*
X79833Y1442408D01*
X79625Y1442617D01*
X79333Y1442783D01*
X79042Y1442825D01*
X78750Y1442783D01*
X78375Y1442617D01*
X78500Y1443700D01*
X79625D01*
G01X82100Y1441200D02*
X82392Y1441242D01*
X82725Y1441367D01*
X82933Y1441575D01*
X83017Y1441867D01*
X82933Y1442158D01*
X82683Y1442408D01*
X82308Y1442533D01*
X81892D01*
X81642Y1442617D01*
X81433Y1442825D01*
X81350Y1443117D01*
X81475Y1443408D01*
X81767Y1443617D01*
X82100Y1443700D01*
X82433Y1443617D01*
X82725Y1443408D01*
X82850Y1443117D01*
X82767Y1442825D01*
X82558Y1442617D01*
X82308Y1442533D01*
X81892D01*
X81517Y1442408D01*
X81267Y1442158D01*
X81183Y1441867D01*
X81267Y1441575D01*
X81475Y1441367D01*
X81808Y1441242D01*
X82100Y1441200D01*
G01X31208Y1460817D02*
X31083Y1460567D01*
X31000Y1460275D01*
Y1459942D01*
X31125Y1459567D01*
X31333Y1459275D01*
X31583Y1459067D01*
X32000Y1458900D01*
X32375Y1458858D01*
X32750Y1458942D01*
X33000Y1459067D01*
X33250Y1459317D01*
X33417Y1459608D01*
X33500Y1459900D01*
Y1460192D01*
X33417Y1460483D01*
X33292Y1460733D01*
X33125Y1460942D01*
G01X33500Y1462042D02*
X31000D01*
X33500Y1463958D01*
X31000D01*
G01X31417Y1465308D02*
X31167Y1465558D01*
X31042Y1465850D01*
X31000Y1466183D01*
X31083Y1466600D01*
X31292Y1466892D01*
X31542Y1466975D01*
X31792Y1466933D01*
X32000Y1466767D01*
X32417Y1465933D01*
X32708Y1465558D01*
X33125Y1465308D01*
X33500Y1465225D01*
Y1466975D01*
G01X64517Y1474500D02*
Y1477000D01*
X65517D01*
X65850Y1476875D01*
X66100Y1476583D01*
X66183Y1476250D01*
X66100Y1475917D01*
X65892Y1475667D01*
X65517Y1475542D01*
X64517D01*
G01X69367Y1476792D02*
X69117Y1476917D01*
X68825Y1477000D01*
X68492D01*
X68117Y1476875D01*
X67825Y1476667D01*
X67617Y1476417D01*
X67450Y1476000D01*
X67408Y1475625D01*
X67492Y1475250D01*
X67617Y1475000D01*
X67867Y1474750D01*
X68158Y1474583D01*
X68450Y1474500D01*
X68742D01*
X69033Y1474583D01*
X69283Y1474708D01*
X69492Y1474875D01*
G01X71550Y1474500D02*
Y1477000D01*
X71050Y1476500D01*
G01Y1474500D02*
X72050D01*
G01X74650Y1477000D02*
X74317Y1476917D01*
X74067Y1476708D01*
X73900Y1476458D01*
X73775Y1476125D01*
X73733Y1475750D01*
X73775Y1475375D01*
X73900Y1475042D01*
X74067Y1474792D01*
X74317Y1474583D01*
X74650Y1474500D01*
X74983Y1474583D01*
X75233Y1474792D01*
X75400Y1475042D01*
X75525Y1475375D01*
X75567Y1475750D01*
X75525Y1476125D01*
X75400Y1476458D01*
X75233Y1476708D01*
X74983Y1476917D01*
X74650Y1477000D01*
G01X69900Y1530300D02*
Y1519100D01*
G01Y1491900D02*
Y1503100D01*
G01X87900Y1491900D02*
X69900D01*
G01X70017Y1483500D02*
Y1486000D01*
X71017D01*
X71350Y1485875D01*
X71600Y1485583D01*
X71683Y1485250D01*
X71600Y1484917D01*
X71392Y1484667D01*
X71017Y1484542D01*
X70017D01*
G01X73117Y1483500D02*
Y1486000D01*
X74158D01*
X74492Y1485875D01*
X74700Y1485708D01*
X74783Y1485375D01*
X74700Y1485042D01*
X74450Y1484833D01*
X74158Y1484708D01*
X73117D01*
G01X74158D02*
X74783Y1483500D01*
G01X76133Y1484000D02*
X76383Y1483708D01*
X76717Y1483542D01*
X77092Y1483500D01*
X77425Y1483542D01*
X77758Y1483750D01*
X77967Y1484000D01*
X78008Y1484250D01*
X77925Y1484542D01*
X77633Y1484750D01*
X77342Y1484833D01*
X76967D01*
G01X77342D02*
X77592Y1484958D01*
X77800Y1485167D01*
X77883Y1485417D01*
X77800Y1485667D01*
X77592Y1485875D01*
X77217Y1486000D01*
X76842Y1485958D01*
X76467Y1485792D01*
G01X80650Y1483500D02*
Y1486000D01*
X79108Y1484208D01*
X81192D01*
G01X78350Y1538000D02*
Y1535500D01*
G01X77392Y1538000D02*
X79308D01*
G01X82367Y1537792D02*
X82117Y1537917D01*
X81825Y1538000D01*
X81492D01*
X81117Y1537875D01*
X80825Y1537667D01*
X80617Y1537417D01*
X80450Y1537000D01*
X80408Y1536625D01*
X80492Y1536250D01*
X80617Y1536000D01*
X80867Y1535750D01*
X81158Y1535583D01*
X81450Y1535500D01*
X81742D01*
X82033Y1535583D01*
X82283Y1535708D01*
X82492Y1535875D01*
G01X84550Y1535500D02*
Y1538000D01*
X84050Y1537500D01*
G01Y1535500D02*
X85050D01*
G01X87650D02*
Y1538000D01*
X87150Y1537500D01*
G01Y1535500D02*
X88150D01*
G01X87900Y1530300D02*
X69900D01*
G01X73600Y1545250D02*
X76100D01*
G01X73600Y1544292D02*
Y1546208D01*
G01X73808Y1549267D02*
X73683Y1549017D01*
X73600Y1548725D01*
Y1548392D01*
X73725Y1548017D01*
X73933Y1547725D01*
X74183Y1547517D01*
X74600Y1547350D01*
X74975Y1547308D01*
X75350Y1547392D01*
X75600Y1547517D01*
X75850Y1547767D01*
X76017Y1548058D01*
X76100Y1548350D01*
Y1548642D01*
X76017Y1548933D01*
X75892Y1549183D01*
X75725Y1549392D01*
G01X76100Y1551450D02*
X73600D01*
X74100Y1550950D01*
G01X76100D02*
Y1551950D01*
G01X74017Y1553758D02*
X73767Y1554008D01*
X73642Y1554300D01*
X73600Y1554633D01*
X73683Y1555050D01*
X73892Y1555342D01*
X74142Y1555425D01*
X74392Y1555383D01*
X74600Y1555217D01*
X75017Y1554383D01*
X75308Y1554008D01*
X75725Y1553758D01*
X76100Y1553675D01*
Y1555425D01*
G01X68200Y1560500D02*
X57000D01*
G01X68200Y1542500D02*
Y1560500D01*
G01X57000Y1542500D02*
X68200D01*
G01X29800Y1560500D02*
X41000D01*
G01X29800Y1542500D02*
Y1560500D01*
G01X41000Y1542500D02*
X29800D01*
G01X71517Y1603000D02*
Y1605500D01*
X72517D01*
X72850Y1605375D01*
X73100Y1605083D01*
X73183Y1604750D01*
X73100Y1604417D01*
X72892Y1604167D01*
X72517Y1604042D01*
X71517D01*
G01X75450Y1603000D02*
X75117Y1603042D01*
X74825Y1603208D01*
X74575Y1603458D01*
X74408Y1603750D01*
X74325Y1604083D01*
Y1604417D01*
X74408Y1604750D01*
X74575Y1605042D01*
X74825Y1605292D01*
X75117Y1605458D01*
X75450Y1605500D01*
X75783Y1605458D01*
X76075Y1605292D01*
X76325Y1605042D01*
X76492Y1604750D01*
X76575Y1604417D01*
Y1604083D01*
X76492Y1603750D01*
X76325Y1603458D01*
X76075Y1603208D01*
X75783Y1603042D01*
X75450Y1603000D01*
G01X75783Y1603667D02*
X76283Y1603000D01*
G01X78550D02*
Y1605500D01*
X78050Y1605000D01*
G01Y1603000D02*
X79050D01*
G01X80733Y1603500D02*
X80983Y1603208D01*
X81317Y1603042D01*
X81692Y1603000D01*
X82025Y1603042D01*
X82358Y1603250D01*
X82567Y1603500D01*
X82608Y1603750D01*
X82525Y1604042D01*
X82233Y1604250D01*
X81942Y1604333D01*
X81567D01*
G01X81942D02*
X82192Y1604458D01*
X82400Y1604667D01*
X82483Y1604917D01*
X82400Y1605167D01*
X82192Y1605375D01*
X81817Y1605500D01*
X81442Y1605458D01*
X81067Y1605292D01*
G01X78750Y1601400D02*
X57050D01*
G01X78750Y1571400D02*
Y1601400D01*
G01X57050Y1571400D02*
X78750D01*
G01X57050Y1601400D02*
Y1571400D01*
G01X65750Y1610000D02*
Y1623000D01*
X81250D01*
Y1610000D01*
X65750D01*
G01X41976Y1654969D02*
X39476D01*
Y1656010D01*
X39601Y1656344D01*
X39768Y1656552D01*
X40101Y1656635D01*
X40434Y1656552D01*
X40643Y1656302D01*
X40768Y1656010D01*
Y1654969D01*
G01Y1656010D02*
X41976Y1656635D01*
G01Y1658902D02*
X39476D01*
X39976Y1658402D01*
G01X41976D02*
Y1659402D01*
G01Y1662002D02*
X39476D01*
X39976Y1661502D01*
G01X41976D02*
Y1662502D01*
G01X41684Y1664394D02*
X41893Y1664685D01*
X41976Y1665019D01*
X41893Y1665352D01*
X41643Y1665644D01*
X41268Y1665852D01*
X40893Y1665935D01*
X40434D01*
X40059Y1665852D01*
X39726Y1665644D01*
X39559Y1665394D01*
X39476Y1665102D01*
X39559Y1664769D01*
X39726Y1664519D01*
X39976Y1664352D01*
X40309Y1664269D01*
X40601Y1664352D01*
X40893Y1664560D01*
X41059Y1664810D01*
X41101Y1665102D01*
X41018Y1665435D01*
X40809Y1665685D01*
X40434Y1665935D01*
G01X34900Y1666200D02*
X30900D01*
Y1658800D01*
G01X44700Y1643550D02*
X44658Y1643217D01*
X44492Y1642925D01*
X44242Y1642675D01*
X43950Y1642508D01*
X43617Y1642425D01*
X43283D01*
X42950Y1642508D01*
X42658Y1642675D01*
X42408Y1642925D01*
X42242Y1643217D01*
X42200Y1643550D01*
X42242Y1643883D01*
X42408Y1644175D01*
X42658Y1644425D01*
X42950Y1644592D01*
X43283Y1644675D01*
X43617D01*
X43950Y1644592D01*
X44242Y1644425D01*
X44492Y1644175D01*
X44658Y1643883D01*
X44700Y1643550D01*
G01X44033Y1643883D02*
X44700Y1644383D01*
G01Y1646567D02*
X44158Y1646650D01*
X43700Y1646775D01*
X43283Y1646942D01*
X42825Y1647150D01*
X42200Y1647483D01*
Y1645817D01*
G01X38000Y1638300D02*
Y1652300D01*
G01X29917Y1704118D02*
Y1718118D01*
G01X44067Y1695000D02*
Y1697500D01*
X45067D01*
X45400Y1697375D01*
X45650Y1697083D01*
X45733Y1696750D01*
X45650Y1696417D01*
X45442Y1696167D01*
X45067Y1696042D01*
X44067D01*
G01X47083Y1695000D02*
Y1697500D01*
X47917D01*
X48250Y1697375D01*
X48500Y1697208D01*
X48708Y1696958D01*
X48875Y1696667D01*
X48917Y1696250D01*
X48875Y1695833D01*
X48708Y1695542D01*
X48500Y1695292D01*
X48250Y1695125D01*
X47917Y1695000D01*
X47083D01*
G01X50308Y1697083D02*
X50558Y1697333D01*
X50850Y1697458D01*
X51183Y1697500D01*
X51600Y1697417D01*
X51892Y1697208D01*
X51975Y1696958D01*
X51933Y1696708D01*
X51767Y1696500D01*
X50933Y1696083D01*
X50558Y1695792D01*
X50308Y1695375D01*
X50225Y1695000D01*
X51975D01*
G01X124407Y1688975D02*
X68507D01*
Y1857875D01*
X124407D01*
Y1784512D01*
X119095D01*
G03Y1773126I0J-5693D01*
G01X124407D01*
Y1688975D01*
G01X38800Y1734917D02*
X41300D01*
Y1736583D01*
G01Y1739683D02*
Y1738017D01*
X38800D01*
Y1739683D01*
G01X40008Y1739017D02*
Y1738017D01*
G01X41300Y1741033D02*
X38800D01*
Y1741867D01*
X38925Y1742200D01*
X39092Y1742450D01*
X39342Y1742658D01*
X39633Y1742825D01*
X40050Y1742867D01*
X40467Y1742825D01*
X40758Y1742658D01*
X41008Y1742450D01*
X41175Y1742200D01*
X41300Y1741867D01*
Y1741033D01*
G01Y1745050D02*
X38800D01*
X39300Y1744550D01*
G01X41300D02*
Y1745550D01*
G01X58797Y1741981D02*
X56297D01*
Y1742815D01*
X56422Y1743148D01*
X56589Y1743398D01*
X56839Y1743606D01*
X57130Y1743773D01*
X57547Y1743815D01*
X57964Y1743773D01*
X58255Y1743606D01*
X58505Y1743398D01*
X58672Y1743148D01*
X58797Y1742815D01*
Y1741981D01*
G01Y1745998D02*
X56297D01*
X56797Y1745498D01*
G01X58797D02*
Y1746498D01*
G01X56714Y1748306D02*
X56464Y1748556D01*
X56339Y1748848D01*
X56297Y1749181D01*
X56380Y1749598D01*
X56589Y1749890D01*
X56839Y1749973D01*
X57089Y1749931D01*
X57297Y1749765D01*
X57714Y1748931D01*
X58005Y1748556D01*
X58422Y1748306D01*
X58797Y1748223D01*
Y1749973D01*
G01X45600Y1750400D02*
Y1771400D01*
G01D02*
X37600D01*
G01D02*
Y1750400D01*
G01D02*
X45600D01*
G01X55617Y1755800D02*
Y1758300D01*
X56658D01*
X56992Y1758175D01*
X57200Y1758008D01*
X57283Y1757675D01*
X57200Y1757342D01*
X56950Y1757133D01*
X56658Y1757008D01*
X55617D01*
G01X56658D02*
X57283Y1755800D01*
G01X59550D02*
Y1758300D01*
X59050Y1757800D01*
G01Y1755800D02*
X60050D01*
G01X62650Y1758300D02*
X62317Y1758217D01*
X62067Y1758008D01*
X61900Y1757758D01*
X61775Y1757425D01*
X61733Y1757050D01*
X61775Y1756675D01*
X61900Y1756342D01*
X62067Y1756092D01*
X62317Y1755883D01*
X62650Y1755800D01*
X62983Y1755883D01*
X63233Y1756092D01*
X63400Y1756342D01*
X63525Y1756675D01*
X63567Y1757050D01*
X63525Y1757425D01*
X63400Y1757758D01*
X63233Y1758008D01*
X62983Y1758217D01*
X62650Y1758300D01*
G01X65750Y1755800D02*
Y1758300D01*
X65250Y1757800D01*
G01Y1755800D02*
X66250D01*
G01X63602Y1741964D02*
X61102D01*
Y1743005D01*
X61227Y1743339D01*
X61394Y1743547D01*
X61727Y1743630D01*
X62060Y1743547D01*
X62269Y1743297D01*
X62394Y1743005D01*
Y1741964D01*
G01Y1743005D02*
X63602Y1743630D01*
G01X63310Y1745189D02*
X63519Y1745480D01*
X63602Y1745814D01*
X63519Y1746147D01*
X63269Y1746439D01*
X62894Y1746647D01*
X62519Y1746730D01*
X62060D01*
X61685Y1746647D01*
X61352Y1746439D01*
X61185Y1746189D01*
X61102Y1745897D01*
X61185Y1745564D01*
X61352Y1745314D01*
X61602Y1745147D01*
X61935Y1745064D01*
X62227Y1745147D01*
X62519Y1745355D01*
X62685Y1745605D01*
X62727Y1745897D01*
X62644Y1746230D01*
X62435Y1746480D01*
X62060Y1746730D01*
G01X63602Y1748914D02*
X63060Y1748997D01*
X62602Y1749122D01*
X62185Y1749289D01*
X61727Y1749497D01*
X61102Y1749830D01*
Y1748164D01*
G01X46300Y1750300D02*
X50300D01*
Y1757700D01*
G01X44100Y1774917D02*
X41600D01*
Y1775958D01*
X41725Y1776292D01*
X41892Y1776500D01*
X42225Y1776583D01*
X42558Y1776500D01*
X42767Y1776250D01*
X42892Y1775958D01*
Y1774917D01*
G01Y1775958D02*
X44100Y1776583D01*
G01Y1778850D02*
X41600D01*
X42100Y1778350D01*
G01X44100D02*
Y1779350D01*
G01X41600Y1781950D02*
X41683Y1781617D01*
X41892Y1781367D01*
X42142Y1781200D01*
X42475Y1781075D01*
X42850Y1781033D01*
X43225Y1781075D01*
X43558Y1781200D01*
X43808Y1781367D01*
X44017Y1781617D01*
X44100Y1781950D01*
X44017Y1782283D01*
X43808Y1782533D01*
X43558Y1782700D01*
X43225Y1782825D01*
X42850Y1782867D01*
X42475Y1782825D01*
X42142Y1782700D01*
X41892Y1782533D01*
X41683Y1782283D01*
X41600Y1781950D01*
G01X43725Y1784133D02*
X43933Y1784383D01*
X44058Y1784675D01*
X44100Y1785050D01*
X44017Y1785425D01*
X43850Y1785717D01*
X43558Y1785925D01*
X43225Y1785967D01*
X42892Y1785883D01*
X42683Y1785675D01*
X42517Y1785383D01*
X42475Y1785092D01*
X42517Y1784800D01*
X42683Y1784425D01*
X41600Y1784550D01*
Y1785675D01*
G01X47400Y1771800D02*
Y1767800D01*
X54800D01*
G01X57817Y1753792D02*
X57567Y1753917D01*
X57275Y1754000D01*
X56942D01*
X56567Y1753875D01*
X56275Y1753667D01*
X56067Y1753417D01*
X55900Y1753000D01*
X55858Y1752625D01*
X55942Y1752250D01*
X56067Y1752000D01*
X56317Y1751750D01*
X56608Y1751583D01*
X56900Y1751500D01*
X57192D01*
X57483Y1751583D01*
X57733Y1751708D01*
X57942Y1751875D01*
G01X60500Y1751500D02*
Y1754000D01*
X58958Y1752208D01*
X61042D01*
G01X62308Y1752542D02*
X62600Y1752833D01*
X62850Y1753000D01*
X63183Y1753083D01*
X63475Y1753000D01*
X63683Y1752833D01*
X63850Y1752583D01*
X63892Y1752292D01*
X63850Y1752042D01*
X63683Y1751792D01*
X63433Y1751583D01*
X63142Y1751500D01*
X62808Y1751583D01*
X62517Y1751833D01*
X62350Y1752208D01*
X62308Y1752625D01*
X62392Y1753167D01*
X62517Y1753458D01*
X62725Y1753750D01*
X63017Y1753958D01*
X63308Y1754000D01*
X63600Y1753917D01*
X63808Y1753708D01*
G01X38500Y1777000D02*
Y1785000D01*
G01X36967Y1792000D02*
Y1794500D01*
X38008D01*
X38342Y1794375D01*
X38550Y1794208D01*
X38633Y1793875D01*
X38550Y1793542D01*
X38300Y1793333D01*
X38008Y1793208D01*
X36967D01*
G01X38008D02*
X38633Y1792000D01*
G01X40192Y1792292D02*
X40483Y1792083D01*
X40817Y1792000D01*
X41150Y1792083D01*
X41442Y1792333D01*
X41650Y1792708D01*
X41733Y1793083D01*
Y1793542D01*
X41650Y1793917D01*
X41442Y1794250D01*
X41192Y1794417D01*
X40900Y1794500D01*
X40567Y1794417D01*
X40317Y1794250D01*
X40150Y1794000D01*
X40067Y1793667D01*
X40150Y1793375D01*
X40358Y1793083D01*
X40608Y1792917D01*
X40900Y1792875D01*
X41233Y1792958D01*
X41483Y1793167D01*
X41733Y1793542D01*
G01X43208Y1793042D02*
X43500Y1793333D01*
X43750Y1793500D01*
X44083Y1793583D01*
X44375Y1793500D01*
X44583Y1793333D01*
X44750Y1793083D01*
X44792Y1792792D01*
X44750Y1792542D01*
X44583Y1792292D01*
X44333Y1792083D01*
X44042Y1792000D01*
X43708Y1792083D01*
X43417Y1792333D01*
X43250Y1792708D01*
X43208Y1793125D01*
X43292Y1793667D01*
X43417Y1793958D01*
X43625Y1794250D01*
X43917Y1794458D01*
X44208Y1794500D01*
X44500Y1794417D01*
X44708Y1794208D01*
G01X40400Y1786200D02*
Y1790200D01*
X33000D01*
G01X56500Y1912917D02*
X51500D01*
Y1916083D01*
G01X53917Y1914917D02*
Y1912917D01*
G01X54417Y1918517D02*
X53833Y1919100D01*
X53500Y1919600D01*
X53333Y1920267D01*
X53500Y1920850D01*
X53833Y1921267D01*
X54333Y1921600D01*
X54917Y1921683D01*
X55417Y1921600D01*
X55917Y1921267D01*
X56333Y1920767D01*
X56500Y1920183D01*
X56333Y1919517D01*
X55833Y1918933D01*
X55083Y1918600D01*
X54250Y1918517D01*
X53167Y1918683D01*
X52583Y1918933D01*
X52000Y1919350D01*
X51583Y1919933D01*
X51500Y1920517D01*
X51667Y1921100D01*
X52083Y1921517D01*
G01X56667Y1925700D02*
X56583Y1925533D01*
X56417D01*
X56333Y1925700D01*
X56417Y1925867D01*
X56583D01*
X56667Y1925700D01*
G01X54417D02*
X54333Y1925533D01*
X54167D01*
X54083Y1925700D01*
X54167Y1925867D01*
X54333D01*
X54417Y1925700D01*
G01X55500Y1929467D02*
X56083Y1929967D01*
X56417Y1930633D01*
X56500Y1931383D01*
X56417Y1932050D01*
X56000Y1932717D01*
X55500Y1933133D01*
X55000Y1933217D01*
X54417Y1933050D01*
X54000Y1932467D01*
X53833Y1931883D01*
Y1931133D01*
G01Y1931883D02*
X53583Y1932383D01*
X53167Y1932800D01*
X52667Y1932967D01*
X52167Y1932800D01*
X51750Y1932383D01*
X51500Y1931633D01*
X51583Y1930883D01*
X51917Y1930133D01*
G01X56500Y1934817D02*
X51500Y1936900D01*
X56500Y1938983D01*
G01X54750Y1938233D02*
Y1935567D01*
G01X56667Y1941000D02*
X51500Y1944000D01*
G01X56500Y1948100D02*
X51500D01*
X52500Y1947100D01*
G01X56500D02*
Y1949100D01*
G01X55750Y1951867D02*
X56167Y1952367D01*
X56417Y1952950D01*
X56500Y1953700D01*
X56333Y1954450D01*
X56000Y1955033D01*
X55417Y1955450D01*
X54750Y1955533D01*
X54083Y1955367D01*
X53667Y1954950D01*
X53333Y1954367D01*
X53250Y1953783D01*
X53333Y1953200D01*
X53667Y1952450D01*
X51500Y1952700D01*
Y1954950D01*
G01Y1957217D02*
X56500Y1959300D01*
X51500Y1961383D01*
G01X79658Y1879000D02*
Y1881500D01*
X81242D01*
G01X80658Y1880292D02*
X79658D01*
G01X82758Y1880042D02*
X83050Y1880333D01*
X83300Y1880500D01*
X83633Y1880583D01*
X83925Y1880500D01*
X84133Y1880333D01*
X84300Y1880083D01*
X84342Y1879792D01*
X84300Y1879542D01*
X84133Y1879292D01*
X83883Y1879083D01*
X83592Y1879000D01*
X83258Y1879083D01*
X82967Y1879333D01*
X82800Y1879708D01*
X82758Y1880125D01*
X82842Y1880667D01*
X82967Y1880958D01*
X83175Y1881250D01*
X83467Y1881458D01*
X83758Y1881500D01*
X84050Y1881417D01*
X84258Y1881208D01*
G01X32708Y1910317D02*
X32583Y1910067D01*
X32500Y1909775D01*
Y1909442D01*
X32625Y1909067D01*
X32833Y1908775D01*
X33083Y1908567D01*
X33500Y1908400D01*
X33875Y1908358D01*
X34250Y1908442D01*
X34500Y1908567D01*
X34750Y1908817D01*
X34917Y1909108D01*
X35000Y1909400D01*
Y1909692D01*
X34917Y1909983D01*
X34792Y1910233D01*
X34625Y1910442D01*
G01X35000Y1911542D02*
X32500D01*
X35000Y1913458D01*
X32500D01*
G01X35000Y1915600D02*
X32500D01*
X33000Y1915100D01*
G01X35000D02*
Y1916100D01*
G01X73000Y1892517D02*
X70500D01*
Y1893558D01*
X70625Y1893892D01*
X70792Y1894100D01*
X71125Y1894183D01*
X71458Y1894100D01*
X71667Y1893850D01*
X71792Y1893558D01*
Y1892517D01*
G01Y1893558D02*
X73000Y1894183D01*
G01Y1896450D02*
X70500D01*
X71000Y1895950D01*
G01X73000D02*
Y1896950D01*
G01Y1899467D02*
X72458Y1899550D01*
X72000Y1899675D01*
X71583Y1899842D01*
X71125Y1900050D01*
X70500Y1900383D01*
Y1898717D01*
G01X73000Y1902567D02*
X72458Y1902650D01*
X72000Y1902775D01*
X71583Y1902942D01*
X71125Y1903150D01*
X70500Y1903483D01*
Y1901817D01*
G01X76100Y1904700D02*
Y1887100D01*
G01X84100Y1904700D02*
X76100D01*
G01Y1887100D02*
X84100D01*
G01X105000Y97700D02*
Y74700D01*
G01X101500Y50033D02*
X99000D01*
Y50867D01*
X99125Y51200D01*
X99292Y51450D01*
X99542Y51658D01*
X99833Y51825D01*
X100250Y51867D01*
X100667Y51825D01*
X100958Y51658D01*
X101208Y51450D01*
X101375Y51200D01*
X101500Y50867D01*
Y50033D01*
G01X101000Y53133D02*
X101292Y53383D01*
X101458Y53717D01*
X101500Y54092D01*
X101458Y54425D01*
X101250Y54758D01*
X101000Y54967D01*
X100750Y55008D01*
X100458Y54925D01*
X100250Y54633D01*
X100167Y54342D01*
Y53967D01*
G01Y54342D02*
X100042Y54592D01*
X99833Y54800D01*
X99583Y54883D01*
X99333Y54800D01*
X99125Y54592D01*
X99000Y54217D01*
X99042Y53842D01*
X99208Y53467D01*
G01X95103Y50502D02*
Y58502D01*
G01X128000Y64533D02*
X125500D01*
Y65367D01*
X125625Y65700D01*
X125792Y65950D01*
X126042Y66158D01*
X126333Y66325D01*
X126750Y66367D01*
X127167Y66325D01*
X127458Y66158D01*
X127708Y65950D01*
X127875Y65700D01*
X128000Y65367D01*
Y64533D01*
G01Y68550D02*
X125500D01*
X126000Y68050D01*
G01X128000D02*
Y69050D01*
G01X113000Y72500D02*
X92000D01*
G01D02*
Y64500D01*
G01D02*
X113000D01*
G01D02*
Y72500D01*
G01X106300Y79500D02*
X117500D01*
G01X106300Y97500D02*
Y79500D01*
G01X96067Y60000D02*
Y62500D01*
X97108D01*
X97442Y62375D01*
X97650Y62208D01*
X97733Y61875D01*
X97650Y61542D01*
X97400Y61333D01*
X97108Y61208D01*
X96067D01*
G01X97108D02*
X97733Y60000D01*
G01X99917D02*
X100000Y60542D01*
X100125Y61000D01*
X100292Y61417D01*
X100500Y61875D01*
X100833Y62500D01*
X99167D01*
G01X102183Y60500D02*
X102433Y60208D01*
X102767Y60042D01*
X103142Y60000D01*
X103475Y60042D01*
X103808Y60250D01*
X104017Y60500D01*
X104058Y60750D01*
X103975Y61042D01*
X103683Y61250D01*
X103392Y61333D01*
X103017D01*
G01X103392D02*
X103642Y61458D01*
X103850Y61667D01*
X103933Y61917D01*
X103850Y62167D01*
X103642Y62375D01*
X103267Y62500D01*
X102892Y62458D01*
X102517Y62292D01*
G01X120000Y64567D02*
X117500D01*
Y65608D01*
X117625Y65942D01*
X117792Y66150D01*
X118125Y66233D01*
X118458Y66150D01*
X118667Y65900D01*
X118792Y65608D01*
Y64567D01*
G01Y65608D02*
X120000Y66233D01*
G01Y68417D02*
X119458Y68500D01*
X119000Y68625D01*
X118583Y68792D01*
X118125Y69000D01*
X117500Y69333D01*
Y67667D01*
G01X120000Y71600D02*
X117500D01*
X118000Y71100D01*
G01X120000D02*
Y72100D01*
G01X106067Y60000D02*
Y62500D01*
X107108D01*
X107442Y62375D01*
X107650Y62208D01*
X107733Y61875D01*
X107650Y61542D01*
X107400Y61333D01*
X107108Y61208D01*
X106067D01*
G01X107108D02*
X107733Y60000D01*
G01X109917D02*
X110000Y60542D01*
X110125Y61000D01*
X110292Y61417D01*
X110500Y61875D01*
X110833Y62500D01*
X109167D01*
G01X113017Y60000D02*
X113100Y60542D01*
X113225Y61000D01*
X113392Y61417D01*
X113600Y61875D01*
X113933Y62500D01*
X112267D01*
G01X86303Y63502D02*
Y59502D01*
X93703D01*
G01X124000Y64567D02*
X121500D01*
Y65608D01*
X121625Y65942D01*
X121792Y66150D01*
X122125Y66233D01*
X122458Y66150D01*
X122667Y65900D01*
X122792Y65608D01*
Y64567D01*
G01Y65608D02*
X124000Y66233D01*
G01Y68417D02*
X123458Y68500D01*
X123000Y68625D01*
X122583Y68792D01*
X122125Y69000D01*
X121500Y69333D01*
Y67667D01*
G01X123625Y70683D02*
X123833Y70933D01*
X123958Y71225D01*
X124000Y71600D01*
X123917Y71975D01*
X123750Y72267D01*
X123458Y72475D01*
X123125Y72517D01*
X122792Y72433D01*
X122583Y72225D01*
X122417Y71933D01*
X122375Y71642D01*
X122417Y71350D01*
X122583Y70975D01*
X121500Y71100D01*
Y72225D01*
G01X83800Y73500D02*
Y69500D01*
X91200D01*
G01X99158Y99000D02*
Y101500D01*
X100742D01*
G01X100158Y100292D02*
X99158D01*
G01X103050Y99000D02*
Y101500D01*
X102550Y101000D01*
G01Y99000D02*
X103550D01*
G01X117500Y97500D02*
X106300D01*
G01X93017Y103500D02*
Y106000D01*
X94058D01*
X94392Y105875D01*
X94600Y105708D01*
X94683Y105375D01*
X94600Y105042D01*
X94350Y104833D01*
X94058Y104708D01*
X93017D01*
G01X94058D02*
X94683Y103500D01*
G01X96950D02*
Y106000D01*
X96450Y105500D01*
G01Y103500D02*
X97450D01*
G01X100050D02*
X100342Y103542D01*
X100675Y103667D01*
X100883Y103875D01*
X100967Y104167D01*
X100883Y104458D01*
X100633Y104708D01*
X100258Y104833D01*
X99842D01*
X99592Y104917D01*
X99383Y105125D01*
X99300Y105417D01*
X99425Y105708D01*
X99717Y105917D01*
X100050Y106000D01*
X100383Y105917D01*
X100675Y105708D01*
X100800Y105417D01*
X100717Y105125D01*
X100508Y104917D01*
X100258Y104833D01*
X99842D01*
X99467Y104708D01*
X99217Y104458D01*
X99133Y104167D01*
X99217Y103875D01*
X99425Y103667D01*
X99758Y103542D01*
X100050Y103500D01*
G01X102358Y105583D02*
X102608Y105833D01*
X102900Y105958D01*
X103233Y106000D01*
X103650Y105917D01*
X103942Y105708D01*
X104025Y105458D01*
X103983Y105208D01*
X103817Y105000D01*
X102983Y104583D01*
X102608Y104292D01*
X102358Y103875D01*
X102275Y103500D01*
X104025D01*
G01X90400Y99000D02*
Y107000D01*
G01X112700Y389500D02*
X101500D01*
G01X112700Y407500D02*
Y389500D01*
G01X101317Y381292D02*
X101067Y381417D01*
X100775Y381500D01*
X100442D01*
X100067Y381375D01*
X99775Y381167D01*
X99567Y380917D01*
X99400Y380500D01*
X99358Y380125D01*
X99442Y379750D01*
X99567Y379500D01*
X99817Y379250D01*
X100108Y379083D01*
X100400Y379000D01*
X100692D01*
X100983Y379083D01*
X101233Y379208D01*
X101442Y379375D01*
G01X102708Y381083D02*
X102958Y381333D01*
X103250Y381458D01*
X103583Y381500D01*
X104000Y381417D01*
X104292Y381208D01*
X104375Y380958D01*
X104333Y380708D01*
X104167Y380500D01*
X103333Y380083D01*
X102958Y379792D01*
X102708Y379375D01*
X102625Y379000D01*
X104375D01*
G01X107100D02*
Y381500D01*
X105558Y379708D01*
X107642D01*
G01X126483Y376500D02*
Y379000D01*
X127317D01*
X127650Y378875D01*
X127900Y378708D01*
X128108Y378458D01*
X128275Y378167D01*
X128317Y377750D01*
X128275Y377333D01*
X128108Y377042D01*
X127900Y376792D01*
X127650Y376625D01*
X127317Y376500D01*
X126483D01*
G01X130500D02*
Y379000D01*
X130000Y378500D01*
G01Y376500D02*
X131000D01*
G01X132808Y377542D02*
X133100Y377833D01*
X133350Y378000D01*
X133683Y378083D01*
X133975Y378000D01*
X134183Y377833D01*
X134350Y377583D01*
X134392Y377292D01*
X134350Y377042D01*
X134183Y376792D01*
X133933Y376583D01*
X133642Y376500D01*
X133308Y376583D01*
X133017Y376833D01*
X132850Y377208D01*
X132808Y377625D01*
X132892Y378167D01*
X133017Y378458D01*
X133225Y378750D01*
X133517Y378958D01*
X133808Y379000D01*
X134100Y378917D01*
X134308Y378708D01*
G01X145700Y349300D02*
X105500D01*
G01Y374300D02*
X145700D01*
G01X105500Y349300D02*
Y374300D01*
G01X104600Y374400D02*
Y349400D01*
G01X114567Y431500D02*
Y434000D01*
X115567D01*
X115900Y433875D01*
X116150Y433583D01*
X116233Y433250D01*
X116150Y432917D01*
X115942Y432667D01*
X115567Y432542D01*
X114567D01*
G01X117667Y431500D02*
Y434000D01*
X118708D01*
X119042Y433875D01*
X119250Y433708D01*
X119333Y433375D01*
X119250Y433042D01*
X119000Y432833D01*
X118708Y432708D01*
X117667D01*
G01X118708D02*
X119333Y431500D01*
G01X121600D02*
Y434000D01*
X121100Y433500D01*
G01Y431500D02*
X122100D01*
G01X124700Y434000D02*
X124367Y433917D01*
X124117Y433708D01*
X123950Y433458D01*
X123825Y433125D01*
X123783Y432750D01*
X123825Y432375D01*
X123950Y432042D01*
X124117Y431792D01*
X124367Y431583D01*
X124700Y431500D01*
X125033Y431583D01*
X125283Y431792D01*
X125450Y432042D01*
X125575Y432375D01*
X125617Y432750D01*
X125575Y433125D01*
X125450Y433458D01*
X125283Y433708D01*
X125033Y433917D01*
X124700Y434000D01*
G01X127008Y433583D02*
X127258Y433833D01*
X127550Y433958D01*
X127883Y434000D01*
X128300Y433917D01*
X128592Y433708D01*
X128675Y433458D01*
X128633Y433208D01*
X128467Y433000D01*
X127633Y432583D01*
X127258Y432292D01*
X127008Y431875D01*
X126925Y431500D01*
X128675D01*
G01X115900Y439500D02*
Y435500D01*
X123300D01*
G01X114850Y435300D02*
Y465300D01*
G01X93150Y435300D02*
X114850D01*
G01X93150Y465300D02*
Y435300D01*
G01X87350Y435800D02*
Y465800D01*
G01X115400Y399500D02*
Y397000D01*
G01X114442Y399500D02*
X116358D01*
G01X119417Y399292D02*
X119167Y399417D01*
X118875Y399500D01*
X118542D01*
X118167Y399375D01*
X117875Y399167D01*
X117667Y398917D01*
X117500Y398500D01*
X117458Y398125D01*
X117542Y397750D01*
X117667Y397500D01*
X117917Y397250D01*
X118208Y397083D01*
X118500Y397000D01*
X118792D01*
X119083Y397083D01*
X119333Y397208D01*
X119542Y397375D01*
G01X122100Y397000D02*
Y399500D01*
X120558Y397708D01*
X122642D01*
G01X101500Y407500D02*
X112700D01*
G01X115400Y421000D02*
Y418500D01*
G01X114442Y421000D02*
X116358D01*
G01X119417Y420792D02*
X119167Y420917D01*
X118875Y421000D01*
X118542D01*
X118167Y420875D01*
X117875Y420667D01*
X117667Y420417D01*
X117500Y420000D01*
X117458Y419625D01*
X117542Y419250D01*
X117667Y419000D01*
X117917Y418750D01*
X118208Y418583D01*
X118500Y418500D01*
X118792D01*
X119083Y418583D01*
X119333Y418708D01*
X119542Y418875D01*
G01X120683Y419000D02*
X120933Y418708D01*
X121267Y418542D01*
X121642Y418500D01*
X121975Y418542D01*
X122308Y418750D01*
X122517Y419000D01*
X122558Y419250D01*
X122475Y419542D01*
X122183Y419750D01*
X121892Y419833D01*
X121517D01*
G01X121892D02*
X122142Y419958D01*
X122350Y420167D01*
X122433Y420417D01*
X122350Y420667D01*
X122142Y420875D01*
X121767Y421000D01*
X121392Y420958D01*
X121017Y420792D01*
G01X112700Y410000D02*
X101500D01*
G01X112700Y428000D02*
Y410000D01*
G01X101500Y428000D02*
X112700D01*
G01X128067Y456000D02*
Y458500D01*
X129067D01*
X129400Y458375D01*
X129650Y458083D01*
X129733Y457750D01*
X129650Y457417D01*
X129442Y457167D01*
X129067Y457042D01*
X128067D01*
G01X132000Y456000D02*
X131667Y456042D01*
X131375Y456208D01*
X131125Y456458D01*
X130958Y456750D01*
X130875Y457083D01*
Y457417D01*
X130958Y457750D01*
X131125Y458042D01*
X131375Y458292D01*
X131667Y458458D01*
X132000Y458500D01*
X132333Y458458D01*
X132625Y458292D01*
X132875Y458042D01*
X133042Y457750D01*
X133125Y457417D01*
Y457083D01*
X133042Y456750D01*
X132875Y456458D01*
X132625Y456208D01*
X132333Y456042D01*
X132000Y456000D01*
G01X132333Y456667D02*
X132833Y456000D01*
G01X135100D02*
X135392Y456042D01*
X135725Y456167D01*
X135933Y456375D01*
X136017Y456667D01*
X135933Y456958D01*
X135683Y457208D01*
X135308Y457333D01*
X134892D01*
X134642Y457417D01*
X134433Y457625D01*
X134350Y457917D01*
X134475Y458208D01*
X134767Y458417D01*
X135100Y458500D01*
X135433Y458417D01*
X135725Y458208D01*
X135850Y457917D01*
X135767Y457625D01*
X135558Y457417D01*
X135308Y457333D01*
X134892D01*
X134517Y457208D01*
X134267Y456958D01*
X134183Y456667D01*
X134267Y456375D01*
X134475Y456167D01*
X134808Y456042D01*
X135100Y456000D01*
G01X121100Y450267D02*
X118600D01*
Y451267D01*
X118725Y451600D01*
X119017Y451850D01*
X119350Y451933D01*
X119683Y451850D01*
X119933Y451642D01*
X120058Y451267D01*
Y450267D01*
G01X121100Y454200D02*
X121058Y453867D01*
X120892Y453575D01*
X120642Y453325D01*
X120350Y453158D01*
X120017Y453075D01*
X119683D01*
X119350Y453158D01*
X119058Y453325D01*
X118808Y453575D01*
X118642Y453867D01*
X118600Y454200D01*
X118642Y454533D01*
X118808Y454825D01*
X119058Y455075D01*
X119350Y455242D01*
X119683Y455325D01*
X120017D01*
X120350Y455242D01*
X120642Y455075D01*
X120892Y454825D01*
X121058Y454533D01*
X121100Y454200D01*
G01X120433Y454533D02*
X121100Y455033D01*
G01Y457217D02*
X120558Y457300D01*
X120100Y457425D01*
X119683Y457592D01*
X119225Y457800D01*
X118600Y458133D01*
Y456467D01*
G01X114850Y465300D02*
X93150D01*
G01X103008Y489667D02*
X102883Y489417D01*
X102800Y489125D01*
Y488792D01*
X102925Y488417D01*
X103133Y488125D01*
X103383Y487917D01*
X103800Y487750D01*
X104175Y487708D01*
X104550Y487792D01*
X104800Y487917D01*
X105050Y488167D01*
X105217Y488458D01*
X105300Y488750D01*
Y489042D01*
X105217Y489333D01*
X105092Y489583D01*
X104925Y489792D01*
G01X103217Y491058D02*
X102967Y491308D01*
X102842Y491600D01*
X102800Y491933D01*
X102883Y492350D01*
X103092Y492642D01*
X103342Y492725D01*
X103592Y492683D01*
X103800Y492517D01*
X104217Y491683D01*
X104508Y491308D01*
X104925Y491058D01*
X105300Y490975D01*
Y492725D01*
G01X104925Y494033D02*
X105133Y494283D01*
X105258Y494575D01*
X105300Y494950D01*
X105217Y495325D01*
X105050Y495617D01*
X104758Y495825D01*
X104425Y495867D01*
X104092Y495783D01*
X103883Y495575D01*
X103717Y495283D01*
X103675Y494992D01*
X103717Y494700D01*
X103883Y494325D01*
X102800Y494450D01*
Y495575D01*
G01X105300Y498050D02*
X105258Y498342D01*
X105133Y498675D01*
X104925Y498883D01*
X104633Y498967D01*
X104342Y498883D01*
X104092Y498633D01*
X103967Y498258D01*
Y497842D01*
X103883Y497592D01*
X103675Y497383D01*
X103383Y497300D01*
X103092Y497425D01*
X102883Y497717D01*
X102800Y498050D01*
X102883Y498383D01*
X103092Y498675D01*
X103383Y498800D01*
X103675Y498717D01*
X103883Y498508D01*
X103967Y498258D01*
Y497842D01*
X104092Y497467D01*
X104342Y497217D01*
X104633Y497133D01*
X104925Y497217D01*
X105133Y497425D01*
X105258Y497758D01*
X105300Y498050D01*
G01X82250Y497500D02*
X97750D01*
Y467500D01*
X82250D01*
Y497500D01*
G01X107117Y541100D02*
Y543600D01*
X108117D01*
X108450Y543475D01*
X108700Y543183D01*
X108783Y542850D01*
X108700Y542517D01*
X108492Y542267D01*
X108117Y542142D01*
X107117D01*
G01X110217Y541100D02*
Y543600D01*
X111258D01*
X111592Y543475D01*
X111800Y543308D01*
X111883Y542975D01*
X111800Y542642D01*
X111550Y542433D01*
X111258Y542308D01*
X110217D01*
G01X111258D02*
X111883Y541100D01*
G01X113442Y541392D02*
X113733Y541183D01*
X114067Y541100D01*
X114400Y541183D01*
X114692Y541433D01*
X114900Y541808D01*
X114983Y542183D01*
Y542642D01*
X114900Y543017D01*
X114692Y543350D01*
X114442Y543517D01*
X114150Y543600D01*
X113817Y543517D01*
X113567Y543350D01*
X113400Y543100D01*
X113317Y542767D01*
X113400Y542475D01*
X113608Y542183D01*
X113858Y542017D01*
X114150Y541975D01*
X114483Y542058D01*
X114733Y542267D01*
X114983Y542642D01*
G01X116542Y541392D02*
X116833Y541183D01*
X117167Y541100D01*
X117500Y541183D01*
X117792Y541433D01*
X118000Y541808D01*
X118083Y542183D01*
Y542642D01*
X118000Y543017D01*
X117792Y543350D01*
X117542Y543517D01*
X117250Y543600D01*
X116917Y543517D01*
X116667Y543350D01*
X116500Y543100D01*
X116417Y542767D01*
X116500Y542475D01*
X116708Y542183D01*
X116958Y542017D01*
X117250Y541975D01*
X117583Y542058D01*
X117833Y542267D01*
X118083Y542642D01*
G01X104100Y547600D02*
Y551600D01*
X96700D01*
G01X83517Y519000D02*
Y521500D01*
X84517D01*
X84850Y521375D01*
X85100Y521083D01*
X85183Y520750D01*
X85100Y520417D01*
X84892Y520167D01*
X84517Y520042D01*
X83517D01*
G01X86617Y519000D02*
Y521500D01*
X87658D01*
X87992Y521375D01*
X88200Y521208D01*
X88283Y520875D01*
X88200Y520542D01*
X87950Y520333D01*
X87658Y520208D01*
X86617D01*
G01X87658D02*
X88283Y519000D01*
G01X89842Y519292D02*
X90133Y519083D01*
X90467Y519000D01*
X90800Y519083D01*
X91092Y519333D01*
X91300Y519708D01*
X91383Y520083D01*
Y520542D01*
X91300Y520917D01*
X91092Y521250D01*
X90842Y521417D01*
X90550Y521500D01*
X90217Y521417D01*
X89967Y521250D01*
X89800Y521000D01*
X89717Y520667D01*
X89800Y520375D01*
X90008Y520083D01*
X90258Y519917D01*
X90550Y519875D01*
X90883Y519958D01*
X91133Y520167D01*
X91383Y520542D01*
G01X93650Y519000D02*
X93942Y519042D01*
X94275Y519167D01*
X94483Y519375D01*
X94567Y519667D01*
X94483Y519958D01*
X94233Y520208D01*
X93858Y520333D01*
X93442D01*
X93192Y520417D01*
X92983Y520625D01*
X92900Y520917D01*
X93025Y521208D01*
X93317Y521417D01*
X93650Y521500D01*
X93983Y521417D01*
X94275Y521208D01*
X94400Y520917D01*
X94317Y520625D01*
X94108Y520417D01*
X93858Y520333D01*
X93442D01*
X93067Y520208D01*
X92817Y519958D01*
X92733Y519667D01*
X92817Y519375D01*
X93025Y519167D01*
X93358Y519042D01*
X93650Y519000D01*
G01X130000Y538850D02*
X132500D01*
G01X130000Y537892D02*
Y539808D01*
G01X132500Y541117D02*
X130000D01*
Y542117D01*
X130125Y542450D01*
X130417Y542700D01*
X130750Y542783D01*
X131083Y542700D01*
X131333Y542492D01*
X131458Y542117D01*
Y541117D01*
G01X130417Y544258D02*
X130167Y544508D01*
X130042Y544800D01*
X130000Y545133D01*
X130083Y545550D01*
X130292Y545842D01*
X130542Y545925D01*
X130792Y545883D01*
X131000Y545717D01*
X131417Y544883D01*
X131708Y544508D01*
X132125Y544258D01*
X132500Y544175D01*
Y545925D01*
G01Y548650D02*
X130000D01*
X131792Y547108D01*
Y549192D01*
G01X132500Y522467D02*
X130000D01*
Y523467D01*
X130125Y523800D01*
X130417Y524050D01*
X130750Y524133D01*
X131083Y524050D01*
X131333Y523842D01*
X131458Y523467D01*
Y522467D01*
G01X132500Y525567D02*
X130000D01*
Y526608D01*
X130125Y526942D01*
X130292Y527150D01*
X130625Y527233D01*
X130958Y527150D01*
X131167Y526900D01*
X131292Y526608D01*
Y525567D01*
G01Y526608D02*
X132500Y527233D01*
G01Y529500D02*
X130000D01*
X130500Y529000D01*
G01X132500D02*
Y530000D01*
G01X130000Y532600D02*
X130083Y532267D01*
X130292Y532017D01*
X130542Y531850D01*
X130875Y531725D01*
X131250Y531683D01*
X131625Y531725D01*
X131958Y531850D01*
X132208Y532017D01*
X132417Y532267D01*
X132500Y532600D01*
X132417Y532933D01*
X132208Y533183D01*
X131958Y533350D01*
X131625Y533475D01*
X131250Y533517D01*
X130875Y533475D01*
X130542Y533350D01*
X130292Y533183D01*
X130083Y532933D01*
X130000Y532600D01*
G01X132125Y534783D02*
X132333Y535033D01*
X132458Y535325D01*
X132500Y535700D01*
X132417Y536075D01*
X132250Y536367D01*
X131958Y536575D01*
X131625Y536617D01*
X131292Y536533D01*
X131083Y536325D01*
X130917Y536033D01*
X130875Y535742D01*
X130917Y535450D01*
X131083Y535075D01*
X130000Y535200D01*
Y536325D01*
G01X102500Y523017D02*
X100000D01*
Y524017D01*
X100125Y524350D01*
X100417Y524600D01*
X100750Y524683D01*
X101083Y524600D01*
X101333Y524392D01*
X101458Y524017D01*
Y523017D01*
G01X102500Y526117D02*
X100000D01*
Y527158D01*
X100125Y527492D01*
X100292Y527700D01*
X100625Y527783D01*
X100958Y527700D01*
X101167Y527450D01*
X101292Y527158D01*
Y526117D01*
G01Y527158D02*
X102500Y527783D01*
G01X102208Y529342D02*
X102417Y529633D01*
X102500Y529967D01*
X102417Y530300D01*
X102167Y530592D01*
X101792Y530800D01*
X101417Y530883D01*
X100958D01*
X100583Y530800D01*
X100250Y530592D01*
X100083Y530342D01*
X100000Y530050D01*
X100083Y529717D01*
X100250Y529467D01*
X100500Y529300D01*
X100833Y529217D01*
X101125Y529300D01*
X101417Y529508D01*
X101583Y529758D01*
X101625Y530050D01*
X101542Y530383D01*
X101333Y530633D01*
X100958Y530883D01*
G01X102500Y533650D02*
X100000D01*
X101792Y532108D01*
Y534192D01*
G01X98100Y535900D02*
X94100D01*
Y528500D01*
G01X107117Y545300D02*
Y547800D01*
X108117D01*
X108450Y547675D01*
X108700Y547383D01*
X108783Y547050D01*
X108700Y546717D01*
X108492Y546467D01*
X108117Y546342D01*
X107117D01*
G01X111967Y547592D02*
X111717Y547717D01*
X111425Y547800D01*
X111092D01*
X110717Y547675D01*
X110425Y547467D01*
X110217Y547217D01*
X110050Y546800D01*
X110008Y546425D01*
X110092Y546050D01*
X110217Y545800D01*
X110467Y545550D01*
X110758Y545383D01*
X111050Y545300D01*
X111342D01*
X111633Y545383D01*
X111883Y545508D01*
X112092Y545675D01*
G01X114150Y545300D02*
X114442Y545342D01*
X114775Y545467D01*
X114983Y545675D01*
X115067Y545967D01*
X114983Y546258D01*
X114733Y546508D01*
X114358Y546633D01*
X113942D01*
X113692Y546717D01*
X113483Y546925D01*
X113400Y547217D01*
X113525Y547508D01*
X113817Y547717D01*
X114150Y547800D01*
X114483Y547717D01*
X114775Y547508D01*
X114900Y547217D01*
X114817Y546925D01*
X114608Y546717D01*
X114358Y546633D01*
X113942D01*
X113567Y546508D01*
X113317Y546258D01*
X113233Y545967D01*
X113317Y545675D01*
X113525Y545467D01*
X113858Y545342D01*
X114150Y545300D01*
G01X116333Y545675D02*
X116583Y545467D01*
X116875Y545342D01*
X117250Y545300D01*
X117625Y545383D01*
X117917Y545550D01*
X118125Y545842D01*
X118167Y546175D01*
X118083Y546508D01*
X117875Y546717D01*
X117583Y546883D01*
X117292Y546925D01*
X117000Y546883D01*
X116625Y546717D01*
X116750Y547800D01*
X117875D01*
G01X83517Y523500D02*
Y526000D01*
X84517D01*
X84850Y525875D01*
X85100Y525583D01*
X85183Y525250D01*
X85100Y524917D01*
X84892Y524667D01*
X84517Y524542D01*
X83517D01*
G01X88367Y525792D02*
X88117Y525917D01*
X87825Y526000D01*
X87492D01*
X87117Y525875D01*
X86825Y525667D01*
X86617Y525417D01*
X86450Y525000D01*
X86408Y524625D01*
X86492Y524250D01*
X86617Y524000D01*
X86867Y523750D01*
X87158Y523583D01*
X87450Y523500D01*
X87742D01*
X88033Y523583D01*
X88283Y523708D01*
X88492Y523875D01*
G01X90550Y523500D02*
X90842Y523542D01*
X91175Y523667D01*
X91383Y523875D01*
X91467Y524167D01*
X91383Y524458D01*
X91133Y524708D01*
X90758Y524833D01*
X90342D01*
X90092Y524917D01*
X89883Y525125D01*
X89800Y525417D01*
X89925Y525708D01*
X90217Y525917D01*
X90550Y526000D01*
X90883Y525917D01*
X91175Y525708D01*
X91300Y525417D01*
X91217Y525125D01*
X91008Y524917D01*
X90758Y524833D01*
X90342D01*
X89967Y524708D01*
X89717Y524458D01*
X89633Y524167D01*
X89717Y523875D01*
X89925Y523667D01*
X90258Y523542D01*
X90550Y523500D01*
G01X93567D02*
X93650Y524042D01*
X93775Y524500D01*
X93942Y524917D01*
X94150Y525375D01*
X94483Y526000D01*
X92817D01*
G01X104017Y536000D02*
Y538500D01*
X105017D01*
X105350Y538375D01*
X105600Y538083D01*
X105683Y537750D01*
X105600Y537417D01*
X105392Y537167D01*
X105017Y537042D01*
X104017D01*
G01X108867Y538292D02*
X108617Y538417D01*
X108325Y538500D01*
X107992D01*
X107617Y538375D01*
X107325Y538167D01*
X107117Y537917D01*
X106950Y537500D01*
X106908Y537125D01*
X106992Y536750D01*
X107117Y536500D01*
X107367Y536250D01*
X107658Y536083D01*
X107950Y536000D01*
X108242D01*
X108533Y536083D01*
X108783Y536208D01*
X108992Y536375D01*
G01X111050Y536000D02*
X111342Y536042D01*
X111675Y536167D01*
X111883Y536375D01*
X111967Y536667D01*
X111883Y536958D01*
X111633Y537208D01*
X111258Y537333D01*
X110842D01*
X110592Y537417D01*
X110383Y537625D01*
X110300Y537917D01*
X110425Y538208D01*
X110717Y538417D01*
X111050Y538500D01*
X111383Y538417D01*
X111675Y538208D01*
X111800Y537917D01*
X111717Y537625D01*
X111508Y537417D01*
X111258Y537333D01*
X110842D01*
X110467Y537208D01*
X110217Y536958D01*
X110133Y536667D01*
X110217Y536375D01*
X110425Y536167D01*
X110758Y536042D01*
X111050Y536000D01*
G01X113442Y536292D02*
X113733Y536083D01*
X114067Y536000D01*
X114400Y536083D01*
X114692Y536333D01*
X114900Y536708D01*
X114983Y537083D01*
Y537542D01*
X114900Y537917D01*
X114692Y538250D01*
X114442Y538417D01*
X114150Y538500D01*
X113817Y538417D01*
X113567Y538250D01*
X113400Y538000D01*
X113317Y537667D01*
X113400Y537375D01*
X113608Y537083D01*
X113858Y536917D01*
X114150Y536875D01*
X114483Y536958D01*
X114733Y537167D01*
X114983Y537542D01*
G01X85017Y502000D02*
Y504500D01*
X86017D01*
X86350Y504375D01*
X86600Y504083D01*
X86683Y503750D01*
X86600Y503417D01*
X86392Y503167D01*
X86017Y503042D01*
X85017D01*
G01X88117Y502000D02*
Y504500D01*
X89158D01*
X89492Y504375D01*
X89700Y504208D01*
X89783Y503875D01*
X89700Y503542D01*
X89450Y503333D01*
X89158Y503208D01*
X88117D01*
G01X89158D02*
X89783Y502000D01*
G01X91258Y503042D02*
X91550Y503333D01*
X91800Y503500D01*
X92133Y503583D01*
X92425Y503500D01*
X92633Y503333D01*
X92800Y503083D01*
X92842Y502792D01*
X92800Y502542D01*
X92633Y502292D01*
X92383Y502083D01*
X92092Y502000D01*
X91758Y502083D01*
X91467Y502333D01*
X91300Y502708D01*
X91258Y503125D01*
X91342Y503667D01*
X91467Y503958D01*
X91675Y504250D01*
X91967Y504458D01*
X92258Y504500D01*
X92550Y504417D01*
X92758Y504208D01*
G01X95150Y502000D02*
Y504500D01*
X94650Y504000D01*
G01Y502000D02*
X95650D01*
G01X93300Y556900D02*
Y548900D01*
X80900D01*
Y556900D01*
X93300D01*
G01X91600Y552900D02*
X93100Y551400D01*
G01X91600Y552900D02*
X93100Y554400D01*
G01X99500Y572517D02*
X97000D01*
Y573517D01*
X97125Y573850D01*
X97417Y574100D01*
X97750Y574183D01*
X98083Y574100D01*
X98333Y573892D01*
X98458Y573517D01*
Y572517D01*
G01X97208Y577367D02*
X97083Y577117D01*
X97000Y576825D01*
Y576492D01*
X97125Y576117D01*
X97333Y575825D01*
X97583Y575617D01*
X98000Y575450D01*
X98375Y575408D01*
X98750Y575492D01*
X99000Y575617D01*
X99250Y575867D01*
X99417Y576158D01*
X99500Y576450D01*
Y576742D01*
X99417Y577033D01*
X99292Y577283D01*
X99125Y577492D01*
G01X99208Y578842D02*
X99417Y579133D01*
X99500Y579467D01*
X99417Y579800D01*
X99167Y580092D01*
X98792Y580300D01*
X98417Y580383D01*
X97958D01*
X97583Y580300D01*
X97250Y580092D01*
X97083Y579842D01*
X97000Y579550D01*
X97083Y579217D01*
X97250Y578967D01*
X97500Y578800D01*
X97833Y578717D01*
X98125Y578800D01*
X98417Y579008D01*
X98583Y579258D01*
X98625Y579550D01*
X98542Y579883D01*
X98333Y580133D01*
X97958Y580383D01*
G01X98458Y581858D02*
X98167Y582150D01*
X98000Y582400D01*
X97917Y582733D01*
X98000Y583025D01*
X98167Y583233D01*
X98417Y583400D01*
X98708Y583442D01*
X98958Y583400D01*
X99208Y583233D01*
X99417Y582983D01*
X99500Y582692D01*
X99417Y582358D01*
X99167Y582067D01*
X98792Y581900D01*
X98375Y581858D01*
X97833Y581942D01*
X97542Y582067D01*
X97250Y582275D01*
X97042Y582567D01*
X97000Y582858D01*
X97083Y583150D01*
X97292Y583358D01*
G01X123900Y599000D02*
Y596500D01*
G01X122942Y599000D02*
X124858D01*
G01X126167Y596500D02*
Y599000D01*
X127167D01*
X127500Y598875D01*
X127750Y598583D01*
X127833Y598250D01*
X127750Y597917D01*
X127542Y597667D01*
X127167Y597542D01*
X126167D01*
G01X129308D02*
X129600Y597833D01*
X129850Y598000D01*
X130183Y598083D01*
X130475Y598000D01*
X130683Y597833D01*
X130850Y597583D01*
X130892Y597292D01*
X130850Y597042D01*
X130683Y596792D01*
X130433Y596583D01*
X130142Y596500D01*
X129808Y596583D01*
X129517Y596833D01*
X129350Y597208D01*
X129308Y597625D01*
X129392Y598167D01*
X129517Y598458D01*
X129725Y598750D01*
X130017Y598958D01*
X130308Y599000D01*
X130600Y598917D01*
X130808Y598708D01*
G01X106900Y599500D02*
Y597000D01*
G01X105942Y599500D02*
X107858D01*
G01X109167Y597000D02*
Y599500D01*
X110167D01*
X110500Y599375D01*
X110750Y599083D01*
X110833Y598750D01*
X110750Y598417D01*
X110542Y598167D01*
X110167Y598042D01*
X109167D01*
G01X113100Y597000D02*
Y599500D01*
X112600Y599000D01*
G01Y597000D02*
X113600D01*
G01X109300Y583867D02*
X106800D01*
Y584908D01*
X106925Y585242D01*
X107092Y585450D01*
X107425Y585533D01*
X107758Y585450D01*
X107967Y585200D01*
X108092Y584908D01*
Y583867D01*
G01Y584908D02*
X109300Y585533D01*
G01Y587800D02*
X106800D01*
X107300Y587300D01*
G01X109300D02*
Y588300D01*
G01X108258Y590108D02*
X107967Y590400D01*
X107800Y590650D01*
X107717Y590983D01*
X107800Y591275D01*
X107967Y591483D01*
X108217Y591650D01*
X108508Y591692D01*
X108758Y591650D01*
X109008Y591483D01*
X109217Y591233D01*
X109300Y590942D01*
X109217Y590608D01*
X108967Y590317D01*
X108592Y590150D01*
X108175Y590108D01*
X107633Y590192D01*
X107342Y590317D01*
X107050Y590525D01*
X106842Y590817D01*
X106800Y591108D01*
X106883Y591400D01*
X107092Y591608D01*
G01X114800Y583196D02*
X118800D01*
Y590596D01*
G01X130500Y573567D02*
X128000D01*
Y574608D01*
X128125Y574942D01*
X128292Y575150D01*
X128625Y575233D01*
X128958Y575150D01*
X129167Y574900D01*
X129292Y574608D01*
Y573567D01*
G01Y574608D02*
X130500Y575233D01*
G01X130000Y576583D02*
X130292Y576833D01*
X130458Y577167D01*
X130500Y577542D01*
X130458Y577875D01*
X130250Y578208D01*
X130000Y578417D01*
X129750Y578458D01*
X129458Y578375D01*
X129250Y578083D01*
X129167Y577792D01*
Y577417D01*
G01Y577792D02*
X129042Y578042D01*
X128833Y578250D01*
X128583Y578333D01*
X128333Y578250D01*
X128125Y578042D01*
X128000Y577667D01*
X128042Y577292D01*
X128208Y576917D01*
G01X129458Y579808D02*
X129167Y580100D01*
X129000Y580350D01*
X128917Y580683D01*
X129000Y580975D01*
X129167Y581183D01*
X129417Y581350D01*
X129708Y581392D01*
X129958Y581350D01*
X130208Y581183D01*
X130417Y580933D01*
X130500Y580642D01*
X130417Y580308D01*
X130167Y580017D01*
X129792Y579850D01*
X129375Y579808D01*
X128833Y579892D01*
X128542Y580017D01*
X128250Y580225D01*
X128042Y580517D01*
X128000Y580808D01*
X128083Y581100D01*
X128292Y581308D01*
G01X126900Y583196D02*
X130900D01*
Y590596D01*
G01X126000Y571517D02*
X123500D01*
Y572558D01*
X123625Y572892D01*
X123792Y573100D01*
X124125Y573183D01*
X124458Y573100D01*
X124667Y572850D01*
X124792Y572558D01*
Y571517D01*
G01Y572558D02*
X126000Y573183D01*
G01Y575450D02*
X123500D01*
X124000Y574950D01*
G01X126000D02*
Y575950D01*
G01X123917Y577758D02*
X123667Y578008D01*
X123542Y578300D01*
X123500Y578633D01*
X123583Y579050D01*
X123792Y579342D01*
X124042Y579425D01*
X124292Y579383D01*
X124500Y579217D01*
X124917Y578383D01*
X125208Y578008D01*
X125625Y577758D01*
X126000Y577675D01*
Y579425D01*
G01Y581650D02*
X125958Y581942D01*
X125833Y582275D01*
X125625Y582483D01*
X125333Y582567D01*
X125042Y582483D01*
X124792Y582233D01*
X124667Y581858D01*
Y581442D01*
X124583Y581192D01*
X124375Y580983D01*
X124083Y580900D01*
X123792Y581025D01*
X123583Y581317D01*
X123500Y581650D01*
X123583Y581983D01*
X123792Y582275D01*
X124083Y582400D01*
X124375Y582317D01*
X124583Y582108D01*
X124667Y581858D01*
Y581442D01*
X124792Y581067D01*
X125042Y580817D01*
X125333Y580733D01*
X125625Y580817D01*
X125833Y581025D01*
X125958Y581358D01*
X126000Y581650D01*
G01X126900Y590604D02*
X122900D01*
Y583204D01*
G01X122100Y574367D02*
X119600D01*
Y575408D01*
X119725Y575742D01*
X119892Y575950D01*
X120225Y576033D01*
X120558Y575950D01*
X120767Y575700D01*
X120892Y575408D01*
Y574367D01*
G01Y575408D02*
X122100Y576033D01*
G01X121600Y577383D02*
X121892Y577633D01*
X122058Y577967D01*
X122100Y578342D01*
X122058Y578675D01*
X121850Y579008D01*
X121600Y579217D01*
X121350Y579258D01*
X121058Y579175D01*
X120850Y578883D01*
X120767Y578592D01*
Y578217D01*
G01Y578592D02*
X120642Y578842D01*
X120433Y579050D01*
X120183Y579133D01*
X119933Y579050D01*
X119725Y578842D01*
X119600Y578467D01*
X119642Y578092D01*
X119808Y577717D01*
G01X121725Y580483D02*
X121933Y580733D01*
X122058Y581025D01*
X122100Y581400D01*
X122017Y581775D01*
X121850Y582067D01*
X121558Y582275D01*
X121225Y582317D01*
X120892Y582233D01*
X120683Y582025D01*
X120517Y581733D01*
X120475Y581442D01*
X120517Y581150D01*
X120683Y580775D01*
X119600Y580900D01*
Y582025D01*
G01X122800Y590604D02*
X118800D01*
Y583204D01*
G01X94500Y577367D02*
X92000D01*
Y578367D01*
X92125Y578700D01*
X92417Y578950D01*
X92750Y579033D01*
X93083Y578950D01*
X93333Y578742D01*
X93458Y578367D01*
Y577367D01*
G01X94500Y580467D02*
X92000D01*
Y581508D01*
X92125Y581842D01*
X92292Y582050D01*
X92625Y582133D01*
X92958Y582050D01*
X93167Y581800D01*
X93292Y581508D01*
Y580467D01*
G01Y581508D02*
X94500Y582133D01*
G01Y584400D02*
X92000D01*
X92500Y583900D01*
G01X94500D02*
Y584900D01*
G01Y587500D02*
X92000D01*
X92500Y587000D01*
G01X94500D02*
Y588000D01*
G01X92417Y589808D02*
X92167Y590058D01*
X92042Y590350D01*
X92000Y590683D01*
X92083Y591100D01*
X92292Y591392D01*
X92542Y591475D01*
X92792Y591433D01*
X93000Y591267D01*
X93417Y590433D01*
X93708Y590058D01*
X94125Y589808D01*
X94500Y589725D01*
Y591475D01*
G01X89300Y567800D02*
X93300D01*
Y575200D01*
G01X89100Y567900D02*
Y571900D01*
X81700D01*
G01X132500Y550967D02*
X130000D01*
Y551967D01*
X130125Y552300D01*
X130417Y552550D01*
X130750Y552633D01*
X131083Y552550D01*
X131333Y552342D01*
X131458Y551967D01*
Y550967D01*
G01X132500Y554067D02*
X130000D01*
Y555108D01*
X130125Y555442D01*
X130292Y555650D01*
X130625Y555733D01*
X130958Y555650D01*
X131167Y555400D01*
X131292Y555108D01*
Y554067D01*
G01Y555108D02*
X132500Y555733D01*
G01Y558000D02*
X130000D01*
X130500Y557500D01*
G01X132500D02*
Y558500D01*
G01X130000Y561100D02*
X130083Y560767D01*
X130292Y560517D01*
X130542Y560350D01*
X130875Y560225D01*
X131250Y560183D01*
X131625Y560225D01*
X131958Y560350D01*
X132208Y560517D01*
X132417Y560767D01*
X132500Y561100D01*
X132417Y561433D01*
X132208Y561683D01*
X131958Y561850D01*
X131625Y561975D01*
X131250Y562017D01*
X130875Y561975D01*
X130542Y561850D01*
X130292Y561683D01*
X130083Y561433D01*
X130000Y561100D01*
G01X132500Y564117D02*
X131958Y564200D01*
X131500Y564325D01*
X131083Y564492D01*
X130625Y564700D01*
X130000Y565033D01*
Y563367D01*
G01X84500Y590567D02*
X82000D01*
Y591608D01*
X82125Y591942D01*
X82292Y592150D01*
X82625Y592233D01*
X82958Y592150D01*
X83167Y591900D01*
X83292Y591608D01*
Y590567D01*
G01Y591608D02*
X84500Y592233D01*
G01Y594500D02*
X82000D01*
X82500Y594000D01*
G01X84500D02*
Y595000D01*
G01X82417Y596808D02*
X82167Y597058D01*
X82042Y597350D01*
X82000Y597683D01*
X82083Y598100D01*
X82292Y598392D01*
X82542Y598475D01*
X82792Y598433D01*
X83000Y598267D01*
X83417Y597433D01*
X83708Y597058D01*
X84125Y596808D01*
X84500Y596725D01*
Y598475D01*
G01X95065Y599471D02*
X91065D01*
Y592071D01*
G01X89000Y593067D02*
X86500D01*
Y594108D01*
X86625Y594442D01*
X86792Y594650D01*
X87125Y594733D01*
X87458Y594650D01*
X87667Y594400D01*
X87792Y594108D01*
Y593067D01*
G01Y594108D02*
X89000Y594733D01*
G01Y597000D02*
X86500D01*
X87000Y596500D01*
G01X89000D02*
Y597500D01*
G01X86500Y600100D02*
X86583Y599767D01*
X86792Y599517D01*
X87042Y599350D01*
X87375Y599225D01*
X87750Y599183D01*
X88125Y599225D01*
X88458Y599350D01*
X88708Y599517D01*
X88917Y599767D01*
X89000Y600100D01*
X88917Y600433D01*
X88708Y600683D01*
X88458Y600850D01*
X88125Y600975D01*
X87750Y601017D01*
X87375Y600975D01*
X87042Y600850D01*
X86792Y600683D01*
X86583Y600433D01*
X86500Y600100D01*
G01X99265Y599471D02*
X95265D01*
Y592071D01*
G01X117950Y570000D02*
X117617Y570042D01*
X117325Y570208D01*
X117075Y570458D01*
X116908Y570750D01*
X116825Y571083D01*
Y571417D01*
X116908Y571750D01*
X117075Y572042D01*
X117325Y572292D01*
X117617Y572458D01*
X117950Y572500D01*
X118283Y572458D01*
X118575Y572292D01*
X118825Y572042D01*
X118992Y571750D01*
X119075Y571417D01*
Y571083D01*
X118992Y570750D01*
X118825Y570458D01*
X118575Y570208D01*
X118283Y570042D01*
X117950Y570000D01*
G01X118283Y570667D02*
X118783Y570000D01*
G01X121050D02*
Y572500D01*
X120550Y572000D01*
G01Y570000D02*
X121550D01*
G01X101268Y564366D02*
X115268D01*
G01X101268Y577366D02*
Y564366D01*
G01X115268Y577366D02*
X101268D01*
G01X115268Y564366D02*
Y577366D01*
G01X89000Y580517D02*
X86500D01*
Y581517D01*
X86625Y581850D01*
X86917Y582100D01*
X87250Y582183D01*
X87583Y582100D01*
X87833Y581892D01*
X87958Y581517D01*
Y580517D01*
G01X86708Y585367D02*
X86583Y585117D01*
X86500Y584825D01*
Y584492D01*
X86625Y584117D01*
X86833Y583825D01*
X87083Y583617D01*
X87500Y583450D01*
X87875Y583408D01*
X88250Y583492D01*
X88500Y583617D01*
X88750Y583867D01*
X88917Y584158D01*
X89000Y584450D01*
Y584742D01*
X88917Y585033D01*
X88792Y585283D01*
X88625Y585492D01*
G01X88708Y586842D02*
X88917Y587133D01*
X89000Y587467D01*
X88917Y587800D01*
X88667Y588092D01*
X88292Y588300D01*
X87917Y588383D01*
X87458D01*
X87083Y588300D01*
X86750Y588092D01*
X86583Y587842D01*
X86500Y587550D01*
X86583Y587217D01*
X86750Y586967D01*
X87000Y586800D01*
X87333Y586717D01*
X87625Y586800D01*
X87917Y587008D01*
X88083Y587258D01*
X88125Y587550D01*
X88042Y587883D01*
X87833Y588133D01*
X87458Y588383D01*
G01X88500Y589733D02*
X88792Y589983D01*
X88958Y590317D01*
X89000Y590692D01*
X88958Y591025D01*
X88750Y591358D01*
X88500Y591567D01*
X88250Y591608D01*
X87958Y591525D01*
X87750Y591233D01*
X87667Y590942D01*
Y590567D01*
G01Y590942D02*
X87542Y591192D01*
X87333Y591400D01*
X87083Y591483D01*
X86833Y591400D01*
X86625Y591192D01*
X86500Y590817D01*
X86542Y590442D01*
X86708Y590067D01*
G01X115208Y597367D02*
X115083Y597117D01*
X115000Y596825D01*
Y596492D01*
X115125Y596117D01*
X115333Y595825D01*
X115583Y595617D01*
X116000Y595450D01*
X116375Y595408D01*
X116750Y595492D01*
X117000Y595617D01*
X117250Y595867D01*
X117417Y596158D01*
X117500Y596450D01*
Y596742D01*
X117417Y597033D01*
X117292Y597283D01*
X117125Y597492D01*
G01X117500Y599550D02*
X117458Y599842D01*
X117333Y600175D01*
X117125Y600383D01*
X116833Y600467D01*
X116542Y600383D01*
X116292Y600133D01*
X116167Y599758D01*
Y599342D01*
X116083Y599092D01*
X115875Y598883D01*
X115583Y598800D01*
X115292Y598925D01*
X115083Y599217D01*
X115000Y599550D01*
X115083Y599883D01*
X115292Y600175D01*
X115583Y600300D01*
X115875Y600217D01*
X116083Y600008D01*
X116167Y599758D01*
Y599342D01*
X116292Y598967D01*
X116542Y598717D01*
X116833Y598633D01*
X117125Y598717D01*
X117333Y598925D01*
X117458Y599258D01*
X117500Y599550D01*
G01X111367Y581292D02*
X111117Y581417D01*
X110825Y581500D01*
X110492D01*
X110117Y581375D01*
X109825Y581167D01*
X109617Y580917D01*
X109450Y580500D01*
X109408Y580125D01*
X109492Y579750D01*
X109617Y579500D01*
X109867Y579250D01*
X110158Y579083D01*
X110450Y579000D01*
X110742D01*
X111033Y579083D01*
X111283Y579208D01*
X111492Y579375D01*
G01X113467Y579000D02*
X113550Y579542D01*
X113675Y580000D01*
X113842Y580417D01*
X114050Y580875D01*
X114383Y581500D01*
X112717D01*
G01X101708Y587767D02*
X101583Y587517D01*
X101500Y587225D01*
Y586892D01*
X101625Y586517D01*
X101833Y586225D01*
X102083Y586017D01*
X102500Y585850D01*
X102875Y585808D01*
X103250Y585892D01*
X103500Y586017D01*
X103750Y586267D01*
X103917Y586558D01*
X104000Y586850D01*
Y587142D01*
X103917Y587433D01*
X103792Y587683D01*
X103625Y587892D01*
G01Y589033D02*
X103833Y589283D01*
X103958Y589575D01*
X104000Y589950D01*
X103917Y590325D01*
X103750Y590617D01*
X103458Y590825D01*
X103125Y590867D01*
X102792Y590783D01*
X102583Y590575D01*
X102417Y590283D01*
X102375Y589992D01*
X102417Y589700D01*
X102583Y589325D01*
X101500Y589450D01*
Y590575D01*
G01X107517Y549500D02*
Y552000D01*
X108517D01*
X108850Y551875D01*
X109100Y551583D01*
X109183Y551250D01*
X109100Y550917D01*
X108892Y550667D01*
X108517Y550542D01*
X107517D01*
G01X112367Y551792D02*
X112117Y551917D01*
X111825Y552000D01*
X111492D01*
X111117Y551875D01*
X110825Y551667D01*
X110617Y551417D01*
X110450Y551000D01*
X110408Y550625D01*
X110492Y550250D01*
X110617Y550000D01*
X110867Y549750D01*
X111158Y549583D01*
X111450Y549500D01*
X111742D01*
X112033Y549583D01*
X112283Y549708D01*
X112492Y549875D01*
G01X113842Y549792D02*
X114133Y549583D01*
X114467Y549500D01*
X114800Y549583D01*
X115092Y549833D01*
X115300Y550208D01*
X115383Y550583D01*
Y551042D01*
X115300Y551417D01*
X115092Y551750D01*
X114842Y551917D01*
X114550Y552000D01*
X114217Y551917D01*
X113967Y551750D01*
X113800Y551500D01*
X113717Y551167D01*
X113800Y550875D01*
X114008Y550583D01*
X114258Y550417D01*
X114550Y550375D01*
X114883Y550458D01*
X115133Y550667D01*
X115383Y551042D01*
G01X117567Y549500D02*
X117650Y550042D01*
X117775Y550500D01*
X117942Y550917D01*
X118150Y551375D01*
X118483Y552000D01*
X116817D01*
G01X84903Y639502D02*
Y600702D01*
G01X94000Y643533D02*
X95792D01*
X96167Y643700D01*
X96417Y644033D01*
X96500Y644450D01*
X96417Y644867D01*
X96167Y645200D01*
X95792Y645367D01*
X94000D01*
G01X96500Y647550D02*
X94000D01*
X94500Y647050D01*
G01X96500D02*
Y648050D01*
G01X107835Y651029D02*
X97835D01*
Y641229D01*
G01X131735Y607629D02*
X141235D01*
Y617729D01*
G01X107535Y607629D02*
X97835D01*
Y617229D01*
X97935D01*
X107535Y607629D01*
G01X99235Y624409D02*
X97235D01*
G01X99235Y634249D02*
X96235D01*
G01X110675Y649629D02*
Y651629D01*
G01X120520Y649629D02*
Y652629D01*
G01X130360Y649629D02*
Y651629D01*
G01X126425Y609029D02*
Y606029D01*
G01X116580Y609029D02*
Y607029D01*
G01X87000Y614850D02*
X89500D01*
G01X87000Y613892D02*
Y615808D01*
G01X89500Y617117D02*
X87000D01*
Y618117D01*
X87125Y618450D01*
X87417Y618700D01*
X87750Y618783D01*
X88083Y618700D01*
X88333Y618492D01*
X88458Y618117D01*
Y617117D01*
G01X89500Y621050D02*
X87000D01*
X87500Y620550D01*
G01X89500D02*
Y621550D01*
G01X88458Y623358D02*
X88167Y623650D01*
X88000Y623900D01*
X87917Y624233D01*
X88000Y624525D01*
X88167Y624733D01*
X88417Y624900D01*
X88708Y624942D01*
X88958Y624900D01*
X89208Y624733D01*
X89417Y624483D01*
X89500Y624192D01*
X89417Y623858D01*
X89167Y623567D01*
X88792Y623400D01*
X88375Y623358D01*
X87833Y623442D01*
X87542Y623567D01*
X87250Y623775D01*
X87042Y624067D01*
X87000Y624358D01*
X87083Y624650D01*
X87292Y624858D01*
G01X119350Y604000D02*
Y601500D01*
G01X118392Y604000D02*
X120308D01*
G01X121617Y601500D02*
Y604000D01*
X122617D01*
X122950Y603875D01*
X123200Y603583D01*
X123283Y603250D01*
X123200Y602917D01*
X122992Y602667D01*
X122617Y602542D01*
X121617D01*
G01X125550Y601500D02*
Y604000D01*
X125050Y603500D01*
G01Y601500D02*
X126050D01*
G01X128650Y604000D02*
X128317Y603917D01*
X128067Y603708D01*
X127900Y603458D01*
X127775Y603125D01*
X127733Y602750D01*
X127775Y602375D01*
X127900Y602042D01*
X128067Y601792D01*
X128317Y601583D01*
X128650Y601500D01*
X128983Y601583D01*
X129233Y601792D01*
X129400Y602042D01*
X129525Y602375D01*
X129567Y602750D01*
X129525Y603125D01*
X129400Y603458D01*
X129233Y603708D01*
X128983Y603917D01*
X128650Y604000D01*
G01X96500Y636117D02*
X94000D01*
Y637158D01*
X94125Y637492D01*
X94292Y637700D01*
X94625Y637783D01*
X94958Y637700D01*
X95167Y637450D01*
X95292Y637158D01*
Y636117D01*
G01Y637158D02*
X96500Y637783D01*
G01Y640050D02*
X96458Y640342D01*
X96333Y640675D01*
X96125Y640883D01*
X95833Y640967D01*
X95542Y640883D01*
X95292Y640633D01*
X95167Y640258D01*
Y639842D01*
X95083Y639592D01*
X94875Y639383D01*
X94583Y639300D01*
X94292Y639425D01*
X94083Y639717D01*
X94000Y640050D01*
X94083Y640383D01*
X94292Y640675D01*
X94583Y640800D01*
X94875Y640717D01*
X95083Y640508D01*
X95167Y640258D01*
Y639842D01*
X95292Y639467D01*
X95542Y639217D01*
X95833Y639133D01*
X96125Y639217D01*
X96333Y639425D01*
X96458Y639758D01*
X96500Y640050D01*
G01X85935Y632129D02*
Y637329D01*
G01X92935Y632129D02*
Y639929D01*
G01X85935Y632129D02*
X92935D01*
G01X85935Y645529D02*
Y636829D01*
G01X92935Y645529D02*
X85935D01*
G01X92935Y639129D02*
Y645529D01*
G01X89000Y606617D02*
X86500D01*
Y607658D01*
X86625Y607992D01*
X86792Y608200D01*
X87125Y608283D01*
X87458Y608200D01*
X87667Y607950D01*
X87792Y607658D01*
Y606617D01*
G01Y607658D02*
X89000Y608283D01*
G01Y611050D02*
X86500D01*
X88292Y609508D01*
Y611592D01*
G01X94465Y612371D02*
X90465D01*
Y604971D01*
G01X102033Y700000D02*
Y698208D01*
X102200Y697833D01*
X102533Y697583D01*
X102950Y697500D01*
X103367Y697583D01*
X103700Y697833D01*
X103867Y698208D01*
Y700000D01*
G01X105258Y699583D02*
X105508Y699833D01*
X105800Y699958D01*
X106133Y700000D01*
X106550Y699917D01*
X106842Y699708D01*
X106925Y699458D01*
X106883Y699208D01*
X106717Y699000D01*
X105883Y698583D01*
X105508Y698292D01*
X105258Y697875D01*
X105175Y697500D01*
X106925D01*
G01X100806Y673565D02*
X103306Y676065D01*
X105806Y673565D01*
X100806D01*
G01X88956D02*
Y695615D01*
X117556D01*
Y673565D01*
X88956D01*
G01X120208Y683817D02*
X120083Y683567D01*
X120000Y683275D01*
Y682942D01*
X120125Y682567D01*
X120333Y682275D01*
X120583Y682067D01*
X121000Y681900D01*
X121375Y681858D01*
X121750Y681942D01*
X122000Y682067D01*
X122250Y682317D01*
X122417Y682608D01*
X122500Y682900D01*
Y683192D01*
X122417Y683483D01*
X122292Y683733D01*
X122125Y683942D01*
G01X122500Y686000D02*
X120000D01*
X120500Y685500D01*
G01X122500D02*
Y686500D01*
G01Y689100D02*
X120000D01*
X120500Y688600D01*
G01X122500D02*
Y689600D01*
G01X141235Y641029D02*
Y651029D01*
X131335D01*
G01X98500Y658400D02*
X101000D01*
G01X98500Y657442D02*
Y659358D01*
G01X101000Y660667D02*
X98500D01*
Y661667D01*
X98625Y662000D01*
X98917Y662250D01*
X99250Y662333D01*
X99583Y662250D01*
X99833Y662042D01*
X99958Y661667D01*
Y660667D01*
G01X100625Y663683D02*
X100833Y663933D01*
X100958Y664225D01*
X101000Y664600D01*
X100917Y664975D01*
X100750Y665267D01*
X100458Y665475D01*
X100125Y665517D01*
X99792Y665433D01*
X99583Y665225D01*
X99417Y664933D01*
X99375Y664642D01*
X99417Y664350D01*
X99583Y663975D01*
X98500Y664100D01*
Y665225D01*
G01X96700Y669000D02*
Y673000D01*
X89300D01*
G01X97200Y667700D02*
X93200D01*
Y660300D01*
G01X119067Y700500D02*
Y703000D01*
X120108D01*
X120442Y702875D01*
X120650Y702708D01*
X120733Y702375D01*
X120650Y702042D01*
X120400Y701833D01*
X120108Y701708D01*
X119067D01*
G01X120108D02*
X120733Y700500D01*
G01X123000D02*
Y703000D01*
X122500Y702500D01*
G01Y700500D02*
X123500D01*
G01X125392Y700792D02*
X125683Y700583D01*
X126017Y700500D01*
X126350Y700583D01*
X126642Y700833D01*
X126850Y701208D01*
X126933Y701583D01*
Y702042D01*
X126850Y702417D01*
X126642Y702750D01*
X126392Y702917D01*
X126100Y703000D01*
X125767Y702917D01*
X125517Y702750D01*
X125350Y702500D01*
X125267Y702167D01*
X125350Y701875D01*
X125558Y701583D01*
X125808Y701417D01*
X126100Y701375D01*
X126433Y701458D01*
X126683Y701667D01*
X126933Y702042D01*
G01X123956Y694165D02*
Y690165D01*
X131356D01*
G01X119067Y696500D02*
Y699000D01*
X120108D01*
X120442Y698875D01*
X120650Y698708D01*
X120733Y698375D01*
X120650Y698042D01*
X120400Y697833D01*
X120108Y697708D01*
X119067D01*
G01X120108D02*
X120733Y696500D01*
G01X123000D02*
Y699000D01*
X122500Y698500D01*
G01Y696500D02*
X123500D01*
G01X126100D02*
X126392Y696542D01*
X126725Y696667D01*
X126933Y696875D01*
X127017Y697167D01*
X126933Y697458D01*
X126683Y697708D01*
X126308Y697833D01*
X125892D01*
X125642Y697917D01*
X125433Y698125D01*
X125350Y698417D01*
X125475Y698708D01*
X125767Y698917D01*
X126100Y699000D01*
X126433Y698917D01*
X126725Y698708D01*
X126850Y698417D01*
X126767Y698125D01*
X126558Y697917D01*
X126308Y697833D01*
X125892D01*
X125517Y697708D01*
X125267Y697458D01*
X125183Y697167D01*
X125267Y696875D01*
X125475Y696667D01*
X125808Y696542D01*
X126100Y696500D01*
G01X123856Y690065D02*
Y686065D01*
X131256D01*
G01X123856Y685665D02*
Y681665D01*
X131256D01*
G01X127335Y656629D02*
X131335D01*
Y664029D01*
G01X131535Y656629D02*
X135535D01*
Y664029D01*
G01X86067Y702000D02*
Y704500D01*
X87108D01*
X87442Y704375D01*
X87650Y704208D01*
X87733Y703875D01*
X87650Y703542D01*
X87400Y703333D01*
X87108Y703208D01*
X86067D01*
G01X87108D02*
X87733Y702000D01*
G01X90000D02*
X90292Y702042D01*
X90625Y702167D01*
X90833Y702375D01*
X90917Y702667D01*
X90833Y702958D01*
X90583Y703208D01*
X90208Y703333D01*
X89792D01*
X89542Y703417D01*
X89333Y703625D01*
X89250Y703917D01*
X89375Y704208D01*
X89667Y704417D01*
X90000Y704500D01*
X90333Y704417D01*
X90625Y704208D01*
X90750Y703917D01*
X90667Y703625D01*
X90458Y703417D01*
X90208Y703333D01*
X89792D01*
X89417Y703208D01*
X89167Y702958D01*
X89083Y702667D01*
X89167Y702375D01*
X89375Y702167D01*
X89708Y702042D01*
X90000Y702000D01*
G01X92183Y702500D02*
X92433Y702208D01*
X92767Y702042D01*
X93142Y702000D01*
X93475Y702042D01*
X93808Y702250D01*
X94017Y702500D01*
X94058Y702750D01*
X93975Y703042D01*
X93683Y703250D01*
X93392Y703333D01*
X93017D01*
G01X93392D02*
X93642Y703458D01*
X93850Y703667D01*
X93933Y703917D01*
X93850Y704167D01*
X93642Y704375D01*
X93267Y704500D01*
X92892Y704458D01*
X92517Y704292D01*
G01X98517Y669000D02*
Y671500D01*
X99558D01*
X99892Y671375D01*
X100100Y671208D01*
X100183Y670875D01*
X100100Y670542D01*
X99850Y670333D01*
X99558Y670208D01*
X98517D01*
G01X99558D02*
X100183Y669000D01*
G01X102450D02*
Y671500D01*
X101950Y671000D01*
G01Y669000D02*
X102950D01*
G01X105467D02*
X105550Y669542D01*
X105675Y670000D01*
X105842Y670417D01*
X106050Y670875D01*
X106383Y671500D01*
X104717D01*
G01X107858Y670042D02*
X108150Y670333D01*
X108400Y670500D01*
X108733Y670583D01*
X109025Y670500D01*
X109233Y670333D01*
X109400Y670083D01*
X109442Y669792D01*
X109400Y669542D01*
X109233Y669292D01*
X108983Y669083D01*
X108692Y669000D01*
X108358Y669083D01*
X108067Y669333D01*
X107900Y669708D01*
X107858Y670125D01*
X107942Y670667D01*
X108067Y670958D01*
X108275Y671250D01*
X108567Y671458D01*
X108858Y671500D01*
X109150Y671417D01*
X109358Y671208D01*
G01X110900Y672600D02*
Y668600D01*
X118300D01*
G01X83517Y651500D02*
Y654000D01*
X84558D01*
X84892Y653875D01*
X85100Y653708D01*
X85183Y653375D01*
X85100Y653042D01*
X84850Y652833D01*
X84558Y652708D01*
X83517D01*
G01X84558D02*
X85183Y651500D01*
G01X87450D02*
Y654000D01*
X86950Y653500D01*
G01Y651500D02*
X87950D01*
G01X89758Y652542D02*
X90050Y652833D01*
X90300Y653000D01*
X90633Y653083D01*
X90925Y653000D01*
X91133Y652833D01*
X91300Y652583D01*
X91342Y652292D01*
X91300Y652042D01*
X91133Y651792D01*
X90883Y651583D01*
X90592Y651500D01*
X90258Y651583D01*
X89967Y651833D01*
X89800Y652208D01*
X89758Y652625D01*
X89842Y653167D01*
X89967Y653458D01*
X90175Y653750D01*
X90467Y653958D01*
X90758Y654000D01*
X91050Y653917D01*
X91258Y653708D01*
G01X92733Y651875D02*
X92983Y651667D01*
X93275Y651542D01*
X93650Y651500D01*
X94025Y651583D01*
X94317Y651750D01*
X94525Y652042D01*
X94567Y652375D01*
X94483Y652708D01*
X94275Y652917D01*
X93983Y653083D01*
X93692Y653125D01*
X93400Y653083D01*
X93025Y652917D01*
X93150Y654000D01*
X94275D01*
G01X121000Y658200D02*
Y662200D01*
X113600D01*
G01X110300Y660200D02*
Y664200D01*
X102900D01*
G01Y656800D02*
X106900D01*
Y664200D01*
G01X113600Y654800D02*
X117600D01*
Y662200D01*
G01X114300Y665200D02*
X118300D01*
Y672600D01*
G01X130267Y700292D02*
X130017Y700417D01*
X129725Y700500D01*
X129392D01*
X129017Y700375D01*
X128725Y700167D01*
X128517Y699917D01*
X128350Y699500D01*
X128308Y699125D01*
X128392Y698750D01*
X128517Y698500D01*
X128767Y698250D01*
X129058Y698083D01*
X129350Y698000D01*
X129642D01*
X129933Y698083D01*
X130183Y698208D01*
X130392Y698375D01*
G01X131658Y700083D02*
X131908Y700333D01*
X132200Y700458D01*
X132533Y700500D01*
X132950Y700417D01*
X133242Y700208D01*
X133325Y699958D01*
X133283Y699708D01*
X133117Y699500D01*
X132283Y699083D01*
X131908Y698792D01*
X131658Y698375D01*
X131575Y698000D01*
X133325D01*
G01X134633Y698375D02*
X134883Y698167D01*
X135175Y698042D01*
X135550Y698000D01*
X135925Y698083D01*
X136217Y698250D01*
X136425Y698542D01*
X136467Y698875D01*
X136383Y699208D01*
X136175Y699417D01*
X135883Y699583D01*
X135592Y699625D01*
X135300Y699583D01*
X134925Y699417D01*
X135050Y700500D01*
X136175D01*
G01X137858Y699042D02*
X138150Y699333D01*
X138400Y699500D01*
X138733Y699583D01*
X139025Y699500D01*
X139233Y699333D01*
X139400Y699083D01*
X139442Y698792D01*
X139400Y698542D01*
X139233Y698292D01*
X138983Y698083D01*
X138692Y698000D01*
X138358Y698083D01*
X138067Y698333D01*
X137900Y698708D01*
X137858Y699125D01*
X137942Y699667D01*
X138067Y699958D01*
X138275Y700250D01*
X138567Y700458D01*
X138858Y700500D01*
X139150Y700417D01*
X139358Y700208D01*
G01X127500Y737917D02*
X122500D01*
Y741083D01*
G01X124917Y739917D02*
Y737917D01*
G01X126500Y743267D02*
X127083Y743767D01*
X127417Y744433D01*
X127500Y745183D01*
X127417Y745850D01*
X127000Y746517D01*
X126500Y746933D01*
X126000Y747017D01*
X125417Y746850D01*
X125000Y746267D01*
X124833Y745683D01*
Y744933D01*
G01Y745683D02*
X124583Y746183D01*
X124167Y746600D01*
X123667Y746767D01*
X123167Y746600D01*
X122750Y746183D01*
X122500Y745433D01*
X122583Y744683D01*
X122917Y743933D01*
G01X127667Y750700D02*
X127583Y750533D01*
X127417D01*
X127333Y750700D01*
X127417Y750867D01*
X127583D01*
X127667Y750700D01*
G01X125417D02*
X125333Y750533D01*
X125167D01*
X125083Y750700D01*
X125167Y750867D01*
X125333D01*
X125417Y750700D01*
G01X126500Y754467D02*
X127083Y754967D01*
X127417Y755633D01*
X127500Y756383D01*
X127417Y757050D01*
X127000Y757717D01*
X126500Y758133D01*
X126000Y758217D01*
X125417Y758050D01*
X125000Y757467D01*
X124833Y756883D01*
Y756133D01*
G01Y756883D02*
X124583Y757383D01*
X124167Y757800D01*
X123667Y757967D01*
X123167Y757800D01*
X122750Y757383D01*
X122500Y756633D01*
X122583Y755883D01*
X122917Y755133D01*
G01X127500Y759817D02*
X122500Y761900D01*
X127500Y763983D01*
G01X125750Y763233D02*
Y760567D01*
G01X127667Y766000D02*
X122500Y769000D01*
G01X127500Y773100D02*
X122500D01*
X123500Y772100D01*
G01X127500D02*
Y774100D01*
G01X126750Y776867D02*
X127167Y777367D01*
X127417Y777950D01*
X127500Y778700D01*
X127333Y779450D01*
X127000Y780033D01*
X126417Y780450D01*
X125750Y780533D01*
X125083Y780367D01*
X124667Y779950D01*
X124333Y779367D01*
X124250Y778783D01*
X124333Y778200D01*
X124667Y777450D01*
X122500Y777700D01*
Y779950D01*
G01Y782217D02*
X127500Y784300D01*
X122500Y786383D01*
G01X105402Y769397D02*
Y746397D01*
G01X105000Y713033D02*
X102500D01*
Y713867D01*
X102625Y714200D01*
X102792Y714450D01*
X103042Y714658D01*
X103333Y714825D01*
X103750Y714867D01*
X104167Y714825D01*
X104458Y714658D01*
X104708Y714450D01*
X104875Y714200D01*
X105000Y713867D01*
Y713033D01*
G01Y717050D02*
X104958Y717342D01*
X104833Y717675D01*
X104625Y717883D01*
X104333Y717967D01*
X104042Y717883D01*
X103792Y717633D01*
X103667Y717258D01*
Y716842D01*
X103583Y716592D01*
X103375Y716383D01*
X103083Y716300D01*
X102792Y716425D01*
X102583Y716717D01*
X102500Y717050D01*
X102583Y717383D01*
X102792Y717675D01*
X103083Y717800D01*
X103375Y717717D01*
X103583Y717508D01*
X103667Y717258D01*
Y716842D01*
X103792Y716467D01*
X104042Y716217D01*
X104333Y716133D01*
X104625Y716217D01*
X104833Y716425D01*
X104958Y716758D01*
X105000Y717050D01*
G01X99000Y711400D02*
Y719400D01*
G01X104000Y738033D02*
X101500D01*
Y738867D01*
X101625Y739200D01*
X101792Y739450D01*
X102042Y739658D01*
X102333Y739825D01*
X102750Y739867D01*
X103167Y739825D01*
X103458Y739658D01*
X103708Y739450D01*
X103875Y739200D01*
X104000Y738867D01*
Y738033D01*
G01X102958Y741258D02*
X102667Y741550D01*
X102500Y741800D01*
X102417Y742133D01*
X102500Y742425D01*
X102667Y742633D01*
X102917Y742800D01*
X103208Y742842D01*
X103458Y742800D01*
X103708Y742633D01*
X103917Y742383D01*
X104000Y742092D01*
X103917Y741758D01*
X103667Y741467D01*
X103292Y741300D01*
X102875Y741258D01*
X102333Y741342D01*
X102042Y741467D01*
X101750Y741675D01*
X101542Y741967D01*
X101500Y742258D01*
X101583Y742550D01*
X101792Y742758D01*
G01X98500Y736400D02*
Y744400D01*
G01X113000Y719467D02*
X110500D01*
Y720467D01*
X110625Y720800D01*
X110917Y721050D01*
X111250Y721133D01*
X111583Y721050D01*
X111833Y720842D01*
X111958Y720467D01*
Y719467D01*
G01X113000Y722567D02*
X110500D01*
Y723608D01*
X110625Y723942D01*
X110792Y724150D01*
X111125Y724233D01*
X111458Y724150D01*
X111667Y723900D01*
X111792Y723608D01*
Y722567D01*
G01Y723608D02*
X113000Y724233D01*
G01Y726500D02*
X110500D01*
X111000Y726000D01*
G01X113000D02*
Y727000D01*
G01Y729600D02*
X110500D01*
X111000Y729100D01*
G01X113000D02*
Y730100D01*
G01Y732617D02*
X112458Y732700D01*
X112000Y732825D01*
X111583Y732992D01*
X111125Y733200D01*
X110500Y733533D01*
Y731867D01*
G01X91000Y722067D02*
X88500D01*
Y723108D01*
X88625Y723442D01*
X88792Y723650D01*
X89125Y723733D01*
X89458Y723650D01*
X89667Y723400D01*
X89792Y723108D01*
Y722067D01*
G01Y723108D02*
X91000Y723733D01*
G01Y726000D02*
X90958Y726292D01*
X90833Y726625D01*
X90625Y726833D01*
X90333Y726917D01*
X90042Y726833D01*
X89792Y726583D01*
X89667Y726208D01*
Y725792D01*
X89583Y725542D01*
X89375Y725333D01*
X89083Y725250D01*
X88792Y725375D01*
X88583Y725667D01*
X88500Y726000D01*
X88583Y726333D01*
X88792Y726625D01*
X89083Y726750D01*
X89375Y726667D01*
X89583Y726458D01*
X89667Y726208D01*
Y725792D01*
X89792Y725417D01*
X90042Y725167D01*
X90333Y725083D01*
X90625Y725167D01*
X90833Y725375D01*
X90958Y725708D01*
X91000Y726000D01*
G01X90625Y728183D02*
X90833Y728433D01*
X90958Y728725D01*
X91000Y729100D01*
X90917Y729475D01*
X90750Y729767D01*
X90458Y729975D01*
X90125Y730017D01*
X89792Y729933D01*
X89583Y729725D01*
X89417Y729433D01*
X89375Y729142D01*
X89417Y728850D01*
X89583Y728475D01*
X88500Y728600D01*
Y729725D01*
G01X87000Y722067D02*
X84500D01*
Y723108D01*
X84625Y723442D01*
X84792Y723650D01*
X85125Y723733D01*
X85458Y723650D01*
X85667Y723400D01*
X85792Y723108D01*
Y722067D01*
G01Y723108D02*
X87000Y723733D01*
G01Y726000D02*
X86958Y726292D01*
X86833Y726625D01*
X86625Y726833D01*
X86333Y726917D01*
X86042Y726833D01*
X85792Y726583D01*
X85667Y726208D01*
Y725792D01*
X85583Y725542D01*
X85375Y725333D01*
X85083Y725250D01*
X84792Y725375D01*
X84583Y725667D01*
X84500Y726000D01*
X84583Y726333D01*
X84792Y726625D01*
X85083Y726750D01*
X85375Y726667D01*
X85583Y726458D01*
X85667Y726208D01*
Y725792D01*
X85792Y725417D01*
X86042Y725167D01*
X86333Y725083D01*
X86625Y725167D01*
X86833Y725375D01*
X86958Y725708D01*
X87000Y726000D01*
G01X86708Y728392D02*
X86917Y728683D01*
X87000Y729017D01*
X86917Y729350D01*
X86667Y729642D01*
X86292Y729850D01*
X85917Y729933D01*
X85458D01*
X85083Y729850D01*
X84750Y729642D01*
X84583Y729392D01*
X84500Y729100D01*
X84583Y728767D01*
X84750Y728517D01*
X85000Y728350D01*
X85333Y728267D01*
X85625Y728350D01*
X85917Y728558D01*
X86083Y728808D01*
X86125Y729100D01*
X86042Y729433D01*
X85833Y729683D01*
X85458Y729933D01*
G01X93200Y705900D02*
Y709900D01*
X85800D01*
G01X93067Y731500D02*
Y734000D01*
X94108D01*
X94442Y733875D01*
X94650Y733708D01*
X94733Y733375D01*
X94650Y733042D01*
X94400Y732833D01*
X94108Y732708D01*
X93067D01*
G01X94108D02*
X94733Y731500D01*
G01X97000D02*
X97292Y731542D01*
X97625Y731667D01*
X97833Y731875D01*
X97917Y732167D01*
X97833Y732458D01*
X97583Y732708D01*
X97208Y732833D01*
X96792D01*
X96542Y732917D01*
X96333Y733125D01*
X96250Y733417D01*
X96375Y733708D01*
X96667Y733917D01*
X97000Y734000D01*
X97333Y733917D01*
X97625Y733708D01*
X97750Y733417D01*
X97667Y733125D01*
X97458Y732917D01*
X97208Y732833D01*
X96792D01*
X96417Y732708D01*
X96167Y732458D01*
X96083Y732167D01*
X96167Y731875D01*
X96375Y731667D01*
X96708Y731542D01*
X97000Y731500D01*
G01X100100D02*
Y734000D01*
X99600Y733500D01*
G01Y731500D02*
X100600D01*
G01X91700Y731400D02*
Y735400D01*
X84300D01*
G01X128900Y733300D02*
Y719300D01*
G01X141900Y733300D02*
X128900D01*
G01Y719300D02*
X141900D01*
G01X110000Y704983D02*
X107500D01*
Y705817D01*
X107625Y706150D01*
X107792Y706400D01*
X108042Y706608D01*
X108333Y706775D01*
X108750Y706817D01*
X109167Y706775D01*
X109458Y706608D01*
X109708Y706400D01*
X109875Y706150D01*
X110000Y705817D01*
Y704983D01*
G01Y709000D02*
X107500D01*
X108000Y708500D01*
G01X110000D02*
Y709500D01*
G01X109500Y711183D02*
X109792Y711433D01*
X109958Y711767D01*
X110000Y712142D01*
X109958Y712475D01*
X109750Y712808D01*
X109500Y713017D01*
X109250Y713058D01*
X108958Y712975D01*
X108750Y712683D01*
X108667Y712392D01*
Y712017D01*
G01Y712392D02*
X108542Y712642D01*
X108333Y712850D01*
X108083Y712933D01*
X107833Y712850D01*
X107625Y712642D01*
X107500Y712267D01*
X107542Y711892D01*
X107708Y711517D01*
G01X139700Y704500D02*
Y716500D01*
X112300D01*
Y704500D01*
X139700D01*
G01X105200Y789400D02*
Y807400D01*
G01X94000Y789400D02*
X105200D01*
G01X111917Y779692D02*
X111667Y779817D01*
X111375Y779900D01*
X111042D01*
X110667Y779775D01*
X110375Y779567D01*
X110167Y779317D01*
X110000Y778900D01*
X109958Y778525D01*
X110042Y778150D01*
X110167Y777900D01*
X110417Y777650D01*
X110708Y777483D01*
X111000Y777400D01*
X111292D01*
X111583Y777483D01*
X111833Y777608D01*
X112042Y777775D01*
G01X114600Y777400D02*
Y779900D01*
X113058Y778108D01*
X115142D01*
G01X116408Y779483D02*
X116658Y779733D01*
X116950Y779858D01*
X117283Y779900D01*
X117700Y779817D01*
X117992Y779608D01*
X118075Y779358D01*
X118033Y779108D01*
X117867Y778900D01*
X117033Y778483D01*
X116658Y778192D01*
X116408Y777775D01*
X116325Y777400D01*
X118075D01*
G01X111917Y775692D02*
X111667Y775817D01*
X111375Y775900D01*
X111042D01*
X110667Y775775D01*
X110375Y775567D01*
X110167Y775317D01*
X110000Y774900D01*
X109958Y774525D01*
X110042Y774150D01*
X110167Y773900D01*
X110417Y773650D01*
X110708Y773483D01*
X111000Y773400D01*
X111292D01*
X111583Y773483D01*
X111833Y773608D01*
X112042Y773775D01*
G01X114600Y773400D02*
Y775900D01*
X113058Y774108D01*
X115142D01*
G01X117200Y773400D02*
Y775900D01*
X116700Y775400D01*
G01Y773400D02*
X117700D01*
G01X96517Y775300D02*
Y777800D01*
X97558D01*
X97892Y777675D01*
X98100Y777508D01*
X98183Y777175D01*
X98100Y776842D01*
X97850Y776633D01*
X97558Y776508D01*
X96517D01*
G01X97558D02*
X98183Y775300D01*
G01X100450D02*
Y777800D01*
X99950Y777300D01*
G01Y775300D02*
X100950D01*
G01X103550D02*
X103842Y775342D01*
X104175Y775467D01*
X104383Y775675D01*
X104467Y775967D01*
X104383Y776258D01*
X104133Y776508D01*
X103758Y776633D01*
X103342D01*
X103092Y776717D01*
X102883Y776925D01*
X102800Y777217D01*
X102925Y777508D01*
X103217Y777717D01*
X103550Y777800D01*
X103883Y777717D01*
X104175Y777508D01*
X104300Y777217D01*
X104217Y776925D01*
X104008Y776717D01*
X103758Y776633D01*
X103342D01*
X102967Y776508D01*
X102717Y776258D01*
X102633Y775967D01*
X102717Y775675D01*
X102925Y775467D01*
X103258Y775342D01*
X103550Y775300D01*
G01X106650Y777800D02*
X106317Y777717D01*
X106067Y777508D01*
X105900Y777258D01*
X105775Y776925D01*
X105733Y776550D01*
X105775Y776175D01*
X105900Y775842D01*
X106067Y775592D01*
X106317Y775383D01*
X106650Y775300D01*
X106983Y775383D01*
X107233Y775592D01*
X107400Y775842D01*
X107525Y776175D01*
X107567Y776550D01*
X107525Y776925D01*
X107400Y777258D01*
X107233Y777508D01*
X106983Y777717D01*
X106650Y777800D01*
G01X95000Y772700D02*
Y780700D01*
G01X116900Y864404D02*
Y850404D01*
X96800D01*
Y864404D01*
X116900D01*
G01X105200Y807400D02*
X94000D01*
G01X126000Y826017D02*
X123500D01*
Y827058D01*
X123625Y827392D01*
X123792Y827600D01*
X124125Y827683D01*
X124458Y827600D01*
X124667Y827350D01*
X124792Y827058D01*
Y826017D01*
G01Y827058D02*
X126000Y827683D01*
G01Y829950D02*
X123500D01*
X124000Y829450D01*
G01X126000D02*
Y830450D01*
G01X125500Y832133D02*
X125792Y832383D01*
X125958Y832717D01*
X126000Y833092D01*
X125958Y833425D01*
X125750Y833758D01*
X125500Y833967D01*
X125250Y834008D01*
X124958Y833925D01*
X124750Y833633D01*
X124667Y833342D01*
Y832967D01*
G01Y833342D02*
X124542Y833592D01*
X124333Y833800D01*
X124083Y833883D01*
X123833Y833800D01*
X123625Y833592D01*
X123500Y833217D01*
X123542Y832842D01*
X123708Y832467D01*
G01X125708Y835442D02*
X125917Y835733D01*
X126000Y836067D01*
X125917Y836400D01*
X125667Y836692D01*
X125292Y836900D01*
X124917Y836983D01*
X124458D01*
X124083Y836900D01*
X123750Y836692D01*
X123583Y836442D01*
X123500Y836150D01*
X123583Y835817D01*
X123750Y835567D01*
X124000Y835400D01*
X124333Y835317D01*
X124625Y835400D01*
X124917Y835608D01*
X125083Y835858D01*
X125125Y836150D01*
X125042Y836483D01*
X124833Y836733D01*
X124458Y836983D01*
G01X117600Y826400D02*
X121600D01*
Y833800D01*
G01X81996Y850500D02*
Y846500D01*
X89396D01*
G01X81996Y846100D02*
Y842100D01*
X89396D01*
G01X81996Y854900D02*
Y850900D01*
X89396D01*
G01X116500Y826517D02*
X114000D01*
Y827558D01*
X114125Y827892D01*
X114292Y828100D01*
X114625Y828183D01*
X114958Y828100D01*
X115167Y827850D01*
X115292Y827558D01*
Y826517D01*
G01Y827558D02*
X116500Y828183D01*
G01Y830450D02*
X114000D01*
X114500Y829950D01*
G01X116500D02*
Y830950D01*
G01X116000Y832633D02*
X116292Y832883D01*
X116458Y833217D01*
X116500Y833592D01*
X116458Y833925D01*
X116250Y834258D01*
X116000Y834467D01*
X115750Y834508D01*
X115458Y834425D01*
X115250Y834133D01*
X115167Y833842D01*
Y833467D01*
G01Y833842D02*
X115042Y834092D01*
X114833Y834300D01*
X114583Y834383D01*
X114333Y834300D01*
X114125Y834092D01*
X114000Y833717D01*
X114042Y833342D01*
X114208Y832967D01*
G01X116500Y836567D02*
X115958Y836650D01*
X115500Y836775D01*
X115083Y836942D01*
X114625Y837150D01*
X114000Y837483D01*
Y835817D01*
G01X109200Y826400D02*
X113200D01*
Y833800D01*
G01X108500Y826517D02*
X106000D01*
Y827558D01*
X106125Y827892D01*
X106292Y828100D01*
X106625Y828183D01*
X106958Y828100D01*
X107167Y827850D01*
X107292Y827558D01*
Y826517D01*
G01Y827558D02*
X108500Y828183D01*
G01Y830450D02*
X106000D01*
X106500Y829950D01*
G01X108500D02*
Y830950D01*
G01X108000Y832633D02*
X108292Y832883D01*
X108458Y833217D01*
X108500Y833592D01*
X108458Y833925D01*
X108250Y834258D01*
X108000Y834467D01*
X107750Y834508D01*
X107458Y834425D01*
X107250Y834133D01*
X107167Y833842D01*
Y833467D01*
G01Y833842D02*
X107042Y834092D01*
X106833Y834300D01*
X106583Y834383D01*
X106333Y834300D01*
X106125Y834092D01*
X106000Y833717D01*
X106042Y833342D01*
X106208Y832967D01*
G01X107458Y835858D02*
X107167Y836150D01*
X107000Y836400D01*
X106917Y836733D01*
X107000Y837025D01*
X107167Y837233D01*
X107417Y837400D01*
X107708Y837442D01*
X107958Y837400D01*
X108208Y837233D01*
X108417Y836983D01*
X108500Y836692D01*
X108417Y836358D01*
X108167Y836067D01*
X107792Y835900D01*
X107375Y835858D01*
X106833Y835942D01*
X106542Y836067D01*
X106250Y836275D01*
X106042Y836567D01*
X106000Y836858D01*
X106083Y837150D01*
X106292Y837358D01*
G01X100900Y826396D02*
X104900D01*
Y833796D01*
G01X102033Y877000D02*
Y875208D01*
X102200Y874833D01*
X102533Y874583D01*
X102950Y874500D01*
X103367Y874583D01*
X103700Y874833D01*
X103867Y875208D01*
Y877000D01*
G01X105967Y874500D02*
X106050Y875042D01*
X106175Y875500D01*
X106342Y875917D01*
X106550Y876375D01*
X106883Y877000D01*
X105217D01*
G01X96950Y859254D02*
X97050D01*
X98900Y857404D01*
X97100Y855604D01*
X97000D01*
G01X90708Y883317D02*
X90583Y883067D01*
X90500Y882775D01*
Y882442D01*
X90625Y882067D01*
X90833Y881775D01*
X91083Y881567D01*
X91500Y881400D01*
X91875Y881358D01*
X92250Y881442D01*
X92500Y881567D01*
X92750Y881817D01*
X92917Y882108D01*
X93000Y882400D01*
Y882692D01*
X92917Y882983D01*
X92792Y883233D01*
X92625Y883442D01*
G01X93000Y885500D02*
X90500D01*
X91000Y885000D01*
G01X93000D02*
Y886000D01*
G01X92625Y887683D02*
X92833Y887933D01*
X92958Y888225D01*
X93000Y888600D01*
X92917Y888975D01*
X92750Y889267D01*
X92458Y889475D01*
X92125Y889517D01*
X91792Y889433D01*
X91583Y889225D01*
X91417Y888933D01*
X91375Y888642D01*
X91417Y888350D01*
X91583Y887975D01*
X90500Y888100D01*
Y889225D01*
G01X86708Y883317D02*
X86583Y883067D01*
X86500Y882775D01*
Y882442D01*
X86625Y882067D01*
X86833Y881775D01*
X87083Y881567D01*
X87500Y881400D01*
X87875Y881358D01*
X88250Y881442D01*
X88500Y881567D01*
X88750Y881817D01*
X88917Y882108D01*
X89000Y882400D01*
Y882692D01*
X88917Y882983D01*
X88792Y883233D01*
X88625Y883442D01*
G01X89000Y885500D02*
X86500D01*
X87000Y885000D01*
G01X89000D02*
Y886000D01*
G01X87958Y887808D02*
X87667Y888100D01*
X87500Y888350D01*
X87417Y888683D01*
X87500Y888975D01*
X87667Y889183D01*
X87917Y889350D01*
X88208Y889392D01*
X88458Y889350D01*
X88708Y889183D01*
X88917Y888933D01*
X89000Y888642D01*
X88917Y888308D01*
X88667Y888017D01*
X88292Y887850D01*
X87875Y887808D01*
X87333Y887892D01*
X87042Y888017D01*
X86750Y888225D01*
X86542Y888517D01*
X86500Y888808D01*
X86583Y889100D01*
X86792Y889308D01*
G01X111500Y889017D02*
X109000D01*
Y890058D01*
X109125Y890392D01*
X109292Y890600D01*
X109625Y890683D01*
X109958Y890600D01*
X110167Y890350D01*
X110292Y890058D01*
Y889017D01*
G01Y890058D02*
X111500Y890683D01*
G01Y892950D02*
X109000D01*
X109500Y892450D01*
G01X111500D02*
Y893450D01*
G01Y896550D02*
X109000D01*
X110792Y895008D01*
Y897092D01*
G01X109000Y899150D02*
X109083Y898817D01*
X109292Y898567D01*
X109542Y898400D01*
X109875Y898275D01*
X110250Y898233D01*
X110625Y898275D01*
X110958Y898400D01*
X111208Y898567D01*
X111417Y898817D01*
X111500Y899150D01*
X111417Y899483D01*
X111208Y899733D01*
X110958Y899900D01*
X110625Y900025D01*
X110250Y900067D01*
X109875Y900025D01*
X109542Y899900D01*
X109292Y899733D01*
X109083Y899483D01*
X109000Y899150D01*
G01X112900Y886800D02*
X108900D01*
Y879400D01*
G01X103500Y889017D02*
X101000D01*
Y890058D01*
X101125Y890392D01*
X101292Y890600D01*
X101625Y890683D01*
X101958Y890600D01*
X102167Y890350D01*
X102292Y890058D01*
Y889017D01*
G01Y890058D02*
X103500Y890683D01*
G01Y892950D02*
X101000D01*
X101500Y892450D01*
G01X103500D02*
Y893450D01*
G01Y896550D02*
X101000D01*
X102792Y895008D01*
Y897092D01*
G01X103500Y899150D02*
X101000D01*
X101500Y898650D01*
G01X103500D02*
Y899650D01*
G01X104600Y886800D02*
X100600D01*
Y879400D01*
G01X82000Y867700D02*
Y863700D01*
X89400D01*
G01X119500Y889017D02*
X117000D01*
Y890058D01*
X117125Y890392D01*
X117292Y890600D01*
X117625Y890683D01*
X117958Y890600D01*
X118167Y890350D01*
X118292Y890058D01*
Y889017D01*
G01Y890058D02*
X119500Y890683D01*
G01Y892950D02*
X117000D01*
X117500Y892450D01*
G01X119500D02*
Y893450D01*
G01X119000Y895133D02*
X119292Y895383D01*
X119458Y895717D01*
X119500Y896092D01*
X119458Y896425D01*
X119250Y896758D01*
X119000Y896967D01*
X118750Y897008D01*
X118458Y896925D01*
X118250Y896633D01*
X118167Y896342D01*
Y895967D01*
G01Y896342D02*
X118042Y896592D01*
X117833Y896800D01*
X117583Y896883D01*
X117333Y896800D01*
X117125Y896592D01*
X117000Y896217D01*
X117042Y895842D01*
X117208Y895467D01*
G01X119500Y899150D02*
X119458Y899442D01*
X119333Y899775D01*
X119125Y899983D01*
X118833Y900067D01*
X118542Y899983D01*
X118292Y899733D01*
X118167Y899358D01*
Y898942D01*
X118083Y898692D01*
X117875Y898483D01*
X117583Y898400D01*
X117292Y898525D01*
X117083Y898817D01*
X117000Y899150D01*
X117083Y899483D01*
X117292Y899775D01*
X117583Y899900D01*
X117875Y899817D01*
X118083Y899608D01*
X118167Y899358D01*
Y898942D01*
X118292Y898567D01*
X118542Y898317D01*
X118833Y898233D01*
X119125Y898317D01*
X119333Y898525D01*
X119458Y898858D01*
X119500Y899150D01*
G01X121300Y886800D02*
X117300D01*
Y879400D01*
G01X82000Y859200D02*
Y855200D01*
X89400D01*
G01X82000Y863500D02*
Y859500D01*
X89400D01*
G01X101500Y952517D02*
X99000D01*
Y953517D01*
X99125Y953850D01*
X99417Y954100D01*
X99750Y954183D01*
X100083Y954100D01*
X100333Y953892D01*
X100458Y953517D01*
Y952517D01*
G01X101500Y955617D02*
X99000D01*
Y956658D01*
X99125Y956992D01*
X99292Y957200D01*
X99625Y957283D01*
X99958Y957200D01*
X100167Y956950D01*
X100292Y956658D01*
Y955617D01*
G01Y956658D02*
X101500Y957283D01*
G01X101125Y958633D02*
X101333Y958883D01*
X101458Y959175D01*
X101500Y959550D01*
X101417Y959925D01*
X101250Y960217D01*
X100958Y960425D01*
X100625Y960467D01*
X100292Y960383D01*
X100083Y960175D01*
X99917Y959883D01*
X99875Y959592D01*
X99917Y959300D01*
X100083Y958925D01*
X99000Y959050D01*
Y960175D01*
G01X101500Y963150D02*
X99000D01*
X100792Y961608D01*
Y963692D01*
G01X96000Y915017D02*
X93500D01*
Y916017D01*
X93625Y916350D01*
X93917Y916600D01*
X94250Y916683D01*
X94583Y916600D01*
X94833Y916392D01*
X94958Y916017D01*
Y915017D01*
G01X93708Y919867D02*
X93583Y919617D01*
X93500Y919325D01*
Y918992D01*
X93625Y918617D01*
X93833Y918325D01*
X94083Y918117D01*
X94500Y917950D01*
X94875Y917908D01*
X95250Y917992D01*
X95500Y918117D01*
X95750Y918367D01*
X95917Y918658D01*
X96000Y918950D01*
Y919242D01*
X95917Y919533D01*
X95792Y919783D01*
X95625Y919992D01*
G01X96000Y922550D02*
X93500D01*
X95292Y921008D01*
Y923092D01*
G01X95500Y924233D02*
X95792Y924483D01*
X95958Y924817D01*
X96000Y925192D01*
X95958Y925525D01*
X95750Y925858D01*
X95500Y926067D01*
X95250Y926108D01*
X94958Y926025D01*
X94750Y925733D01*
X94667Y925442D01*
Y925067D01*
G01Y925442D02*
X94542Y925692D01*
X94333Y925900D01*
X94083Y925983D01*
X93833Y925900D01*
X93625Y925692D01*
X93500Y925317D01*
X93542Y924942D01*
X93708Y924567D01*
G01X100000Y945300D02*
Y939800D01*
G01X92000Y945300D02*
X100000D01*
G01X92000Y939800D02*
Y945300D01*
G01Y927700D02*
Y933200D01*
G01X100000Y927700D02*
X92000D01*
G01X100000Y933200D02*
Y927700D01*
G01X121500Y925067D02*
X119000D01*
Y926108D01*
X119125Y926442D01*
X119292Y926650D01*
X119625Y926733D01*
X119958Y926650D01*
X120167Y926400D01*
X120292Y926108D01*
Y925067D01*
G01Y926108D02*
X121500Y926733D01*
G01Y929500D02*
X119000D01*
X120792Y927958D01*
Y930042D01*
G01X121500Y932600D02*
X119000D01*
X120792Y931058D01*
Y933142D01*
G01X124529Y957744D02*
X120529D01*
Y950344D01*
G01X117500Y925067D02*
X115000D01*
Y926108D01*
X115125Y926442D01*
X115292Y926650D01*
X115625Y926733D01*
X115958Y926650D01*
X116167Y926400D01*
X116292Y926108D01*
Y925067D01*
G01Y926108D02*
X117500Y926733D01*
G01Y929500D02*
X115000D01*
X116792Y927958D01*
Y930042D01*
G01X117000Y931183D02*
X117292Y931433D01*
X117458Y931767D01*
X117500Y932142D01*
X117458Y932475D01*
X117250Y932808D01*
X117000Y933017D01*
X116750Y933058D01*
X116458Y932975D01*
X116250Y932683D01*
X116167Y932392D01*
Y932017D01*
G01Y932392D02*
X116042Y932642D01*
X115833Y932850D01*
X115583Y932933D01*
X115333Y932850D01*
X115125Y932642D01*
X115000Y932267D01*
X115042Y931892D01*
X115208Y931517D01*
G01X119529Y957744D02*
X115529D01*
Y950344D01*
G01X113500Y925067D02*
X111000D01*
Y926108D01*
X111125Y926442D01*
X111292Y926650D01*
X111625Y926733D01*
X111958Y926650D01*
X112167Y926400D01*
X112292Y926108D01*
Y925067D01*
G01Y926108D02*
X113500Y926733D01*
G01Y929500D02*
X111000D01*
X112792Y927958D01*
Y930042D01*
G01X111417Y931308D02*
X111167Y931558D01*
X111042Y931850D01*
X111000Y932183D01*
X111083Y932600D01*
X111292Y932892D01*
X111542Y932975D01*
X111792Y932933D01*
X112000Y932767D01*
X112417Y931933D01*
X112708Y931558D01*
X113125Y931308D01*
X113500Y931225D01*
Y932975D01*
G01X114529Y957744D02*
X110529D01*
Y950344D01*
G01X122071Y914623D02*
X119571D01*
Y915664D01*
X119696Y915998D01*
X119863Y916206D01*
X120196Y916289D01*
X120529Y916206D01*
X120738Y915956D01*
X120863Y915664D01*
Y914623D01*
G01Y915664D02*
X122071Y916289D01*
G01Y919056D02*
X119571D01*
X121363Y917514D01*
Y919598D01*
G01X122071Y921656D02*
X119571D01*
X120071Y921156D01*
G01X122071D02*
Y922156D01*
G01X119671Y934356D02*
X123671D01*
Y941756D01*
G01X117700Y914567D02*
X115200D01*
Y915608D01*
X115325Y915942D01*
X115492Y916150D01*
X115825Y916233D01*
X116158Y916150D01*
X116367Y915900D01*
X116492Y915608D01*
Y914567D01*
G01Y915608D02*
X117700Y916233D01*
G01Y919000D02*
X115200D01*
X116992Y917458D01*
Y919542D01*
G01X115200Y921600D02*
X115283Y921267D01*
X115492Y921017D01*
X115742Y920850D01*
X116075Y920725D01*
X116450Y920683D01*
X116825Y920725D01*
X117158Y920850D01*
X117408Y921017D01*
X117617Y921267D01*
X117700Y921600D01*
X117617Y921933D01*
X117408Y922183D01*
X117158Y922350D01*
X116825Y922475D01*
X116450Y922517D01*
X116075Y922475D01*
X115742Y922350D01*
X115492Y922183D01*
X115283Y921933D01*
X115200Y921600D01*
G01X115300Y934300D02*
X119300D01*
Y941700D01*
G01X112500Y914567D02*
X110000D01*
Y915608D01*
X110125Y915942D01*
X110292Y916150D01*
X110625Y916233D01*
X110958Y916150D01*
X111167Y915900D01*
X111292Y915608D01*
Y914567D01*
G01Y915608D02*
X112500Y916233D01*
G01X112000Y917583D02*
X112292Y917833D01*
X112458Y918167D01*
X112500Y918542D01*
X112458Y918875D01*
X112250Y919208D01*
X112000Y919417D01*
X111750Y919458D01*
X111458Y919375D01*
X111250Y919083D01*
X111167Y918792D01*
Y918417D01*
G01Y918792D02*
X111042Y919042D01*
X110833Y919250D01*
X110583Y919333D01*
X110333Y919250D01*
X110125Y919042D01*
X110000Y918667D01*
X110042Y918292D01*
X110208Y917917D01*
G01X112208Y920892D02*
X112417Y921183D01*
X112500Y921517D01*
X112417Y921850D01*
X112167Y922142D01*
X111792Y922350D01*
X111417Y922433D01*
X110958D01*
X110583Y922350D01*
X110250Y922142D01*
X110083Y921892D01*
X110000Y921600D01*
X110083Y921267D01*
X110250Y921017D01*
X110500Y920850D01*
X110833Y920767D01*
X111125Y920850D01*
X111417Y921058D01*
X111583Y921308D01*
X111625Y921600D01*
X111542Y921933D01*
X111333Y922183D01*
X110958Y922433D01*
G01X108500Y934300D02*
X112500D01*
Y941700D01*
G01X133500Y931067D02*
X131000D01*
Y932108D01*
X131125Y932442D01*
X131292Y932650D01*
X131625Y932733D01*
X131958Y932650D01*
X132167Y932400D01*
X132292Y932108D01*
Y931067D01*
G01Y932108D02*
X133500Y932733D01*
G01X133125Y934083D02*
X133333Y934333D01*
X133458Y934625D01*
X133500Y935000D01*
X133417Y935375D01*
X133250Y935667D01*
X132958Y935875D01*
X132625Y935917D01*
X132292Y935833D01*
X132083Y935625D01*
X131917Y935333D01*
X131875Y935042D01*
X131917Y934750D01*
X132083Y934375D01*
X131000Y934500D01*
Y935625D01*
G01X133500Y938600D02*
X131000D01*
X132792Y937058D01*
Y939142D01*
G01X129500Y942400D02*
X133500D01*
Y949800D01*
G01X106500Y916017D02*
X104000D01*
Y917058D01*
X104125Y917392D01*
X104292Y917600D01*
X104625Y917683D01*
X104958Y917600D01*
X105167Y917350D01*
X105292Y917058D01*
Y916017D01*
G01Y917058D02*
X106500Y917683D01*
G01Y919950D02*
X104000D01*
X104500Y919450D01*
G01X106500D02*
Y920450D01*
G01X106125Y922133D02*
X106333Y922383D01*
X106458Y922675D01*
X106500Y923050D01*
X106417Y923425D01*
X106250Y923717D01*
X105958Y923925D01*
X105625Y923967D01*
X105292Y923883D01*
X105083Y923675D01*
X104917Y923383D01*
X104875Y923092D01*
X104917Y922800D01*
X105083Y922425D01*
X104000Y922550D01*
Y923675D01*
G01X106500Y926650D02*
X104000D01*
X105792Y925108D01*
Y927192D01*
G01X101000Y943200D02*
X108000D01*
Y929800D01*
X101000D01*
Y943200D01*
G01X111033Y993500D02*
Y991708D01*
X111200Y991333D01*
X111533Y991083D01*
X111950Y991000D01*
X112367Y991083D01*
X112700Y991333D01*
X112867Y991708D01*
Y993500D01*
G01X114133Y991375D02*
X114383Y991167D01*
X114675Y991042D01*
X115050Y991000D01*
X115425Y991083D01*
X115717Y991250D01*
X115925Y991542D01*
X115967Y991875D01*
X115883Y992208D01*
X115675Y992417D01*
X115383Y992583D01*
X115092Y992625D01*
X114800Y992583D01*
X114425Y992417D01*
X114550Y993500D01*
X115675D01*
G01X83033Y990500D02*
Y988708D01*
X83200Y988333D01*
X83533Y988083D01*
X83950Y988000D01*
X84367Y988083D01*
X84700Y988333D01*
X84867Y988708D01*
Y990500D01*
G01X87550Y988000D02*
Y990500D01*
X86008Y988708D01*
X88092D01*
G01X82700Y970150D02*
X84300Y968550D01*
G01X81100D02*
X82700Y970150D01*
G01X85000Y968550D02*
Y983050D01*
G01X96000Y986017D02*
X93500D01*
Y987017D01*
X93625Y987350D01*
X93917Y987600D01*
X94250Y987683D01*
X94583Y987600D01*
X94833Y987392D01*
X94958Y987017D01*
Y986017D01*
G01X96000Y989117D02*
X93500D01*
Y990158D01*
X93625Y990492D01*
X93792Y990700D01*
X94125Y990783D01*
X94458Y990700D01*
X94667Y990450D01*
X94792Y990158D01*
Y989117D01*
G01Y990158D02*
X96000Y990783D01*
G01X95625Y992133D02*
X95833Y992383D01*
X95958Y992675D01*
X96000Y993050D01*
X95917Y993425D01*
X95750Y993717D01*
X95458Y993925D01*
X95125Y993967D01*
X94792Y993883D01*
X94583Y993675D01*
X94417Y993383D01*
X94375Y993092D01*
X94417Y992800D01*
X94583Y992425D01*
X93500Y992550D01*
Y993675D01*
G01X94958Y995358D02*
X94667Y995650D01*
X94500Y995900D01*
X94417Y996233D01*
X94500Y996525D01*
X94667Y996733D01*
X94917Y996900D01*
X95208Y996942D01*
X95458Y996900D01*
X95708Y996733D01*
X95917Y996483D01*
X96000Y996192D01*
X95917Y995858D01*
X95667Y995567D01*
X95292Y995400D01*
X94875Y995358D01*
X94333Y995442D01*
X94042Y995567D01*
X93750Y995775D01*
X93542Y996067D01*
X93500Y996358D01*
X93583Y996650D01*
X93792Y996858D01*
G01X101317Y1009792D02*
X101067Y1009917D01*
X100775Y1010000D01*
X100442D01*
X100067Y1009875D01*
X99775Y1009667D01*
X99567Y1009417D01*
X99400Y1009000D01*
X99358Y1008625D01*
X99442Y1008250D01*
X99567Y1008000D01*
X99817Y1007750D01*
X100108Y1007583D01*
X100400Y1007500D01*
X100692D01*
X100983Y1007583D01*
X101233Y1007708D01*
X101442Y1007875D01*
G01X103500Y1007500D02*
Y1010000D01*
X103000Y1009500D01*
G01Y1007500D02*
X104000D01*
G01X107100D02*
Y1010000D01*
X105558Y1008208D01*
X107642D01*
G01X107500Y994017D02*
X105000D01*
Y995017D01*
X105125Y995350D01*
X105417Y995600D01*
X105750Y995683D01*
X106083Y995600D01*
X106333Y995392D01*
X106458Y995017D01*
Y994017D01*
G01X105208Y998867D02*
X105083Y998617D01*
X105000Y998325D01*
Y997992D01*
X105125Y997617D01*
X105333Y997325D01*
X105583Y997117D01*
X106000Y996950D01*
X106375Y996908D01*
X106750Y996992D01*
X107000Y997117D01*
X107250Y997367D01*
X107417Y997658D01*
X107500Y997950D01*
Y998242D01*
X107417Y998533D01*
X107292Y998783D01*
X107125Y998992D01*
G01X107500Y1001550D02*
X105000D01*
X106792Y1000008D01*
Y1002092D01*
G01X105417Y1003358D02*
X105167Y1003608D01*
X105042Y1003900D01*
X105000Y1004233D01*
X105083Y1004650D01*
X105292Y1004942D01*
X105542Y1005025D01*
X105792Y1004983D01*
X106000Y1004817D01*
X106417Y1003983D01*
X106708Y1003608D01*
X107125Y1003358D01*
X107500Y1003275D01*
Y1005025D01*
G01X129708Y965817D02*
X129583Y965567D01*
X129500Y965275D01*
Y964942D01*
X129625Y964567D01*
X129833Y964275D01*
X130083Y964067D01*
X130500Y963900D01*
X130875Y963858D01*
X131250Y963942D01*
X131500Y964067D01*
X131750Y964317D01*
X131917Y964608D01*
X132000Y964900D01*
Y965192D01*
X131917Y965483D01*
X131792Y965733D01*
X131625Y965942D01*
G01X129917Y967208D02*
X129667Y967458D01*
X129542Y967750D01*
X129500Y968083D01*
X129583Y968500D01*
X129792Y968792D01*
X130042Y968875D01*
X130292Y968833D01*
X130500Y968667D01*
X130917Y967833D01*
X131208Y967458D01*
X131625Y967208D01*
X132000Y967125D01*
Y968875D01*
G01X129500Y971100D02*
X129583Y970767D01*
X129792Y970517D01*
X130042Y970350D01*
X130375Y970225D01*
X130750Y970183D01*
X131125Y970225D01*
X131458Y970350D01*
X131708Y970517D01*
X131917Y970767D01*
X132000Y971100D01*
X131917Y971433D01*
X131708Y971683D01*
X131458Y971850D01*
X131125Y971975D01*
X130750Y972017D01*
X130375Y971975D01*
X130042Y971850D01*
X129792Y971683D01*
X129583Y971433D01*
X129500Y971100D01*
G01X124800Y1004467D02*
X122300D01*
Y1005508D01*
X122425Y1005842D01*
X122592Y1006050D01*
X122925Y1006133D01*
X123258Y1006050D01*
X123467Y1005800D01*
X123592Y1005508D01*
Y1004467D01*
G01Y1005508D02*
X124800Y1006133D01*
G01Y1008900D02*
X122300D01*
X124092Y1007358D01*
Y1009442D01*
G01X124800Y1011417D02*
X124258Y1011500D01*
X123800Y1011625D01*
X123383Y1011792D01*
X122925Y1012000D01*
X122300Y1012333D01*
Y1010667D01*
G01X121300Y995900D02*
X125300D01*
Y1003300D01*
G01X120800Y1004467D02*
X118300D01*
Y1005508D01*
X118425Y1005842D01*
X118592Y1006050D01*
X118925Y1006133D01*
X119258Y1006050D01*
X119467Y1005800D01*
X119592Y1005508D01*
Y1004467D01*
G01Y1005508D02*
X120800Y1006133D01*
G01Y1008900D02*
X118300D01*
X120092Y1007358D01*
Y1009442D01*
G01X119758Y1010708D02*
X119467Y1011000D01*
X119300Y1011250D01*
X119217Y1011583D01*
X119300Y1011875D01*
X119467Y1012083D01*
X119717Y1012250D01*
X120008Y1012292D01*
X120258Y1012250D01*
X120508Y1012083D01*
X120717Y1011833D01*
X120800Y1011542D01*
X120717Y1011208D01*
X120467Y1010917D01*
X120092Y1010750D01*
X119675Y1010708D01*
X119133Y1010792D01*
X118842Y1010917D01*
X118550Y1011125D01*
X118342Y1011417D01*
X118300Y1011708D01*
X118383Y1012000D01*
X118592Y1012208D01*
G01X117300Y995900D02*
X121300D01*
Y1003300D01*
G01X116300Y1004467D02*
X113800D01*
Y1005508D01*
X113925Y1005842D01*
X114092Y1006050D01*
X114425Y1006133D01*
X114758Y1006050D01*
X114967Y1005800D01*
X115092Y1005508D01*
Y1004467D01*
G01Y1005508D02*
X116300Y1006133D01*
G01Y1008900D02*
X113800D01*
X115592Y1007358D01*
Y1009442D01*
G01X115925Y1010583D02*
X116133Y1010833D01*
X116258Y1011125D01*
X116300Y1011500D01*
X116217Y1011875D01*
X116050Y1012167D01*
X115758Y1012375D01*
X115425Y1012417D01*
X115092Y1012333D01*
X114883Y1012125D01*
X114717Y1011833D01*
X114675Y1011542D01*
X114717Y1011250D01*
X114883Y1010875D01*
X113800Y1011000D01*
Y1012125D01*
G01X112800Y995900D02*
X116800D01*
Y1003300D01*
G01X101500Y994517D02*
X99000D01*
Y995517D01*
X99125Y995850D01*
X99417Y996100D01*
X99750Y996183D01*
X100083Y996100D01*
X100333Y995892D01*
X100458Y995517D01*
Y994517D01*
G01X101500Y997617D02*
X99000D01*
Y998658D01*
X99125Y998992D01*
X99292Y999200D01*
X99625Y999283D01*
X99958Y999200D01*
X100167Y998950D01*
X100292Y998658D01*
Y997617D01*
G01Y998658D02*
X101500Y999283D01*
G01X101125Y1000633D02*
X101333Y1000883D01*
X101458Y1001175D01*
X101500Y1001550D01*
X101417Y1001925D01*
X101250Y1002217D01*
X100958Y1002425D01*
X100625Y1002467D01*
X100292Y1002383D01*
X100083Y1002175D01*
X99917Y1001883D01*
X99875Y1001592D01*
X99917Y1001300D01*
X100083Y1000925D01*
X99000Y1001050D01*
Y1002175D01*
G01X101125Y1003733D02*
X101333Y1003983D01*
X101458Y1004275D01*
X101500Y1004650D01*
X101417Y1005025D01*
X101250Y1005317D01*
X100958Y1005525D01*
X100625Y1005567D01*
X100292Y1005483D01*
X100083Y1005275D01*
X99917Y1004983D01*
X99875Y1004692D01*
X99917Y1004400D01*
X100083Y1004025D01*
X99000Y1004150D01*
Y1005275D01*
G01X97000Y974300D02*
X101000D01*
Y981700D01*
G01X128500Y1019917D02*
X123500D01*
Y1023083D01*
G01X125917Y1021917D02*
Y1019917D01*
G01X128500Y1028100D02*
X123500D01*
X127083Y1025017D01*
Y1029183D01*
G01X128667Y1032700D02*
X128583Y1032533D01*
X128417D01*
X128333Y1032700D01*
X128417Y1032867D01*
X128583D01*
X128667Y1032700D01*
G01X126417D02*
X126333Y1032533D01*
X126167D01*
X126083Y1032700D01*
X126167Y1032867D01*
X126333D01*
X126417Y1032700D01*
G01X127500Y1036467D02*
X128083Y1036967D01*
X128417Y1037633D01*
X128500Y1038383D01*
X128417Y1039050D01*
X128000Y1039717D01*
X127500Y1040133D01*
X127000Y1040217D01*
X126417Y1040050D01*
X126000Y1039467D01*
X125833Y1038883D01*
Y1038133D01*
G01Y1038883D02*
X125583Y1039383D01*
X125167Y1039800D01*
X124667Y1039967D01*
X124167Y1039800D01*
X123750Y1039383D01*
X123500Y1038633D01*
X123583Y1037883D01*
X123917Y1037133D01*
G01X128500Y1041817D02*
X123500Y1043900D01*
X128500Y1045983D01*
G01X126750Y1045233D02*
Y1042567D01*
G01X128667Y1048000D02*
X123500Y1051000D01*
G01X128500Y1055100D02*
X123500D01*
X124500Y1054100D01*
G01X128500D02*
Y1056100D01*
G01X127750Y1058867D02*
X128167Y1059367D01*
X128417Y1059950D01*
X128500Y1060700D01*
X128333Y1061450D01*
X128000Y1062033D01*
X127417Y1062450D01*
X126750Y1062533D01*
X126083Y1062367D01*
X125667Y1061950D01*
X125333Y1061367D01*
X125250Y1060783D01*
X125333Y1060200D01*
X125667Y1059450D01*
X123500Y1059700D01*
Y1061950D01*
G01Y1064217D02*
X128500Y1066300D01*
X123500Y1068383D01*
G01X96500Y1061600D02*
Y1038600D01*
G01X83500Y1012033D02*
X81000D01*
Y1012867D01*
X81125Y1013200D01*
X81292Y1013450D01*
X81542Y1013658D01*
X81833Y1013825D01*
X82250Y1013867D01*
X82667Y1013825D01*
X82958Y1013658D01*
X83208Y1013450D01*
X83375Y1013200D01*
X83500Y1012867D01*
Y1012033D01*
G01Y1015967D02*
X82958Y1016050D01*
X82500Y1016175D01*
X82083Y1016342D01*
X81625Y1016550D01*
X81000Y1016883D01*
Y1015217D01*
G01X88500Y1031033D02*
X86000D01*
Y1031867D01*
X86125Y1032200D01*
X86292Y1032450D01*
X86542Y1032658D01*
X86833Y1032825D01*
X87250Y1032867D01*
X87667Y1032825D01*
X87958Y1032658D01*
X88208Y1032450D01*
X88375Y1032200D01*
X88500Y1031867D01*
Y1031033D01*
G01X88125Y1034133D02*
X88333Y1034383D01*
X88458Y1034675D01*
X88500Y1035050D01*
X88417Y1035425D01*
X88250Y1035717D01*
X87958Y1035925D01*
X87625Y1035967D01*
X87292Y1035883D01*
X87083Y1035675D01*
X86917Y1035383D01*
X86875Y1035092D01*
X86917Y1034800D01*
X87083Y1034425D01*
X86000Y1034550D01*
Y1035675D01*
G01X81600Y1028100D02*
Y1036100D01*
G01X111017Y1058692D02*
X110767Y1058817D01*
X110475Y1058900D01*
X110142D01*
X109767Y1058775D01*
X109475Y1058567D01*
X109267Y1058317D01*
X109100Y1057900D01*
X109058Y1057525D01*
X109142Y1057150D01*
X109267Y1056900D01*
X109517Y1056650D01*
X109808Y1056483D01*
X110100Y1056400D01*
X110392D01*
X110683Y1056483D01*
X110933Y1056608D01*
X111142Y1056775D01*
G01X113700Y1056400D02*
Y1058900D01*
X112158Y1057108D01*
X114242D01*
G01X116300Y1058900D02*
X115967Y1058817D01*
X115717Y1058608D01*
X115550Y1058358D01*
X115425Y1058025D01*
X115383Y1057650D01*
X115425Y1057275D01*
X115550Y1056942D01*
X115717Y1056692D01*
X115967Y1056483D01*
X116300Y1056400D01*
X116633Y1056483D01*
X116883Y1056692D01*
X117050Y1056942D01*
X117175Y1057275D01*
X117217Y1057650D01*
X117175Y1058025D01*
X117050Y1058358D01*
X116883Y1058608D01*
X116633Y1058817D01*
X116300Y1058900D01*
G01X111017Y1053992D02*
X110767Y1054117D01*
X110475Y1054200D01*
X110142D01*
X109767Y1054075D01*
X109475Y1053867D01*
X109267Y1053617D01*
X109100Y1053200D01*
X109058Y1052825D01*
X109142Y1052450D01*
X109267Y1052200D01*
X109517Y1051950D01*
X109808Y1051783D01*
X110100Y1051700D01*
X110392D01*
X110683Y1051783D01*
X110933Y1051908D01*
X111142Y1052075D01*
G01X112283Y1052200D02*
X112533Y1051908D01*
X112867Y1051742D01*
X113242Y1051700D01*
X113575Y1051742D01*
X113908Y1051950D01*
X114117Y1052200D01*
X114158Y1052450D01*
X114075Y1052742D01*
X113783Y1052950D01*
X113492Y1053033D01*
X113117D01*
G01X113492D02*
X113742Y1053158D01*
X113950Y1053367D01*
X114033Y1053617D01*
X113950Y1053867D01*
X113742Y1054075D01*
X113367Y1054200D01*
X112992Y1054158D01*
X112617Y1053992D01*
G01X115592Y1051992D02*
X115883Y1051783D01*
X116217Y1051700D01*
X116550Y1051783D01*
X116842Y1052033D01*
X117050Y1052408D01*
X117133Y1052783D01*
Y1053242D01*
X117050Y1053617D01*
X116842Y1053950D01*
X116592Y1054117D01*
X116300Y1054200D01*
X115967Y1054117D01*
X115717Y1053950D01*
X115550Y1053700D01*
X115467Y1053367D01*
X115550Y1053075D01*
X115758Y1052783D01*
X116008Y1052617D01*
X116300Y1052575D01*
X116633Y1052658D01*
X116883Y1052867D01*
X117133Y1053242D01*
G01X101317Y1013792D02*
X101067Y1013917D01*
X100775Y1014000D01*
X100442D01*
X100067Y1013875D01*
X99775Y1013667D01*
X99567Y1013417D01*
X99400Y1013000D01*
X99358Y1012625D01*
X99442Y1012250D01*
X99567Y1012000D01*
X99817Y1011750D01*
X100108Y1011583D01*
X100400Y1011500D01*
X100692D01*
X100983Y1011583D01*
X101233Y1011708D01*
X101442Y1011875D01*
G01X103500Y1011500D02*
Y1014000D01*
X103000Y1013500D01*
G01Y1011500D02*
X104000D01*
G01X105683Y1012000D02*
X105933Y1011708D01*
X106267Y1011542D01*
X106642Y1011500D01*
X106975Y1011542D01*
X107308Y1011750D01*
X107517Y1012000D01*
X107558Y1012250D01*
X107475Y1012542D01*
X107183Y1012750D01*
X106892Y1012833D01*
X106517D01*
G01X106892D02*
X107142Y1012958D01*
X107350Y1013167D01*
X107433Y1013417D01*
X107350Y1013667D01*
X107142Y1013875D01*
X106767Y1014000D01*
X106392Y1013958D01*
X106017Y1013792D01*
G01X107000Y1077417D02*
X102000D01*
Y1080583D01*
G01X104417Y1079417D02*
Y1077417D01*
G01X106250Y1082767D02*
X106667Y1083267D01*
X106917Y1083850D01*
X107000Y1084600D01*
X106833Y1085350D01*
X106500Y1085933D01*
X105917Y1086350D01*
X105250Y1086433D01*
X104583Y1086267D01*
X104167Y1085850D01*
X103833Y1085267D01*
X103750Y1084683D01*
X103833Y1084100D01*
X104167Y1083350D01*
X102000Y1083600D01*
Y1085850D01*
G01X107167Y1090200D02*
X107083Y1090033D01*
X106917D01*
X106833Y1090200D01*
X106917Y1090367D01*
X107083D01*
X107167Y1090200D01*
G01X104917D02*
X104833Y1090033D01*
X104667D01*
X104583Y1090200D01*
X104667Y1090367D01*
X104833D01*
X104917Y1090200D01*
G01X106000Y1093967D02*
X106583Y1094467D01*
X106917Y1095133D01*
X107000Y1095883D01*
X106917Y1096550D01*
X106500Y1097217D01*
X106000Y1097633D01*
X105500Y1097717D01*
X104917Y1097550D01*
X104500Y1096967D01*
X104333Y1096383D01*
Y1095633D01*
G01Y1096383D02*
X104083Y1096883D01*
X103667Y1097300D01*
X103167Y1097467D01*
X102667Y1097300D01*
X102250Y1096883D01*
X102000Y1096133D01*
X102083Y1095383D01*
X102417Y1094633D01*
G01X107000Y1099317D02*
X102000Y1101400D01*
X107000Y1103483D01*
G01X105250Y1102733D02*
Y1100067D01*
G01X107167Y1105500D02*
X102000Y1108500D01*
G01X107000Y1112600D02*
X102000D01*
X103000Y1111600D01*
G01X107000D02*
Y1113600D01*
G01X106250Y1116367D02*
X106667Y1116867D01*
X106917Y1117450D01*
X107000Y1118200D01*
X106833Y1118950D01*
X106500Y1119533D01*
X105917Y1119950D01*
X105250Y1120033D01*
X104583Y1119867D01*
X104167Y1119450D01*
X103833Y1118867D01*
X103750Y1118283D01*
X103833Y1117700D01*
X104167Y1116950D01*
X102000Y1117200D01*
Y1119450D01*
G01Y1121717D02*
X107000Y1123800D01*
X102000Y1125883D01*
G01X95300Y1099600D02*
X84100D01*
G01X95300Y1081600D02*
Y1099600D01*
G01X84100Y1081600D02*
X95300D01*
G01X83617Y1067800D02*
Y1070300D01*
X84658D01*
X84992Y1070175D01*
X85200Y1070008D01*
X85283Y1069675D01*
X85200Y1069342D01*
X84950Y1069133D01*
X84658Y1069008D01*
X83617D01*
G01X84658D02*
X85283Y1067800D01*
G01X87550D02*
Y1070300D01*
X87050Y1069800D01*
G01Y1067800D02*
X88050D01*
G01X90567D02*
X90650Y1068342D01*
X90775Y1068800D01*
X90942Y1069217D01*
X91150Y1069675D01*
X91483Y1070300D01*
X89817D01*
G01X93042Y1068092D02*
X93333Y1067883D01*
X93667Y1067800D01*
X94000Y1067883D01*
X94292Y1068133D01*
X94500Y1068508D01*
X94583Y1068883D01*
Y1069342D01*
X94500Y1069717D01*
X94292Y1070050D01*
X94042Y1070217D01*
X93750Y1070300D01*
X93417Y1070217D01*
X93167Y1070050D01*
X93000Y1069800D01*
X92917Y1069467D01*
X93000Y1069175D01*
X93208Y1068883D01*
X93458Y1068717D01*
X93750Y1068675D01*
X94083Y1068758D01*
X94333Y1068967D01*
X94583Y1069342D01*
G01X80800Y1065700D02*
Y1073700D01*
G01X120658Y1114500D02*
Y1117000D01*
X122242D01*
G01X121658Y1115792D02*
X120658D01*
G01X123633Y1114875D02*
X123883Y1114667D01*
X124175Y1114542D01*
X124550Y1114500D01*
X124925Y1114583D01*
X125217Y1114750D01*
X125425Y1115042D01*
X125467Y1115375D01*
X125383Y1115708D01*
X125175Y1115917D01*
X124883Y1116083D01*
X124592Y1116125D01*
X124300Y1116083D01*
X123925Y1115917D01*
X124050Y1117000D01*
X125175D01*
G01X110597Y1158098D02*
X133597D01*
G01X110597Y1119298D02*
Y1158098D01*
G01X133597Y1119298D02*
X110597D01*
G01X84483Y1113000D02*
Y1115500D01*
X85317D01*
X85650Y1115375D01*
X85900Y1115208D01*
X86108Y1114958D01*
X86275Y1114667D01*
X86317Y1114250D01*
X86275Y1113833D01*
X86108Y1113542D01*
X85900Y1113292D01*
X85650Y1113125D01*
X85317Y1113000D01*
X84483D01*
G01X88500D02*
Y1115500D01*
X88000Y1115000D01*
G01Y1113000D02*
X89000D01*
G01X91600Y1115500D02*
X91267Y1115417D01*
X91017Y1115208D01*
X90850Y1114958D01*
X90725Y1114625D01*
X90683Y1114250D01*
X90725Y1113875D01*
X90850Y1113542D01*
X91017Y1113292D01*
X91267Y1113083D01*
X91600Y1113000D01*
X91933Y1113083D01*
X92183Y1113292D01*
X92350Y1113542D01*
X92475Y1113875D01*
X92517Y1114250D01*
X92475Y1114625D01*
X92350Y1114958D01*
X92183Y1115208D01*
X91933Y1115417D01*
X91600Y1115500D01*
G01X92502Y1119097D02*
Y1140097D01*
G01D02*
X84502D01*
G01D02*
Y1119097D01*
G01D02*
X92502D01*
G01X86417Y1148492D02*
X86167Y1148617D01*
X85875Y1148700D01*
X85542D01*
X85167Y1148575D01*
X84875Y1148367D01*
X84667Y1148117D01*
X84500Y1147700D01*
X84458Y1147325D01*
X84542Y1146950D01*
X84667Y1146700D01*
X84917Y1146450D01*
X85208Y1146283D01*
X85500Y1146200D01*
X85792D01*
X86083Y1146283D01*
X86333Y1146408D01*
X86542Y1146575D01*
G01X89100Y1146200D02*
Y1148700D01*
X87558Y1146908D01*
X89642D01*
G01X92200Y1146200D02*
Y1148700D01*
X90658Y1146908D01*
X92742D01*
G01X105000Y1152517D02*
X102500D01*
Y1153558D01*
X102625Y1153892D01*
X102792Y1154100D01*
X103125Y1154183D01*
X103458Y1154100D01*
X103667Y1153850D01*
X103792Y1153558D01*
Y1152517D01*
G01Y1153558D02*
X105000Y1154183D01*
G01Y1156450D02*
X102500D01*
X103000Y1155950D01*
G01X105000D02*
Y1156950D01*
G01Y1159467D02*
X104458Y1159550D01*
X104000Y1159675D01*
X103583Y1159842D01*
X103125Y1160050D01*
X102500Y1160383D01*
Y1158717D01*
G01X105000Y1162650D02*
X104958Y1162942D01*
X104833Y1163275D01*
X104625Y1163483D01*
X104333Y1163567D01*
X104042Y1163483D01*
X103792Y1163233D01*
X103667Y1162858D01*
Y1162442D01*
X103583Y1162192D01*
X103375Y1161983D01*
X103083Y1161900D01*
X102792Y1162025D01*
X102583Y1162317D01*
X102500Y1162650D01*
X102583Y1162983D01*
X102792Y1163275D01*
X103083Y1163400D01*
X103375Y1163317D01*
X103583Y1163108D01*
X103667Y1162858D01*
Y1162442D01*
X103792Y1162067D01*
X104042Y1161817D01*
X104333Y1161733D01*
X104625Y1161817D01*
X104833Y1162025D01*
X104958Y1162358D01*
X105000Y1162650D01*
G01X101100Y1148300D02*
Y1130700D01*
G01X109100Y1148300D02*
X101100D01*
G01X109100Y1130700D02*
Y1148300D01*
G01X101100Y1130700D02*
X109100D01*
G01X95950Y1258500D02*
X95617Y1258542D01*
X95325Y1258708D01*
X95075Y1258958D01*
X94908Y1259250D01*
X94825Y1259583D01*
Y1259917D01*
X94908Y1260250D01*
X95075Y1260542D01*
X95325Y1260792D01*
X95617Y1260958D01*
X95950Y1261000D01*
X96283Y1260958D01*
X96575Y1260792D01*
X96825Y1260542D01*
X96992Y1260250D01*
X97075Y1259917D01*
Y1259583D01*
X96992Y1259250D01*
X96825Y1258958D01*
X96575Y1258708D01*
X96283Y1258542D01*
X95950Y1258500D01*
G01X96283Y1259167D02*
X96783Y1258500D01*
G01X98258Y1260583D02*
X98508Y1260833D01*
X98800Y1260958D01*
X99133Y1261000D01*
X99550Y1260917D01*
X99842Y1260708D01*
X99925Y1260458D01*
X99883Y1260208D01*
X99717Y1260000D01*
X98883Y1259583D01*
X98508Y1259292D01*
X98258Y1258875D01*
X98175Y1258500D01*
X99925D01*
G01X101268Y1253343D02*
X115268D01*
G01X101268Y1266343D02*
Y1253343D01*
G01X115268D02*
Y1266343D01*
G01X86000Y1277633D02*
X81000D01*
X85167Y1279800D01*
X81000Y1281967D01*
X86000D01*
G01Y1283317D02*
X81000Y1285400D01*
X86000Y1287483D01*
G01X84250Y1286733D02*
Y1284067D01*
G01X86000Y1289167D02*
X81000D01*
Y1290833D01*
X81250Y1291500D01*
X81583Y1292000D01*
X82083Y1292417D01*
X82667Y1292750D01*
X83500Y1292833D01*
X84333Y1292750D01*
X84917Y1292417D01*
X85417Y1292000D01*
X85750Y1291500D01*
X86000Y1290833D01*
Y1289167D01*
G01Y1298267D02*
Y1294933D01*
X81000D01*
Y1298267D01*
G01X83417Y1296933D02*
Y1294933D01*
G01X81000Y1306800D02*
Y1308800D01*
G01Y1307800D02*
X86000D01*
G01Y1306800D02*
Y1308800D01*
G01Y1311483D02*
X81000D01*
X86000Y1315317D01*
X81000D01*
G01Y1324600D02*
X86000D01*
G01X81000Y1322683D02*
Y1326517D01*
G01X86000Y1328117D02*
X81000Y1330200D01*
X86000Y1332283D01*
G01X84250Y1331533D02*
Y1328867D01*
G01X81000Y1334800D02*
Y1336800D01*
G01Y1335800D02*
X86000D01*
G01Y1334800D02*
Y1336800D01*
G01X81000Y1338900D02*
X86000Y1340067D01*
X81000Y1341400D01*
X86000Y1342733D01*
X81000Y1343900D01*
G01X86000Y1344917D02*
X81000Y1347000D01*
X86000Y1349083D01*
G01X84250Y1348333D02*
Y1345667D01*
G01X86000Y1350683D02*
X81000D01*
X86000Y1354517D01*
X81000D01*
G01X115268Y1266343D02*
X101268D01*
G01X123767Y1362292D02*
X123517Y1362417D01*
X123225Y1362500D01*
X122892D01*
X122517Y1362375D01*
X122225Y1362167D01*
X122017Y1361917D01*
X121850Y1361500D01*
X121808Y1361125D01*
X121892Y1360750D01*
X122017Y1360500D01*
X122267Y1360250D01*
X122558Y1360083D01*
X122850Y1360000D01*
X123142D01*
X123433Y1360083D01*
X123683Y1360208D01*
X123892Y1360375D01*
G01X125158Y1362083D02*
X125408Y1362333D01*
X125700Y1362458D01*
X126033Y1362500D01*
X126450Y1362417D01*
X126742Y1362208D01*
X126825Y1361958D01*
X126783Y1361708D01*
X126617Y1361500D01*
X125783Y1361083D01*
X125408Y1360792D01*
X125158Y1360375D01*
X125075Y1360000D01*
X126825D01*
G01X128133Y1360375D02*
X128383Y1360167D01*
X128675Y1360042D01*
X129050Y1360000D01*
X129425Y1360083D01*
X129717Y1360250D01*
X129925Y1360542D01*
X129967Y1360875D01*
X129883Y1361208D01*
X129675Y1361417D01*
X129383Y1361583D01*
X129092Y1361625D01*
X128800Y1361583D01*
X128425Y1361417D01*
X128550Y1362500D01*
X129675D01*
G01X131442Y1360292D02*
X131733Y1360083D01*
X132067Y1360000D01*
X132400Y1360083D01*
X132692Y1360333D01*
X132900Y1360708D01*
X132983Y1361083D01*
Y1361542D01*
X132900Y1361917D01*
X132692Y1362250D01*
X132442Y1362417D01*
X132150Y1362500D01*
X131817Y1362417D01*
X131567Y1362250D01*
X131400Y1362000D01*
X131317Y1361667D01*
X131400Y1361375D01*
X131608Y1361083D01*
X131858Y1360917D01*
X132150Y1360875D01*
X132483Y1360958D01*
X132733Y1361167D01*
X132983Y1361542D01*
G01X106767Y1362292D02*
X106517Y1362417D01*
X106225Y1362500D01*
X105892D01*
X105517Y1362375D01*
X105225Y1362167D01*
X105017Y1361917D01*
X104850Y1361500D01*
X104808Y1361125D01*
X104892Y1360750D01*
X105017Y1360500D01*
X105267Y1360250D01*
X105558Y1360083D01*
X105850Y1360000D01*
X106142D01*
X106433Y1360083D01*
X106683Y1360208D01*
X106892Y1360375D01*
G01X108158Y1362083D02*
X108408Y1362333D01*
X108700Y1362458D01*
X109033Y1362500D01*
X109450Y1362417D01*
X109742Y1362208D01*
X109825Y1361958D01*
X109783Y1361708D01*
X109617Y1361500D01*
X108783Y1361083D01*
X108408Y1360792D01*
X108158Y1360375D01*
X108075Y1360000D01*
X109825D01*
G01X111258Y1361042D02*
X111550Y1361333D01*
X111800Y1361500D01*
X112133Y1361583D01*
X112425Y1361500D01*
X112633Y1361333D01*
X112800Y1361083D01*
X112842Y1360792D01*
X112800Y1360542D01*
X112633Y1360292D01*
X112383Y1360083D01*
X112092Y1360000D01*
X111758Y1360083D01*
X111467Y1360333D01*
X111300Y1360708D01*
X111258Y1361125D01*
X111342Y1361667D01*
X111467Y1361958D01*
X111675Y1362250D01*
X111967Y1362458D01*
X112258Y1362500D01*
X112550Y1362417D01*
X112758Y1362208D01*
G01X115150Y1362500D02*
X114817Y1362417D01*
X114567Y1362208D01*
X114400Y1361958D01*
X114275Y1361625D01*
X114233Y1361250D01*
X114275Y1360875D01*
X114400Y1360542D01*
X114567Y1360292D01*
X114817Y1360083D01*
X115150Y1360000D01*
X115483Y1360083D01*
X115733Y1360292D01*
X115900Y1360542D01*
X116025Y1360875D01*
X116067Y1361250D01*
X116025Y1361625D01*
X115900Y1361958D01*
X115733Y1362208D01*
X115483Y1362417D01*
X115150Y1362500D01*
G01X117400Y1365000D02*
X117067Y1365042D01*
X116775Y1365208D01*
X116525Y1365458D01*
X116358Y1365750D01*
X116275Y1366083D01*
Y1366417D01*
X116358Y1366750D01*
X116525Y1367042D01*
X116775Y1367292D01*
X117067Y1367458D01*
X117400Y1367500D01*
X117733Y1367458D01*
X118025Y1367292D01*
X118275Y1367042D01*
X118442Y1366750D01*
X118525Y1366417D01*
Y1366083D01*
X118442Y1365750D01*
X118275Y1365458D01*
X118025Y1365208D01*
X117733Y1365042D01*
X117400Y1365000D01*
G01X117733Y1365667D02*
X118233Y1365000D01*
G01X121000D02*
Y1367500D01*
X119458Y1365708D01*
X121542D01*
G01X122892Y1365292D02*
X123183Y1365083D01*
X123517Y1365000D01*
X123850Y1365083D01*
X124142Y1365333D01*
X124350Y1365708D01*
X124433Y1366083D01*
Y1366542D01*
X124350Y1366917D01*
X124142Y1367250D01*
X123892Y1367417D01*
X123600Y1367500D01*
X123267Y1367417D01*
X123017Y1367250D01*
X122850Y1367000D01*
X122767Y1366667D01*
X122850Y1366375D01*
X123058Y1366083D01*
X123308Y1365917D01*
X123600Y1365875D01*
X123933Y1365958D01*
X124183Y1366167D01*
X124433Y1366542D01*
G01X121396Y1396300D02*
X126896D01*
G01X121396Y1388300D02*
Y1396300D01*
G01X126896Y1388300D02*
X121396D01*
G01X120300Y1383500D02*
X114800D01*
G01X120300Y1391500D02*
Y1383500D01*
G01X114800Y1391500D02*
X120300D01*
G01X102700D02*
X108200D01*
G01X102700Y1383500D02*
Y1391500D01*
G01X108200Y1383500D02*
X102700D01*
G01X134000Y1415017D02*
X131500D01*
Y1416017D01*
X131625Y1416350D01*
X131917Y1416600D01*
X132250Y1416683D01*
X132583Y1416600D01*
X132833Y1416392D01*
X132958Y1416017D01*
Y1415017D01*
G01X134000Y1418117D02*
X131500D01*
Y1419158D01*
X131625Y1419492D01*
X131792Y1419700D01*
X132125Y1419783D01*
X132458Y1419700D01*
X132667Y1419450D01*
X132792Y1419158D01*
Y1418117D01*
G01Y1419158D02*
X134000Y1419783D01*
G01X133500Y1421133D02*
X133792Y1421383D01*
X133958Y1421717D01*
X134000Y1422092D01*
X133958Y1422425D01*
X133750Y1422758D01*
X133500Y1422967D01*
X133250Y1423008D01*
X132958Y1422925D01*
X132750Y1422633D01*
X132667Y1422342D01*
Y1421967D01*
G01Y1422342D02*
X132542Y1422592D01*
X132333Y1422800D01*
X132083Y1422883D01*
X131833Y1422800D01*
X131625Y1422592D01*
X131500Y1422217D01*
X131542Y1421842D01*
X131708Y1421467D01*
G01X133708Y1424442D02*
X133917Y1424733D01*
X134000Y1425067D01*
X133917Y1425400D01*
X133667Y1425692D01*
X133292Y1425900D01*
X132917Y1425983D01*
X132458D01*
X132083Y1425900D01*
X131750Y1425692D01*
X131583Y1425442D01*
X131500Y1425150D01*
X131583Y1424817D01*
X131750Y1424567D01*
X132000Y1424400D01*
X132333Y1424317D01*
X132625Y1424400D01*
X132917Y1424608D01*
X133083Y1424858D01*
X133125Y1425150D01*
X133042Y1425483D01*
X132833Y1425733D01*
X132458Y1425983D01*
G01X124000Y1370017D02*
X121500D01*
Y1371058D01*
X121625Y1371392D01*
X121792Y1371600D01*
X122125Y1371683D01*
X122458Y1371600D01*
X122667Y1371350D01*
X122792Y1371058D01*
Y1370017D01*
G01Y1371058D02*
X124000Y1371683D01*
G01Y1373950D02*
X121500D01*
X122000Y1373450D01*
G01X124000D02*
Y1374450D01*
G01X121500Y1377050D02*
X121583Y1376717D01*
X121792Y1376467D01*
X122042Y1376300D01*
X122375Y1376175D01*
X122750Y1376133D01*
X123125Y1376175D01*
X123458Y1376300D01*
X123708Y1376467D01*
X123917Y1376717D01*
X124000Y1377050D01*
X123917Y1377383D01*
X123708Y1377633D01*
X123458Y1377800D01*
X123125Y1377925D01*
X122750Y1377967D01*
X122375Y1377925D01*
X122042Y1377800D01*
X121792Y1377633D01*
X121583Y1377383D01*
X121500Y1377050D01*
G01X123708Y1379442D02*
X123917Y1379733D01*
X124000Y1380067D01*
X123917Y1380400D01*
X123667Y1380692D01*
X123292Y1380900D01*
X122917Y1380983D01*
X122458D01*
X122083Y1380900D01*
X121750Y1380692D01*
X121583Y1380442D01*
X121500Y1380150D01*
X121583Y1379817D01*
X121750Y1379567D01*
X122000Y1379400D01*
X122333Y1379317D01*
X122625Y1379400D01*
X122917Y1379608D01*
X123083Y1379858D01*
X123125Y1380150D01*
X123042Y1380483D01*
X122833Y1380733D01*
X122458Y1380983D01*
G01X129000Y1370017D02*
X126500D01*
Y1371058D01*
X126625Y1371392D01*
X126792Y1371600D01*
X127125Y1371683D01*
X127458Y1371600D01*
X127667Y1371350D01*
X127792Y1371058D01*
Y1370017D01*
G01Y1371058D02*
X129000Y1371683D01*
G01Y1373950D02*
X126500D01*
X127000Y1373450D01*
G01X129000D02*
Y1374450D01*
G01X126500Y1377050D02*
X126583Y1376717D01*
X126792Y1376467D01*
X127042Y1376300D01*
X127375Y1376175D01*
X127750Y1376133D01*
X128125Y1376175D01*
X128458Y1376300D01*
X128708Y1376467D01*
X128917Y1376717D01*
X129000Y1377050D01*
X128917Y1377383D01*
X128708Y1377633D01*
X128458Y1377800D01*
X128125Y1377925D01*
X127750Y1377967D01*
X127375Y1377925D01*
X127042Y1377800D01*
X126792Y1377633D01*
X126583Y1377383D01*
X126500Y1377050D01*
G01X129000Y1380150D02*
X128958Y1380442D01*
X128833Y1380775D01*
X128625Y1380983D01*
X128333Y1381067D01*
X128042Y1380983D01*
X127792Y1380733D01*
X127667Y1380358D01*
Y1379942D01*
X127583Y1379692D01*
X127375Y1379483D01*
X127083Y1379400D01*
X126792Y1379525D01*
X126583Y1379817D01*
X126500Y1380150D01*
X126583Y1380483D01*
X126792Y1380775D01*
X127083Y1380900D01*
X127375Y1380817D01*
X127583Y1380608D01*
X127667Y1380358D01*
Y1379942D01*
X127792Y1379567D01*
X128042Y1379317D01*
X128333Y1379233D01*
X128625Y1379317D01*
X128833Y1379525D01*
X128958Y1379858D01*
X129000Y1380150D01*
G01X83500Y1414567D02*
X81000D01*
Y1415567D01*
X81125Y1415900D01*
X81417Y1416150D01*
X81750Y1416233D01*
X82083Y1416150D01*
X82333Y1415942D01*
X82458Y1415567D01*
Y1414567D01*
G01X83500Y1417667D02*
X81000D01*
Y1418708D01*
X81125Y1419042D01*
X81292Y1419250D01*
X81625Y1419333D01*
X81958Y1419250D01*
X82167Y1419000D01*
X82292Y1418708D01*
Y1417667D01*
G01Y1418708D02*
X83500Y1419333D01*
G01X83208Y1420892D02*
X83417Y1421183D01*
X83500Y1421517D01*
X83417Y1421850D01*
X83167Y1422142D01*
X82792Y1422350D01*
X82417Y1422433D01*
X81958D01*
X81583Y1422350D01*
X81250Y1422142D01*
X81083Y1421892D01*
X81000Y1421600D01*
X81083Y1421267D01*
X81250Y1421017D01*
X81500Y1420850D01*
X81833Y1420767D01*
X82125Y1420850D01*
X82417Y1421058D01*
X82583Y1421308D01*
X82625Y1421600D01*
X82542Y1421933D01*
X82333Y1422183D01*
X81958Y1422433D01*
G01X104317Y1411500D02*
Y1414000D01*
X105317D01*
X105650Y1413875D01*
X105900Y1413583D01*
X105983Y1413250D01*
X105900Y1412917D01*
X105692Y1412667D01*
X105317Y1412542D01*
X104317D01*
G01X107417Y1411500D02*
Y1414000D01*
X108458D01*
X108792Y1413875D01*
X109000Y1413708D01*
X109083Y1413375D01*
X109000Y1413042D01*
X108750Y1412833D01*
X108458Y1412708D01*
X107417D01*
G01X108458D02*
X109083Y1411500D01*
G01X111350D02*
Y1414000D01*
X110850Y1413500D01*
G01Y1411500D02*
X111850D01*
G01X113658Y1412542D02*
X113950Y1412833D01*
X114200Y1413000D01*
X114533Y1413083D01*
X114825Y1413000D01*
X115033Y1412833D01*
X115200Y1412583D01*
X115242Y1412292D01*
X115200Y1412042D01*
X115033Y1411792D01*
X114783Y1411583D01*
X114492Y1411500D01*
X114158Y1411583D01*
X113867Y1411833D01*
X113700Y1412208D01*
X113658Y1412625D01*
X113742Y1413167D01*
X113867Y1413458D01*
X114075Y1413750D01*
X114367Y1413958D01*
X114658Y1414000D01*
X114950Y1413917D01*
X115158Y1413708D01*
G01X119000Y1370017D02*
X116500D01*
Y1371017D01*
X116625Y1371350D01*
X116917Y1371600D01*
X117250Y1371683D01*
X117583Y1371600D01*
X117833Y1371392D01*
X117958Y1371017D01*
Y1370017D01*
G01X119000Y1373117D02*
X116500D01*
Y1374158D01*
X116625Y1374492D01*
X116792Y1374700D01*
X117125Y1374783D01*
X117458Y1374700D01*
X117667Y1374450D01*
X117792Y1374158D01*
Y1373117D01*
G01Y1374158D02*
X119000Y1374783D01*
G01Y1377050D02*
X116500D01*
X117000Y1376550D01*
G01X119000D02*
Y1377550D01*
G01X118625Y1379233D02*
X118833Y1379483D01*
X118958Y1379775D01*
X119000Y1380150D01*
X118917Y1380525D01*
X118750Y1380817D01*
X118458Y1381025D01*
X118125Y1381067D01*
X117792Y1380983D01*
X117583Y1380775D01*
X117417Y1380483D01*
X117375Y1380192D01*
X117417Y1379900D01*
X117583Y1379525D01*
X116500Y1379650D01*
Y1380775D01*
G01X104517Y1415000D02*
Y1417500D01*
X105517D01*
X105850Y1417375D01*
X106100Y1417083D01*
X106183Y1416750D01*
X106100Y1416417D01*
X105892Y1416167D01*
X105517Y1416042D01*
X104517D01*
G01X107617Y1415000D02*
Y1417500D01*
X108658D01*
X108992Y1417375D01*
X109200Y1417208D01*
X109283Y1416875D01*
X109200Y1416542D01*
X108950Y1416333D01*
X108658Y1416208D01*
X107617D01*
G01X108658D02*
X109283Y1415000D01*
G01X111550D02*
Y1417500D01*
X111050Y1417000D01*
G01Y1415000D02*
X112050D01*
G01X113858Y1417083D02*
X114108Y1417333D01*
X114400Y1417458D01*
X114733Y1417500D01*
X115150Y1417417D01*
X115442Y1417208D01*
X115525Y1416958D01*
X115483Y1416708D01*
X115317Y1416500D01*
X114483Y1416083D01*
X114108Y1415792D01*
X113858Y1415375D01*
X113775Y1415000D01*
X115525D01*
G01X87500Y1414567D02*
X85000D01*
Y1415567D01*
X85125Y1415900D01*
X85417Y1416150D01*
X85750Y1416233D01*
X86083Y1416150D01*
X86333Y1415942D01*
X86458Y1415567D01*
Y1414567D01*
G01X87500Y1417667D02*
X85000D01*
Y1418708D01*
X85125Y1419042D01*
X85292Y1419250D01*
X85625Y1419333D01*
X85958Y1419250D01*
X86167Y1419000D01*
X86292Y1418708D01*
Y1417667D01*
G01Y1418708D02*
X87500Y1419333D01*
G01Y1421600D02*
X85000D01*
X85500Y1421100D01*
G01X87500D02*
Y1422100D01*
G01Y1424700D02*
X85000D01*
X85500Y1424200D01*
G01X87500D02*
Y1425200D01*
G01X86458Y1427008D02*
X86167Y1427300D01*
X86000Y1427550D01*
X85917Y1427883D01*
X86000Y1428175D01*
X86167Y1428383D01*
X86417Y1428550D01*
X86708Y1428592D01*
X86958Y1428550D01*
X87208Y1428383D01*
X87417Y1428133D01*
X87500Y1427842D01*
X87417Y1427508D01*
X87167Y1427217D01*
X86792Y1427050D01*
X86375Y1427008D01*
X85833Y1427092D01*
X85542Y1427217D01*
X85250Y1427425D01*
X85042Y1427717D01*
X85000Y1428008D01*
X85083Y1428300D01*
X85292Y1428508D01*
G01X109500Y1406100D02*
Y1410100D01*
X102100D01*
G01X84817Y1407200D02*
Y1409700D01*
X85858D01*
X86192Y1409575D01*
X86400Y1409408D01*
X86483Y1409075D01*
X86400Y1408742D01*
X86150Y1408533D01*
X85858Y1408408D01*
X84817D01*
G01X85858D02*
X86483Y1407200D01*
G01X87833Y1407700D02*
X88083Y1407408D01*
X88417Y1407242D01*
X88792Y1407200D01*
X89125Y1407242D01*
X89458Y1407450D01*
X89667Y1407700D01*
X89708Y1407950D01*
X89625Y1408242D01*
X89333Y1408450D01*
X89042Y1408533D01*
X88667D01*
G01X89042D02*
X89292Y1408658D01*
X89500Y1408867D01*
X89583Y1409117D01*
X89500Y1409367D01*
X89292Y1409575D01*
X88917Y1409700D01*
X88542Y1409658D01*
X88167Y1409492D01*
G01X91058Y1408242D02*
X91350Y1408533D01*
X91600Y1408700D01*
X91933Y1408783D01*
X92225Y1408700D01*
X92433Y1408533D01*
X92600Y1408283D01*
X92642Y1407992D01*
X92600Y1407742D01*
X92433Y1407492D01*
X92183Y1407283D01*
X91892Y1407200D01*
X91558Y1407283D01*
X91267Y1407533D01*
X91100Y1407908D01*
X91058Y1408325D01*
X91142Y1408867D01*
X91267Y1409158D01*
X91475Y1409450D01*
X91767Y1409658D01*
X92058Y1409700D01*
X92350Y1409617D01*
X92558Y1409408D01*
G01X94158Y1408242D02*
X94450Y1408533D01*
X94700Y1408700D01*
X95033Y1408783D01*
X95325Y1408700D01*
X95533Y1408533D01*
X95700Y1408283D01*
X95742Y1407992D01*
X95700Y1407742D01*
X95533Y1407492D01*
X95283Y1407283D01*
X94992Y1407200D01*
X94658Y1407283D01*
X94367Y1407533D01*
X94200Y1407908D01*
X94158Y1408325D01*
X94242Y1408867D01*
X94367Y1409158D01*
X94575Y1409450D01*
X94867Y1409658D01*
X95158Y1409700D01*
X95450Y1409617D01*
X95658Y1409408D01*
G01X109900Y1410200D02*
Y1406200D01*
X117300D01*
G01X101500Y1395400D02*
X101458Y1395067D01*
X101292Y1394775D01*
X101042Y1394525D01*
X100750Y1394358D01*
X100417Y1394275D01*
X100083D01*
X99750Y1394358D01*
X99458Y1394525D01*
X99208Y1394775D01*
X99042Y1395067D01*
X99000Y1395400D01*
X99042Y1395733D01*
X99208Y1396025D01*
X99458Y1396275D01*
X99750Y1396442D01*
X100083Y1396525D01*
X100417D01*
X100750Y1396442D01*
X101042Y1396275D01*
X101292Y1396025D01*
X101458Y1395733D01*
X101500Y1395400D01*
G01X100833Y1395733D02*
X101500Y1396233D01*
G01Y1398500D02*
X99000D01*
X99500Y1398000D01*
G01X101500D02*
Y1399000D01*
G01X99000Y1401600D02*
X99083Y1401267D01*
X99292Y1401017D01*
X99542Y1400850D01*
X99875Y1400725D01*
X100250Y1400683D01*
X100625Y1400725D01*
X100958Y1400850D01*
X101208Y1401017D01*
X101417Y1401267D01*
X101500Y1401600D01*
X101417Y1401933D01*
X101208Y1402183D01*
X100958Y1402350D01*
X100625Y1402475D01*
X100250Y1402517D01*
X99875Y1402475D01*
X99542Y1402350D01*
X99292Y1402183D01*
X99083Y1401933D01*
X99000Y1401600D01*
G01X116800Y1394000D02*
Y1405400D01*
G01X103400Y1394000D02*
X116800D01*
G01X103400Y1405400D02*
Y1394000D01*
G01X116800Y1405400D02*
X103400D01*
G01X118500Y1412704D02*
Y1398704D01*
G01X131500Y1412704D02*
X118500D01*
G01X131500Y1398704D02*
Y1412704D01*
G01X118500Y1398704D02*
X131500D01*
G01X115867Y1467100D02*
Y1469600D01*
X116867D01*
X117200Y1469475D01*
X117450Y1469183D01*
X117533Y1468850D01*
X117450Y1468517D01*
X117242Y1468267D01*
X116867Y1468142D01*
X115867D01*
G01X118883Y1469600D02*
Y1467808D01*
X119050Y1467433D01*
X119383Y1467183D01*
X119800Y1467100D01*
X120217Y1467183D01*
X120550Y1467433D01*
X120717Y1467808D01*
Y1469600D01*
G01X122900Y1467100D02*
Y1469600D01*
X122400Y1469100D01*
G01Y1467100D02*
X123400D01*
G01X111900Y1465000D02*
Y1468000D01*
G01X122100Y1436000D02*
Y1439000D01*
G01X132000Y1457100D02*
X130000D01*
G01X104000Y1446800D02*
X102000D01*
G01X130850Y1460850D02*
Y1465850D01*
X125850D01*
G01Y1438150D02*
X130850D01*
Y1443150D01*
G01X108150Y1438150D02*
X103150D01*
Y1443150D01*
G01X103950Y1433800D02*
Y1431300D01*
G01X102992Y1433800D02*
X104908D01*
G01X106217Y1431300D02*
Y1433800D01*
X107217D01*
X107550Y1433675D01*
X107800Y1433383D01*
X107883Y1433050D01*
X107800Y1432717D01*
X107592Y1432467D01*
X107217Y1432342D01*
X106217D01*
G01X109358Y1433383D02*
X109608Y1433633D01*
X109900Y1433758D01*
X110233Y1433800D01*
X110650Y1433717D01*
X110942Y1433508D01*
X111025Y1433258D01*
X110983Y1433008D01*
X110817Y1432800D01*
X109983Y1432383D01*
X109608Y1432092D01*
X109358Y1431675D01*
X109275Y1431300D01*
X111025D01*
G01X112458Y1433383D02*
X112708Y1433633D01*
X113000Y1433758D01*
X113333Y1433800D01*
X113750Y1433717D01*
X114042Y1433508D01*
X114125Y1433258D01*
X114083Y1433008D01*
X113917Y1432800D01*
X113083Y1432383D01*
X112708Y1432092D01*
X112458Y1431675D01*
X112375Y1431300D01*
X114125D01*
G01X135200Y1426300D02*
Y1430300D01*
X127800D01*
G01X121000Y1418800D02*
X125000D01*
Y1426200D01*
G01X125500Y1418800D02*
X129500D01*
Y1426200D01*
G01X102500Y1425700D02*
X98500D01*
Y1418300D01*
G01X93500Y1425700D02*
X89500D01*
Y1418300D01*
G01X94817Y1467100D02*
Y1469600D01*
X95817D01*
X96150Y1469475D01*
X96400Y1469183D01*
X96483Y1468850D01*
X96400Y1468517D01*
X96192Y1468267D01*
X95817Y1468142D01*
X94817D01*
G01X97917Y1467100D02*
Y1469600D01*
X98958D01*
X99292Y1469475D01*
X99500Y1469308D01*
X99583Y1468975D01*
X99500Y1468642D01*
X99250Y1468433D01*
X98958Y1468308D01*
X97917D01*
G01X98958D02*
X99583Y1467100D01*
G01X100933Y1467600D02*
X101183Y1467308D01*
X101517Y1467142D01*
X101892Y1467100D01*
X102225Y1467142D01*
X102558Y1467350D01*
X102767Y1467600D01*
X102808Y1467850D01*
X102725Y1468142D01*
X102433Y1468350D01*
X102142Y1468433D01*
X101767D01*
G01X102142D02*
X102392Y1468558D01*
X102600Y1468767D01*
X102683Y1469017D01*
X102600Y1469267D01*
X102392Y1469475D01*
X102017Y1469600D01*
X101642Y1469558D01*
X101267Y1469392D01*
G01X104158Y1468142D02*
X104450Y1468433D01*
X104700Y1468600D01*
X105033Y1468683D01*
X105325Y1468600D01*
X105533Y1468433D01*
X105700Y1468183D01*
X105742Y1467892D01*
X105700Y1467642D01*
X105533Y1467392D01*
X105283Y1467183D01*
X104992Y1467100D01*
X104658Y1467183D01*
X104367Y1467433D01*
X104200Y1467808D01*
X104158Y1468225D01*
X104242Y1468767D01*
X104367Y1469058D01*
X104575Y1469350D01*
X104867Y1469558D01*
X105158Y1469600D01*
X105450Y1469517D01*
X105658Y1469308D01*
G01X93500Y1458800D02*
X97500D01*
Y1466200D01*
G01X89300Y1453000D02*
Y1449000D01*
X96700D01*
G01X85500Y1467200D02*
X81500D01*
Y1459800D01*
G01X96700Y1444500D02*
Y1448500D01*
X89300D01*
G01X115100Y1419600D02*
Y1423600D01*
X107700D01*
G01X116000Y1418800D02*
X120000D01*
Y1426200D01*
G01X107700Y1427900D02*
Y1423900D01*
X115100D01*
G01X107000Y1425700D02*
X103000D01*
Y1418300D01*
G01X93600D02*
X97600D01*
Y1425700D01*
G01X89300Y1441000D02*
Y1437000D01*
X96700D01*
G01X132317Y1436792D02*
X132067Y1436917D01*
X131775Y1437000D01*
X131442D01*
X131067Y1436875D01*
X130775Y1436667D01*
X130567Y1436417D01*
X130400Y1436000D01*
X130358Y1435625D01*
X130442Y1435250D01*
X130567Y1435000D01*
X130817Y1434750D01*
X131108Y1434583D01*
X131400Y1434500D01*
X131692D01*
X131983Y1434583D01*
X132233Y1434708D01*
X132442Y1434875D01*
G01X133583D02*
X133833Y1434667D01*
X134125Y1434542D01*
X134500Y1434500D01*
X134875Y1434583D01*
X135167Y1434750D01*
X135375Y1435042D01*
X135417Y1435375D01*
X135333Y1435708D01*
X135125Y1435917D01*
X134833Y1436083D01*
X134542Y1436125D01*
X134250Y1436083D01*
X133875Y1435917D01*
X134000Y1437000D01*
X135125D01*
G01X137600Y1434500D02*
Y1437000D01*
X137100Y1436500D01*
G01Y1434500D02*
X138100D01*
G01X134000Y1505517D02*
X131500D01*
Y1506517D01*
X131625Y1506850D01*
X131917Y1507100D01*
X132250Y1507183D01*
X132583Y1507100D01*
X132833Y1506892D01*
X132958Y1506517D01*
Y1505517D01*
G01X134000Y1508617D02*
X131500D01*
Y1509658D01*
X131625Y1509992D01*
X131792Y1510200D01*
X132125Y1510283D01*
X132458Y1510200D01*
X132667Y1509950D01*
X132792Y1509658D01*
Y1508617D01*
G01Y1509658D02*
X134000Y1510283D01*
G01X131917Y1511758D02*
X131667Y1512008D01*
X131542Y1512300D01*
X131500Y1512633D01*
X131583Y1513050D01*
X131792Y1513342D01*
X132042Y1513425D01*
X132292Y1513383D01*
X132500Y1513217D01*
X132917Y1512383D01*
X133208Y1512008D01*
X133625Y1511758D01*
X134000Y1511675D01*
Y1513425D01*
G01X133500Y1514733D02*
X133792Y1514983D01*
X133958Y1515317D01*
X134000Y1515692D01*
X133958Y1516025D01*
X133750Y1516358D01*
X133500Y1516567D01*
X133250Y1516608D01*
X132958Y1516525D01*
X132750Y1516233D01*
X132667Y1515942D01*
Y1515567D01*
G01Y1515942D02*
X132542Y1516192D01*
X132333Y1516400D01*
X132083Y1516483D01*
X131833Y1516400D01*
X131625Y1516192D01*
X131500Y1515817D01*
X131542Y1515442D01*
X131708Y1515067D01*
G01X131000Y1496300D02*
X135000D01*
Y1503700D01*
G01X130000Y1505517D02*
X127500D01*
Y1506517D01*
X127625Y1506850D01*
X127917Y1507100D01*
X128250Y1507183D01*
X128583Y1507100D01*
X128833Y1506892D01*
X128958Y1506517D01*
Y1505517D01*
G01X130000Y1508617D02*
X127500D01*
Y1509658D01*
X127625Y1509992D01*
X127792Y1510200D01*
X128125Y1510283D01*
X128458Y1510200D01*
X128667Y1509950D01*
X128792Y1509658D01*
Y1508617D01*
G01Y1509658D02*
X130000Y1510283D01*
G01X127917Y1511758D02*
X127667Y1512008D01*
X127542Y1512300D01*
X127500Y1512633D01*
X127583Y1513050D01*
X127792Y1513342D01*
X128042Y1513425D01*
X128292Y1513383D01*
X128500Y1513217D01*
X128917Y1512383D01*
X129208Y1512008D01*
X129625Y1511758D01*
X130000Y1511675D01*
Y1513425D01*
G01X127917Y1514858D02*
X127667Y1515108D01*
X127542Y1515400D01*
X127500Y1515733D01*
X127583Y1516150D01*
X127792Y1516442D01*
X128042Y1516525D01*
X128292Y1516483D01*
X128500Y1516317D01*
X128917Y1515483D01*
X129208Y1515108D01*
X129625Y1514858D01*
X130000Y1514775D01*
Y1516525D01*
G01X127000Y1496300D02*
X131000D01*
Y1503700D01*
G01X126000Y1505517D02*
X123500D01*
Y1506517D01*
X123625Y1506850D01*
X123917Y1507100D01*
X124250Y1507183D01*
X124583Y1507100D01*
X124833Y1506892D01*
X124958Y1506517D01*
Y1505517D01*
G01X126000Y1508617D02*
X123500D01*
Y1509658D01*
X123625Y1509992D01*
X123792Y1510200D01*
X124125Y1510283D01*
X124458Y1510200D01*
X124667Y1509950D01*
X124792Y1509658D01*
Y1508617D01*
G01Y1509658D02*
X126000Y1510283D01*
G01X123917Y1511758D02*
X123667Y1512008D01*
X123542Y1512300D01*
X123500Y1512633D01*
X123583Y1513050D01*
X123792Y1513342D01*
X124042Y1513425D01*
X124292Y1513383D01*
X124500Y1513217D01*
X124917Y1512383D01*
X125208Y1512008D01*
X125625Y1511758D01*
X126000Y1511675D01*
Y1513425D01*
G01Y1515650D02*
X123500D01*
X124000Y1515150D01*
G01X126000D02*
Y1516150D01*
G01X123000Y1496300D02*
X127000D01*
Y1503700D01*
G01X122000Y1505517D02*
X119500D01*
Y1506517D01*
X119625Y1506850D01*
X119917Y1507100D01*
X120250Y1507183D01*
X120583Y1507100D01*
X120833Y1506892D01*
X120958Y1506517D01*
Y1505517D01*
G01X122000Y1508617D02*
X119500D01*
Y1509658D01*
X119625Y1509992D01*
X119792Y1510200D01*
X120125Y1510283D01*
X120458Y1510200D01*
X120667Y1509950D01*
X120792Y1509658D01*
Y1508617D01*
G01Y1509658D02*
X122000Y1510283D01*
G01X119917Y1511758D02*
X119667Y1512008D01*
X119542Y1512300D01*
X119500Y1512633D01*
X119583Y1513050D01*
X119792Y1513342D01*
X120042Y1513425D01*
X120292Y1513383D01*
X120500Y1513217D01*
X120917Y1512383D01*
X121208Y1512008D01*
X121625Y1511758D01*
X122000Y1511675D01*
Y1513425D01*
G01X119500Y1515650D02*
X119583Y1515317D01*
X119792Y1515067D01*
X120042Y1514900D01*
X120375Y1514775D01*
X120750Y1514733D01*
X121125Y1514775D01*
X121458Y1514900D01*
X121708Y1515067D01*
X121917Y1515317D01*
X122000Y1515650D01*
X121917Y1515983D01*
X121708Y1516233D01*
X121458Y1516400D01*
X121125Y1516525D01*
X120750Y1516567D01*
X120375Y1516525D01*
X120042Y1516400D01*
X119792Y1516233D01*
X119583Y1515983D01*
X119500Y1515650D01*
G01X119000Y1496300D02*
X123000D01*
Y1503700D01*
G01X96067Y1493000D02*
Y1495500D01*
X97067D01*
X97400Y1495375D01*
X97650Y1495083D01*
X97733Y1494750D01*
X97650Y1494417D01*
X97442Y1494167D01*
X97067Y1494042D01*
X96067D01*
G01X99167Y1493000D02*
Y1495500D01*
X100208D01*
X100542Y1495375D01*
X100750Y1495208D01*
X100833Y1494875D01*
X100750Y1494542D01*
X100500Y1494333D01*
X100208Y1494208D01*
X99167D01*
G01X100208D02*
X100833Y1493000D01*
G01X102308Y1495083D02*
X102558Y1495333D01*
X102850Y1495458D01*
X103183Y1495500D01*
X103600Y1495417D01*
X103892Y1495208D01*
X103975Y1494958D01*
X103933Y1494708D01*
X103767Y1494500D01*
X102933Y1494083D01*
X102558Y1493792D01*
X102308Y1493375D01*
X102225Y1493000D01*
X103975D01*
G01X109500Y1492200D02*
X105500D01*
Y1484800D01*
G01X118000Y1505517D02*
X115500D01*
Y1506517D01*
X115625Y1506850D01*
X115917Y1507100D01*
X116250Y1507183D01*
X116583Y1507100D01*
X116833Y1506892D01*
X116958Y1506517D01*
Y1505517D01*
G01X118000Y1508617D02*
X115500D01*
Y1509658D01*
X115625Y1509992D01*
X115792Y1510200D01*
X116125Y1510283D01*
X116458Y1510200D01*
X116667Y1509950D01*
X116792Y1509658D01*
Y1508617D01*
G01Y1509658D02*
X118000Y1510283D01*
G01Y1512550D02*
X115500D01*
X116000Y1512050D01*
G01X118000D02*
Y1513050D01*
G01X117708Y1514942D02*
X117917Y1515233D01*
X118000Y1515567D01*
X117917Y1515900D01*
X117667Y1516192D01*
X117292Y1516400D01*
X116917Y1516483D01*
X116458D01*
X116083Y1516400D01*
X115750Y1516192D01*
X115583Y1515942D01*
X115500Y1515650D01*
X115583Y1515317D01*
X115750Y1515067D01*
X116000Y1514900D01*
X116333Y1514817D01*
X116625Y1514900D01*
X116917Y1515108D01*
X117083Y1515358D01*
X117125Y1515650D01*
X117042Y1515983D01*
X116833Y1516233D01*
X116458Y1516483D01*
G01X115000Y1496300D02*
X119000D01*
Y1503700D01*
G01X114000Y1505517D02*
X111500D01*
Y1506517D01*
X111625Y1506850D01*
X111917Y1507100D01*
X112250Y1507183D01*
X112583Y1507100D01*
X112833Y1506892D01*
X112958Y1506517D01*
Y1505517D01*
G01X114000Y1508617D02*
X111500D01*
Y1509658D01*
X111625Y1509992D01*
X111792Y1510200D01*
X112125Y1510283D01*
X112458Y1510200D01*
X112667Y1509950D01*
X112792Y1509658D01*
Y1508617D01*
G01Y1509658D02*
X114000Y1510283D01*
G01Y1512550D02*
X111500D01*
X112000Y1512050D01*
G01X114000D02*
Y1513050D01*
G01Y1515650D02*
X113958Y1515942D01*
X113833Y1516275D01*
X113625Y1516483D01*
X113333Y1516567D01*
X113042Y1516483D01*
X112792Y1516233D01*
X112667Y1515858D01*
Y1515442D01*
X112583Y1515192D01*
X112375Y1514983D01*
X112083Y1514900D01*
X111792Y1515025D01*
X111583Y1515317D01*
X111500Y1515650D01*
X111583Y1515983D01*
X111792Y1516275D01*
X112083Y1516400D01*
X112375Y1516317D01*
X112583Y1516108D01*
X112667Y1515858D01*
Y1515442D01*
X112792Y1515067D01*
X113042Y1514817D01*
X113333Y1514733D01*
X113625Y1514817D01*
X113833Y1515025D01*
X113958Y1515358D01*
X114000Y1515650D01*
G01X111000Y1496300D02*
X115000D01*
Y1503700D01*
G01X110000Y1505517D02*
X107500D01*
Y1506517D01*
X107625Y1506850D01*
X107917Y1507100D01*
X108250Y1507183D01*
X108583Y1507100D01*
X108833Y1506892D01*
X108958Y1506517D01*
Y1505517D01*
G01X110000Y1508617D02*
X107500D01*
Y1509658D01*
X107625Y1509992D01*
X107792Y1510200D01*
X108125Y1510283D01*
X108458Y1510200D01*
X108667Y1509950D01*
X108792Y1509658D01*
Y1508617D01*
G01Y1509658D02*
X110000Y1510283D01*
G01Y1512550D02*
X107500D01*
X108000Y1512050D01*
G01X110000D02*
Y1513050D01*
G01Y1515567D02*
X109458Y1515650D01*
X109000Y1515775D01*
X108583Y1515942D01*
X108125Y1516150D01*
X107500Y1516483D01*
Y1514817D01*
G01X107000Y1496300D02*
X111000D01*
Y1503700D01*
G01X125500Y1473067D02*
X123000D01*
Y1474067D01*
X123125Y1474400D01*
X123417Y1474650D01*
X123750Y1474733D01*
X124083Y1474650D01*
X124333Y1474442D01*
X124458Y1474067D01*
Y1473067D01*
G01X125500Y1476083D02*
X123000D01*
Y1476917D01*
X123125Y1477250D01*
X123292Y1477500D01*
X123542Y1477708D01*
X123833Y1477875D01*
X124250Y1477917D01*
X124667Y1477875D01*
X124958Y1477708D01*
X125208Y1477500D01*
X125375Y1477250D01*
X125500Y1476917D01*
Y1476083D01*
G01Y1480100D02*
X123000D01*
X123500Y1479600D01*
G01X125500D02*
Y1480600D01*
G01X121500Y1473067D02*
X119000D01*
Y1474067D01*
X119125Y1474400D01*
X119417Y1474650D01*
X119750Y1474733D01*
X120083Y1474650D01*
X120333Y1474442D01*
X120458Y1474067D01*
Y1473067D01*
G01X119208Y1477917D02*
X119083Y1477667D01*
X119000Y1477375D01*
Y1477042D01*
X119125Y1476667D01*
X119333Y1476375D01*
X119583Y1476167D01*
X120000Y1476000D01*
X120375Y1475958D01*
X120750Y1476042D01*
X121000Y1476167D01*
X121250Y1476417D01*
X121417Y1476708D01*
X121500Y1477000D01*
Y1477292D01*
X121417Y1477583D01*
X121292Y1477833D01*
X121125Y1478042D01*
G01X120458Y1479308D02*
X120167Y1479600D01*
X120000Y1479850D01*
X119917Y1480183D01*
X120000Y1480475D01*
X120167Y1480683D01*
X120417Y1480850D01*
X120708Y1480892D01*
X120958Y1480850D01*
X121208Y1480683D01*
X121417Y1480433D01*
X121500Y1480142D01*
X121417Y1479808D01*
X121167Y1479517D01*
X120792Y1479350D01*
X120375Y1479308D01*
X119833Y1479392D01*
X119542Y1479517D01*
X119250Y1479725D01*
X119042Y1480017D01*
X119000Y1480308D01*
X119083Y1480600D01*
X119292Y1480808D01*
G01X87900Y1519100D02*
Y1530300D01*
G01Y1503100D02*
Y1491900D01*
G01X96067Y1485000D02*
Y1487500D01*
X97067D01*
X97400Y1487375D01*
X97650Y1487083D01*
X97733Y1486750D01*
X97650Y1486417D01*
X97442Y1486167D01*
X97067Y1486042D01*
X96067D01*
G01X100917Y1487292D02*
X100667Y1487417D01*
X100375Y1487500D01*
X100042D01*
X99667Y1487375D01*
X99375Y1487167D01*
X99167Y1486917D01*
X99000Y1486500D01*
X98958Y1486125D01*
X99042Y1485750D01*
X99167Y1485500D01*
X99417Y1485250D01*
X99708Y1485083D01*
X100000Y1485000D01*
X100292D01*
X100583Y1485083D01*
X100833Y1485208D01*
X101042Y1485375D01*
G01X103100Y1485000D02*
Y1487500D01*
X102600Y1487000D01*
G01Y1485000D02*
X103600D01*
G01X94300Y1482817D02*
X91800D01*
Y1483817D01*
X91925Y1484150D01*
X92217Y1484400D01*
X92550Y1484483D01*
X92883Y1484400D01*
X93133Y1484192D01*
X93258Y1483817D01*
Y1482817D01*
G01X94300Y1485917D02*
X91800D01*
Y1486958D01*
X91925Y1487292D01*
X92092Y1487500D01*
X92425Y1487583D01*
X92758Y1487500D01*
X92967Y1487250D01*
X93092Y1486958D01*
Y1485917D01*
G01Y1486958D02*
X94300Y1487583D01*
G01X93800Y1488933D02*
X94092Y1489183D01*
X94258Y1489517D01*
X94300Y1489892D01*
X94258Y1490225D01*
X94050Y1490558D01*
X93800Y1490767D01*
X93550Y1490808D01*
X93258Y1490725D01*
X93050Y1490433D01*
X92967Y1490142D01*
Y1489767D01*
G01Y1490142D02*
X92842Y1490392D01*
X92633Y1490600D01*
X92383Y1490683D01*
X92133Y1490600D01*
X91925Y1490392D01*
X91800Y1490017D01*
X91842Y1489642D01*
X92008Y1489267D01*
G01X94300Y1492867D02*
X93758Y1492950D01*
X93300Y1493075D01*
X92883Y1493242D01*
X92425Y1493450D01*
X91800Y1493783D01*
Y1492117D01*
G01X91500Y1473800D02*
X95500D01*
Y1481200D01*
G01X82300Y1486000D02*
Y1482000D01*
X89700D01*
G01X114517Y1487000D02*
Y1489500D01*
X115517D01*
X115850Y1489375D01*
X116100Y1489083D01*
X116183Y1488750D01*
X116100Y1488417D01*
X115892Y1488167D01*
X115517Y1488042D01*
X114517D01*
G01X117617Y1487000D02*
Y1489500D01*
X118658D01*
X118992Y1489375D01*
X119200Y1489208D01*
X119283Y1488875D01*
X119200Y1488542D01*
X118950Y1488333D01*
X118658Y1488208D01*
X117617D01*
G01X118658D02*
X119283Y1487000D01*
G01X121550D02*
Y1489500D01*
X121050Y1489000D01*
G01Y1487000D02*
X122050D01*
G01X125150D02*
Y1489500D01*
X123608Y1487708D01*
X125692D01*
G01X126800Y1484000D02*
Y1480000D01*
X134200D01*
G01X96067Y1489000D02*
Y1491500D01*
X97067D01*
X97400Y1491375D01*
X97650Y1491083D01*
X97733Y1490750D01*
X97650Y1490417D01*
X97442Y1490167D01*
X97067Y1490042D01*
X96067D01*
G01X100917Y1491292D02*
X100667Y1491417D01*
X100375Y1491500D01*
X100042D01*
X99667Y1491375D01*
X99375Y1491167D01*
X99167Y1490917D01*
X99000Y1490500D01*
X98958Y1490125D01*
X99042Y1489750D01*
X99167Y1489500D01*
X99417Y1489250D01*
X99708Y1489083D01*
X100000Y1489000D01*
X100292D01*
X100583Y1489083D01*
X100833Y1489208D01*
X101042Y1489375D01*
G01X102308Y1491083D02*
X102558Y1491333D01*
X102850Y1491458D01*
X103183Y1491500D01*
X103600Y1491417D01*
X103892Y1491208D01*
X103975Y1490958D01*
X103933Y1490708D01*
X103767Y1490500D01*
X102933Y1490083D01*
X102558Y1489792D01*
X102308Y1489375D01*
X102225Y1489000D01*
X103975D01*
G01X117300Y1473317D02*
X114800D01*
Y1474317D01*
X114925Y1474650D01*
X115217Y1474900D01*
X115550Y1474983D01*
X115883Y1474900D01*
X116133Y1474692D01*
X116258Y1474317D01*
Y1473317D01*
G01X117300Y1476417D02*
X114800D01*
Y1477458D01*
X114925Y1477792D01*
X115092Y1478000D01*
X115425Y1478083D01*
X115758Y1478000D01*
X115967Y1477750D01*
X116092Y1477458D01*
Y1476417D01*
G01Y1477458D02*
X117300Y1478083D01*
G01Y1480350D02*
X114800D01*
X115300Y1479850D01*
G01X117300D02*
Y1480850D01*
G01X114800Y1483450D02*
X114883Y1483117D01*
X115092Y1482867D01*
X115342Y1482700D01*
X115675Y1482575D01*
X116050Y1482533D01*
X116425Y1482575D01*
X116758Y1482700D01*
X117008Y1482867D01*
X117217Y1483117D01*
X117300Y1483450D01*
X117217Y1483783D01*
X117008Y1484033D01*
X116758Y1484200D01*
X116425Y1484325D01*
X116050Y1484367D01*
X115675Y1484325D01*
X115342Y1484200D01*
X115092Y1484033D01*
X114883Y1483783D01*
X114800Y1483450D01*
G01X127000Y1471800D02*
X131000D01*
Y1479200D01*
G01X146850Y1601300D02*
X125150D01*
G01Y1571300D02*
X146850D01*
G01X125150Y1601300D02*
Y1571300D01*
G01X98467Y1604100D02*
Y1606600D01*
X99467D01*
X99800Y1606475D01*
X100050Y1606183D01*
X100133Y1605850D01*
X100050Y1605517D01*
X99842Y1605267D01*
X99467Y1605142D01*
X98467D01*
G01X102400Y1604100D02*
X102067Y1604142D01*
X101775Y1604308D01*
X101525Y1604558D01*
X101358Y1604850D01*
X101275Y1605183D01*
Y1605517D01*
X101358Y1605850D01*
X101525Y1606142D01*
X101775Y1606392D01*
X102067Y1606558D01*
X102400Y1606600D01*
X102733Y1606558D01*
X103025Y1606392D01*
X103275Y1606142D01*
X103442Y1605850D01*
X103525Y1605517D01*
Y1605183D01*
X103442Y1604850D01*
X103275Y1604558D01*
X103025Y1604308D01*
X102733Y1604142D01*
X102400Y1604100D01*
G01X102733Y1604767D02*
X103233Y1604100D01*
G01X105500D02*
Y1606600D01*
X105000Y1606100D01*
G01Y1604100D02*
X106000D01*
G01X111850Y1601300D02*
X90150D01*
G01X111850Y1571300D02*
Y1601300D01*
G01X90150Y1571300D02*
X111850D01*
G01X90150Y1601300D02*
Y1571300D01*
G01X85500Y1611017D02*
X83000D01*
Y1612017D01*
X83125Y1612350D01*
X83417Y1612600D01*
X83750Y1612683D01*
X84083Y1612600D01*
X84333Y1612392D01*
X84458Y1612017D01*
Y1611017D01*
G01X85500Y1614117D02*
X83000D01*
Y1615158D01*
X83125Y1615492D01*
X83292Y1615700D01*
X83625Y1615783D01*
X83958Y1615700D01*
X84167Y1615450D01*
X84292Y1615158D01*
Y1614117D01*
G01Y1615158D02*
X85500Y1615783D01*
G01X83417Y1617258D02*
X83167Y1617508D01*
X83042Y1617800D01*
X83000Y1618133D01*
X83083Y1618550D01*
X83292Y1618842D01*
X83542Y1618925D01*
X83792Y1618883D01*
X84000Y1618717D01*
X84417Y1617883D01*
X84708Y1617508D01*
X85125Y1617258D01*
X85500Y1617175D01*
Y1618925D01*
G01X85208Y1620442D02*
X85417Y1620733D01*
X85500Y1621067D01*
X85417Y1621400D01*
X85167Y1621692D01*
X84792Y1621900D01*
X84417Y1621983D01*
X83958D01*
X83583Y1621900D01*
X83250Y1621692D01*
X83083Y1621442D01*
X83000Y1621150D01*
X83083Y1620817D01*
X83250Y1620567D01*
X83500Y1620400D01*
X83833Y1620317D01*
X84125Y1620400D01*
X84417Y1620608D01*
X84583Y1620858D01*
X84625Y1621150D01*
X84542Y1621483D01*
X84333Y1621733D01*
X83958Y1621983D01*
G01X116000Y1611517D02*
X113500D01*
Y1612517D01*
X113625Y1612850D01*
X113917Y1613100D01*
X114250Y1613183D01*
X114583Y1613100D01*
X114833Y1612892D01*
X114958Y1612517D01*
Y1611517D01*
G01X116000Y1614617D02*
X113500D01*
Y1615658D01*
X113625Y1615992D01*
X113792Y1616200D01*
X114125Y1616283D01*
X114458Y1616200D01*
X114667Y1615950D01*
X114792Y1615658D01*
Y1614617D01*
G01Y1615658D02*
X116000Y1616283D01*
G01X115500Y1617633D02*
X115792Y1617883D01*
X115958Y1618217D01*
X116000Y1618592D01*
X115958Y1618925D01*
X115750Y1619258D01*
X115500Y1619467D01*
X115250Y1619508D01*
X114958Y1619425D01*
X114750Y1619133D01*
X114667Y1618842D01*
Y1618467D01*
G01Y1618842D02*
X114542Y1619092D01*
X114333Y1619300D01*
X114083Y1619383D01*
X113833Y1619300D01*
X113625Y1619092D01*
X113500Y1618717D01*
X113542Y1618342D01*
X113708Y1617967D01*
G01X113500Y1621650D02*
X113583Y1621317D01*
X113792Y1621067D01*
X114042Y1620900D01*
X114375Y1620775D01*
X114750Y1620733D01*
X115125Y1620775D01*
X115458Y1620900D01*
X115708Y1621067D01*
X115917Y1621317D01*
X116000Y1621650D01*
X115917Y1621983D01*
X115708Y1622233D01*
X115458Y1622400D01*
X115125Y1622525D01*
X114750Y1622567D01*
X114375Y1622525D01*
X114042Y1622400D01*
X113792Y1622233D01*
X113583Y1621983D01*
X113500Y1621650D01*
G01X96250Y1610000D02*
Y1623000D01*
X111750D01*
Y1610000D01*
X96250D01*
G01X124750D02*
Y1623000D01*
X140250D01*
Y1610000D01*
X124750D01*
G01X128208Y1763817D02*
X128083Y1763567D01*
X128000Y1763275D01*
Y1762942D01*
X128125Y1762567D01*
X128333Y1762275D01*
X128583Y1762067D01*
X129000Y1761900D01*
X129375Y1761858D01*
X129750Y1761942D01*
X130000Y1762067D01*
X130250Y1762317D01*
X130417Y1762608D01*
X130500Y1762900D01*
Y1763192D01*
X130417Y1763483D01*
X130292Y1763733D01*
X130125Y1763942D01*
G01X130500Y1765042D02*
X128000D01*
X130500Y1766958D01*
X128000D01*
G01X130500Y1769100D02*
X130458Y1769392D01*
X130333Y1769725D01*
X130125Y1769933D01*
X129833Y1770017D01*
X129542Y1769933D01*
X129292Y1769683D01*
X129167Y1769308D01*
Y1768892D01*
X129083Y1768642D01*
X128875Y1768433D01*
X128583Y1768350D01*
X128292Y1768475D01*
X128083Y1768767D01*
X128000Y1769100D01*
X128083Y1769433D01*
X128292Y1769725D01*
X128583Y1769850D01*
X128875Y1769767D01*
X129083Y1769558D01*
X129167Y1769308D01*
Y1768892D01*
X129292Y1768517D01*
X129542Y1768267D01*
X129833Y1768183D01*
X130125Y1768267D01*
X130333Y1768475D01*
X130458Y1768808D01*
X130500Y1769100D01*
G01X144937Y1784819D02*
X112937D01*
Y1772819D01*
X144937D01*
Y1784819D01*
G01X86997Y1877198D02*
Y1915998D01*
G01X109997Y1877198D02*
X86997D01*
G01X109997Y1915998D02*
Y1877198D01*
G01X119850Y1874000D02*
Y1871500D01*
G01X118892Y1874000D02*
X120808D01*
G01X123867Y1873792D02*
X123617Y1873917D01*
X123325Y1874000D01*
X122992D01*
X122617Y1873875D01*
X122325Y1873667D01*
X122117Y1873417D01*
X121950Y1873000D01*
X121908Y1872625D01*
X121992Y1872250D01*
X122117Y1872000D01*
X122367Y1871750D01*
X122658Y1871583D01*
X122950Y1871500D01*
X123242D01*
X123533Y1871583D01*
X123783Y1871708D01*
X123992Y1871875D01*
G01X126050Y1871500D02*
Y1874000D01*
X125550Y1873500D01*
G01Y1871500D02*
X126550D01*
G01X129150D02*
X129442Y1871542D01*
X129775Y1871667D01*
X129983Y1871875D01*
X130067Y1872167D01*
X129983Y1872458D01*
X129733Y1872708D01*
X129358Y1872833D01*
X128942D01*
X128692Y1872917D01*
X128483Y1873125D01*
X128400Y1873417D01*
X128525Y1873708D01*
X128817Y1873917D01*
X129150Y1874000D01*
X129483Y1873917D01*
X129775Y1873708D01*
X129900Y1873417D01*
X129817Y1873125D01*
X129608Y1872917D01*
X129358Y1872833D01*
X128942D01*
X128567Y1872708D01*
X128317Y1872458D01*
X128233Y1872167D01*
X128317Y1871875D01*
X128525Y1871667D01*
X128858Y1871542D01*
X129150Y1871500D01*
G01X115298Y1876703D02*
X133298D01*
G01X115298Y1887903D02*
Y1876703D01*
G01X91517Y1861000D02*
Y1863500D01*
X92517D01*
X92850Y1863375D01*
X93100Y1863083D01*
X93183Y1862750D01*
X93100Y1862417D01*
X92892Y1862167D01*
X92517Y1862042D01*
X91517D01*
G01X94408Y1861000D02*
X95450Y1863500D01*
X96492Y1861000D01*
G01X96117Y1861875D02*
X94783D01*
G01X97633Y1861000D02*
Y1863500D01*
X98467D01*
X98800Y1863375D01*
X99050Y1863208D01*
X99258Y1862958D01*
X99425Y1862667D01*
X99467Y1862250D01*
X99425Y1861833D01*
X99258Y1861542D01*
X99050Y1861292D01*
X98800Y1861125D01*
X98467Y1861000D01*
X97633D01*
G01X101650D02*
Y1863500D01*
X101150Y1863000D01*
G01Y1861000D02*
X102150D01*
G01X86997Y1915998D02*
X109997D01*
G01X115298Y1915103D02*
X133298D01*
G01X115298Y1903903D02*
Y1915103D01*
G01X84100Y1887100D02*
Y1904700D01*
G01X147000Y85850D02*
X149500D01*
G01X147000Y84892D02*
Y86808D01*
G01X147208Y89867D02*
X147083Y89617D01*
X147000Y89325D01*
Y88992D01*
X147125Y88617D01*
X147333Y88325D01*
X147583Y88117D01*
X148000Y87950D01*
X148375Y87908D01*
X148750Y87992D01*
X149000Y88117D01*
X149250Y88367D01*
X149417Y88658D01*
X149500Y88950D01*
Y89242D01*
X149417Y89533D01*
X149292Y89783D01*
X149125Y89992D01*
G01X149500Y92050D02*
X147000D01*
X147500Y91550D01*
G01X149500D02*
Y92550D01*
G01X149000Y94233D02*
X149292Y94483D01*
X149458Y94817D01*
X149500Y95192D01*
X149458Y95525D01*
X149250Y95858D01*
X149000Y96067D01*
X148750Y96108D01*
X148458Y96025D01*
X148250Y95733D01*
X148167Y95442D01*
Y95067D01*
G01Y95442D02*
X148042Y95692D01*
X147833Y95900D01*
X147583Y95983D01*
X147333Y95900D01*
X147125Y95692D01*
X147000Y95317D01*
X147042Y94942D01*
X147208Y94567D01*
G01X144700Y79500D02*
X133500D01*
G01X144700Y97500D02*
Y79500D01*
G01X133500Y97500D02*
X144700D01*
G01X134906Y340409D02*
X164306D01*
Y311909D01*
X194306D01*
Y136909D01*
X164306D01*
Y108409D01*
X134906D01*
Y340409D01*
G01X176709Y98740D02*
Y101240D01*
G01X178459D02*
Y98740D01*
G01Y99990D02*
X176709D01*
G01X180684Y98740D02*
Y101240D01*
X180184Y100740D01*
G01Y98740D02*
X181184D01*
G01X135893Y345292D02*
X135643Y345417D01*
X135351Y345500D01*
X135018D01*
X134643Y345375D01*
X134351Y345167D01*
X134143Y344917D01*
X133976Y344500D01*
X133934Y344125D01*
X134018Y343750D01*
X134143Y343500D01*
X134393Y343250D01*
X134684Y343083D01*
X134976Y343000D01*
X135268D01*
X135559Y343083D01*
X135809Y343208D01*
X136018Y343375D01*
G01X137118Y343000D02*
Y345500D01*
X139034Y343000D01*
Y345500D01*
G01X141176Y343000D02*
Y345500D01*
X140676Y345000D01*
G01Y343000D02*
X141676D01*
G01X144276Y345500D02*
X143943Y345417D01*
X143693Y345208D01*
X143526Y344958D01*
X143401Y344625D01*
X143359Y344250D01*
X143401Y343875D01*
X143526Y343542D01*
X143693Y343292D01*
X143943Y343083D01*
X144276Y343000D01*
X144609Y343083D01*
X144859Y343292D01*
X145026Y343542D01*
X145151Y343875D01*
X145193Y344250D01*
X145151Y344625D01*
X145026Y344958D01*
X144859Y345208D01*
X144609Y345417D01*
X144276Y345500D01*
G01X153700Y388900D02*
X164900D01*
G01X153700Y406900D02*
Y388900D01*
G01X192100D02*
X180900D01*
G01X149000Y353400D02*
X151500D01*
G01X149000Y352442D02*
Y354358D01*
G01X149208Y357417D02*
X149083Y357167D01*
X149000Y356875D01*
Y356542D01*
X149125Y356167D01*
X149333Y355875D01*
X149583Y355667D01*
X150000Y355500D01*
X150375Y355458D01*
X150750Y355542D01*
X151000Y355667D01*
X151250Y355917D01*
X151417Y356208D01*
X151500Y356500D01*
Y356792D01*
X151417Y357083D01*
X151292Y357333D01*
X151125Y357542D01*
G01X150458Y358808D02*
X150167Y359100D01*
X150000Y359350D01*
X149917Y359683D01*
X150000Y359975D01*
X150167Y360183D01*
X150417Y360350D01*
X150708Y360392D01*
X150958Y360350D01*
X151208Y360183D01*
X151417Y359933D01*
X151500Y359642D01*
X151417Y359308D01*
X151167Y359017D01*
X150792Y358850D01*
X150375Y358808D01*
X149833Y358892D01*
X149542Y359017D01*
X149250Y359225D01*
X149042Y359517D01*
X149000Y359808D01*
X149083Y360100D01*
X149292Y360308D01*
G01X153600Y347700D02*
X164800D01*
G01X153600Y365700D02*
Y347700D01*
G01X164800Y365700D02*
X153600D01*
G01X192000Y347700D02*
X180800D01*
G01Y365700D02*
X192000D01*
G01X149000Y373800D02*
X151500D01*
G01X149000Y372842D02*
Y374758D01*
G01X149208Y377817D02*
X149083Y377567D01*
X149000Y377275D01*
Y376942D01*
X149125Y376567D01*
X149333Y376275D01*
X149583Y376067D01*
X150000Y375900D01*
X150375Y375858D01*
X150750Y375942D01*
X151000Y376067D01*
X151250Y376317D01*
X151417Y376608D01*
X151500Y376900D01*
Y377192D01*
X151417Y377483D01*
X151292Y377733D01*
X151125Y377942D01*
G01Y379083D02*
X151333Y379333D01*
X151458Y379625D01*
X151500Y380000D01*
X151417Y380375D01*
X151250Y380667D01*
X150958Y380875D01*
X150625Y380917D01*
X150292Y380833D01*
X150083Y380625D01*
X149917Y380333D01*
X149875Y380042D01*
X149917Y379750D01*
X150083Y379375D01*
X149000Y379500D01*
Y380625D01*
G01X153800Y367900D02*
X165000D01*
G01X153800Y385900D02*
Y367900D01*
G01X165000Y385900D02*
X153800D01*
G01X192200Y367900D02*
X181000D01*
G01Y385900D02*
X192200D01*
G01X145700Y374300D02*
Y349300D01*
G01X133967Y425100D02*
Y427600D01*
X134967D01*
X135300Y427475D01*
X135550Y427183D01*
X135633Y426850D01*
X135550Y426517D01*
X135342Y426267D01*
X134967Y426142D01*
X133967D01*
G01X137067Y425100D02*
Y427600D01*
X138108D01*
X138442Y427475D01*
X138650Y427308D01*
X138733Y426975D01*
X138650Y426642D01*
X138400Y426433D01*
X138108Y426308D01*
X137067D01*
G01X138108D02*
X138733Y425100D01*
G01X141000D02*
Y427600D01*
X140500Y427100D01*
G01Y425100D02*
X141500D01*
G01X144100Y427600D02*
X143767Y427517D01*
X143517Y427308D01*
X143350Y427058D01*
X143225Y426725D01*
X143183Y426350D01*
X143225Y425975D01*
X143350Y425642D01*
X143517Y425392D01*
X143767Y425183D01*
X144100Y425100D01*
X144433Y425183D01*
X144683Y425392D01*
X144850Y425642D01*
X144975Y425975D01*
X145017Y426350D01*
X144975Y426725D01*
X144850Y427058D01*
X144683Y427308D01*
X144433Y427517D01*
X144100Y427600D01*
G01X146283Y425600D02*
X146533Y425308D01*
X146867Y425142D01*
X147242Y425100D01*
X147575Y425142D01*
X147908Y425350D01*
X148117Y425600D01*
X148158Y425850D01*
X148075Y426142D01*
X147783Y426350D01*
X147492Y426433D01*
X147117D01*
G01X147492D02*
X147742Y426558D01*
X147950Y426767D01*
X148033Y427017D01*
X147950Y427267D01*
X147742Y427475D01*
X147367Y427600D01*
X146992Y427558D01*
X146617Y427392D01*
G01X155500Y428800D02*
Y432800D01*
X148100D01*
G01X159350Y435300D02*
Y465300D01*
G01X137650Y435300D02*
X159350D01*
G01X137650Y465300D02*
Y435300D01*
G01X165650D02*
X187350D01*
G01X165650Y465300D02*
Y435300D01*
G01X143800Y401900D02*
Y399400D01*
G01X142842Y401900D02*
X144758D01*
G01X147817Y401692D02*
X147567Y401817D01*
X147275Y401900D01*
X146942D01*
X146567Y401775D01*
X146275Y401567D01*
X146067Y401317D01*
X145900Y400900D01*
X145858Y400525D01*
X145942Y400150D01*
X146067Y399900D01*
X146317Y399650D01*
X146608Y399483D01*
X146900Y399400D01*
X147192D01*
X147483Y399483D01*
X147733Y399608D01*
X147942Y399775D01*
G01X150000Y399400D02*
X150292Y399442D01*
X150625Y399567D01*
X150833Y399775D01*
X150917Y400067D01*
X150833Y400358D01*
X150583Y400608D01*
X150208Y400733D01*
X149792D01*
X149542Y400817D01*
X149333Y401025D01*
X149250Y401317D01*
X149375Y401608D01*
X149667Y401817D01*
X150000Y401900D01*
X150333Y401817D01*
X150625Y401608D01*
X150750Y401317D01*
X150667Y401025D01*
X150458Y400817D01*
X150208Y400733D01*
X149792D01*
X149417Y400608D01*
X149167Y400358D01*
X149083Y400067D01*
X149167Y399775D01*
X149375Y399567D01*
X149708Y399442D01*
X150000Y399400D01*
G01X164900Y406900D02*
X153700D01*
G01X180900D02*
X192100D01*
G01X144800Y420900D02*
Y418400D01*
G01X143842Y420900D02*
X145758D01*
G01X148817Y420692D02*
X148567Y420817D01*
X148275Y420900D01*
X147942D01*
X147567Y420775D01*
X147275Y420567D01*
X147067Y420317D01*
X146900Y419900D01*
X146858Y419525D01*
X146942Y419150D01*
X147067Y418900D01*
X147317Y418650D01*
X147608Y418483D01*
X147900Y418400D01*
X148192D01*
X148483Y418483D01*
X148733Y418608D01*
X148942Y418775D01*
G01X150917Y418400D02*
X151000Y418942D01*
X151125Y419400D01*
X151292Y419817D01*
X151500Y420275D01*
X151833Y420900D01*
X150167D01*
G01X153700Y409400D02*
X164900D01*
G01X153700Y427400D02*
Y409400D01*
G01X164900Y427400D02*
X153700D01*
G01X192100Y409400D02*
X180900D01*
G01Y427400D02*
X192100D01*
G01X159350Y465300D02*
X137650D01*
G01X187350D02*
X165650D01*
G01X143908Y491467D02*
X143783Y491217D01*
X143700Y490925D01*
Y490592D01*
X143825Y490217D01*
X144033Y489925D01*
X144283Y489717D01*
X144700Y489550D01*
X145075Y489508D01*
X145450Y489592D01*
X145700Y489717D01*
X145950Y489967D01*
X146117Y490258D01*
X146200Y490550D01*
Y490842D01*
X146117Y491133D01*
X145992Y491383D01*
X145825Y491592D01*
G01X144117Y492858D02*
X143867Y493108D01*
X143742Y493400D01*
X143700Y493733D01*
X143783Y494150D01*
X143992Y494442D01*
X144242Y494525D01*
X144492Y494483D01*
X144700Y494317D01*
X145117Y493483D01*
X145408Y493108D01*
X145825Y492858D01*
X146200Y492775D01*
Y494525D01*
G01X145825Y495833D02*
X146033Y496083D01*
X146158Y496375D01*
X146200Y496750D01*
X146117Y497125D01*
X145950Y497417D01*
X145658Y497625D01*
X145325Y497667D01*
X144992Y497583D01*
X144783Y497375D01*
X144617Y497083D01*
X144575Y496792D01*
X144617Y496500D01*
X144783Y496125D01*
X143700Y496250D01*
Y497375D01*
G01X146200Y499767D02*
X145658Y499850D01*
X145200Y499975D01*
X144783Y500142D01*
X144325Y500350D01*
X143700Y500683D01*
Y499017D01*
G01X168250Y497000D02*
X183750D01*
Y467000D01*
X168250D01*
Y497000D01*
G01X150250D02*
X165750D01*
Y467000D01*
X150250D01*
Y497000D01*
G01X140067Y532000D02*
Y534500D01*
X141067D01*
X141400Y534375D01*
X141650Y534083D01*
X141733Y533750D01*
X141650Y533417D01*
X141442Y533167D01*
X141067Y533042D01*
X140067D01*
G01X143083Y534500D02*
Y532708D01*
X143250Y532333D01*
X143583Y532083D01*
X144000Y532000D01*
X144417Y532083D01*
X144750Y532333D01*
X144917Y532708D01*
Y534500D01*
G01X147017Y532000D02*
X147100Y532542D01*
X147225Y533000D01*
X147392Y533417D01*
X147600Y533875D01*
X147933Y534500D01*
X146267D01*
G01X157100Y555100D02*
Y547100D01*
X144700D01*
Y555100D01*
X157100D01*
G01X159067Y518600D02*
Y521100D01*
X160067D01*
X160400Y520975D01*
X160650Y520683D01*
X160733Y520350D01*
X160650Y520017D01*
X160442Y519767D01*
X160067Y519642D01*
X159067D01*
G01X162167Y518600D02*
Y521100D01*
X163208D01*
X163542Y520975D01*
X163750Y520808D01*
X163833Y520475D01*
X163750Y520142D01*
X163500Y519933D01*
X163208Y519808D01*
X162167D01*
G01X163208D02*
X163833Y518600D01*
G01X166100D02*
Y521100D01*
X165600Y520600D01*
G01Y518600D02*
X166600D01*
G01X169200Y521100D02*
X168867Y521017D01*
X168617Y520808D01*
X168450Y520558D01*
X168325Y520225D01*
X168283Y519850D01*
X168325Y519475D01*
X168450Y519142D01*
X168617Y518892D01*
X168867Y518683D01*
X169200Y518600D01*
X169533Y518683D01*
X169783Y518892D01*
X169950Y519142D01*
X170075Y519475D01*
X170117Y519850D01*
X170075Y520225D01*
X169950Y520558D01*
X169783Y520808D01*
X169533Y521017D01*
X169200Y521100D01*
G01X172300Y518600D02*
Y521100D01*
X171800Y520600D01*
G01Y518600D02*
X172800D01*
G01X157900Y547600D02*
Y543600D01*
X165300D01*
G01X158967Y514500D02*
Y517000D01*
X159967D01*
X160300Y516875D01*
X160550Y516583D01*
X160633Y516250D01*
X160550Y515917D01*
X160342Y515667D01*
X159967Y515542D01*
X158967D01*
G01X162067Y514500D02*
Y517000D01*
X163108D01*
X163442Y516875D01*
X163650Y516708D01*
X163733Y516375D01*
X163650Y516042D01*
X163400Y515833D01*
X163108Y515708D01*
X162067D01*
G01X163108D02*
X163733Y514500D01*
G01X166000D02*
Y517000D01*
X165500Y516500D01*
G01Y514500D02*
X166500D01*
G01X169100Y517000D02*
X168767Y516917D01*
X168517Y516708D01*
X168350Y516458D01*
X168225Y516125D01*
X168183Y515750D01*
X168225Y515375D01*
X168350Y515042D01*
X168517Y514792D01*
X168767Y514583D01*
X169100Y514500D01*
X169433Y514583D01*
X169683Y514792D01*
X169850Y515042D01*
X169975Y515375D01*
X170017Y515750D01*
X169975Y516125D01*
X169850Y516458D01*
X169683Y516708D01*
X169433Y516917D01*
X169100Y517000D01*
G01X172200D02*
X171867Y516917D01*
X171617Y516708D01*
X171450Y516458D01*
X171325Y516125D01*
X171283Y515750D01*
X171325Y515375D01*
X171450Y515042D01*
X171617Y514792D01*
X171867Y514583D01*
X172200Y514500D01*
X172533Y514583D01*
X172783Y514792D01*
X172950Y515042D01*
X173075Y515375D01*
X173117Y515750D01*
X173075Y516125D01*
X172950Y516458D01*
X172783Y516708D01*
X172533Y516917D01*
X172200Y517000D01*
G01X182967Y548000D02*
Y550500D01*
X183967D01*
X184300Y550375D01*
X184550Y550083D01*
X184633Y549750D01*
X184550Y549417D01*
X184342Y549167D01*
X183967Y549042D01*
X182967D01*
G01X186067Y548000D02*
Y550500D01*
X187108D01*
X187442Y550375D01*
X187650Y550208D01*
X187733Y549875D01*
X187650Y549542D01*
X187400Y549333D01*
X187108Y549208D01*
X186067D01*
G01X187108D02*
X187733Y548000D01*
G01X190000D02*
Y550500D01*
X189500Y550000D01*
G01Y548000D02*
X190500D01*
G01X193100D02*
Y550500D01*
X192600Y550000D01*
G01Y548000D02*
X193600D01*
G01X196200D02*
Y550500D01*
X195700Y550000D01*
G01Y548000D02*
X196700D01*
G01X134779Y537671D02*
X138779D01*
Y545071D01*
G01X179500Y520017D02*
X177000D01*
Y521017D01*
X177125Y521350D01*
X177417Y521600D01*
X177750Y521683D01*
X178083Y521600D01*
X178333Y521392D01*
X178458Y521017D01*
Y520017D01*
G01X179500Y523117D02*
X177000D01*
Y524158D01*
X177125Y524492D01*
X177292Y524700D01*
X177625Y524783D01*
X177958Y524700D01*
X178167Y524450D01*
X178292Y524158D01*
Y523117D01*
G01Y524158D02*
X179500Y524783D01*
G01X179208Y526342D02*
X179417Y526633D01*
X179500Y526967D01*
X179417Y527300D01*
X179167Y527592D01*
X178792Y527800D01*
X178417Y527883D01*
X177958D01*
X177583Y527800D01*
X177250Y527592D01*
X177083Y527342D01*
X177000Y527050D01*
X177083Y526717D01*
X177250Y526467D01*
X177500Y526300D01*
X177833Y526217D01*
X178125Y526300D01*
X178417Y526508D01*
X178583Y526758D01*
X178625Y527050D01*
X178542Y527383D01*
X178333Y527633D01*
X177958Y527883D01*
G01X178458Y529358D02*
X178167Y529650D01*
X178000Y529900D01*
X177917Y530233D01*
X178000Y530525D01*
X178167Y530733D01*
X178417Y530900D01*
X178708Y530942D01*
X178958Y530900D01*
X179208Y530733D01*
X179417Y530483D01*
X179500Y530192D01*
X179417Y529858D01*
X179167Y529567D01*
X178792Y529400D01*
X178375Y529358D01*
X177833Y529442D01*
X177542Y529567D01*
X177250Y529775D01*
X177042Y530067D01*
X177000Y530358D01*
X177083Y530650D01*
X177292Y530858D01*
G01X172600Y534500D02*
X168600D01*
Y527100D01*
G01X155500Y514017D02*
X153000D01*
Y515017D01*
X153125Y515350D01*
X153417Y515600D01*
X153750Y515683D01*
X154083Y515600D01*
X154333Y515392D01*
X154458Y515017D01*
Y514017D01*
G01X155500Y517117D02*
X153000D01*
Y518158D01*
X153125Y518492D01*
X153292Y518700D01*
X153625Y518783D01*
X153958Y518700D01*
X154167Y518450D01*
X154292Y518158D01*
Y517117D01*
G01Y518158D02*
X155500Y518783D01*
G01X155208Y520342D02*
X155417Y520633D01*
X155500Y520967D01*
X155417Y521300D01*
X155167Y521592D01*
X154792Y521800D01*
X154417Y521883D01*
X153958D01*
X153583Y521800D01*
X153250Y521592D01*
X153083Y521342D01*
X153000Y521050D01*
X153083Y520717D01*
X153250Y520467D01*
X153500Y520300D01*
X153833Y520217D01*
X154125Y520300D01*
X154417Y520508D01*
X154583Y520758D01*
X154625Y521050D01*
X154542Y521383D01*
X154333Y521633D01*
X153958Y521883D01*
G01X155500Y524067D02*
X154958Y524150D01*
X154500Y524275D01*
X154083Y524442D01*
X153625Y524650D01*
X153000Y524983D01*
Y523317D01*
G01X157600Y534400D02*
X153600D01*
Y527000D01*
G01X183600Y530417D02*
X181100D01*
Y531417D01*
X181225Y531750D01*
X181517Y532000D01*
X181850Y532083D01*
X182183Y532000D01*
X182433Y531792D01*
X182558Y531417D01*
Y530417D01*
G01X181308Y535267D02*
X181183Y535017D01*
X181100Y534725D01*
Y534392D01*
X181225Y534017D01*
X181433Y533725D01*
X181683Y533517D01*
X182100Y533350D01*
X182475Y533308D01*
X182850Y533392D01*
X183100Y533517D01*
X183350Y533767D01*
X183517Y534058D01*
X183600Y534350D01*
Y534642D01*
X183517Y534933D01*
X183392Y535183D01*
X183225Y535392D01*
G01X183600Y537450D02*
X183558Y537742D01*
X183433Y538075D01*
X183225Y538283D01*
X182933Y538367D01*
X182642Y538283D01*
X182392Y538033D01*
X182267Y537658D01*
Y537242D01*
X182183Y536992D01*
X181975Y536783D01*
X181683Y536700D01*
X181392Y536825D01*
X181183Y537117D01*
X181100Y537450D01*
X181183Y537783D01*
X181392Y538075D01*
X181683Y538200D01*
X181975Y538117D01*
X182183Y537908D01*
X182267Y537658D01*
Y537242D01*
X182392Y536867D01*
X182642Y536617D01*
X182933Y536533D01*
X183225Y536617D01*
X183433Y536825D01*
X183558Y537158D01*
X183600Y537450D01*
G01Y540550D02*
X183558Y540842D01*
X183433Y541175D01*
X183225Y541383D01*
X182933Y541467D01*
X182642Y541383D01*
X182392Y541133D01*
X182267Y540758D01*
Y540342D01*
X182183Y540092D01*
X181975Y539883D01*
X181683Y539800D01*
X181392Y539925D01*
X181183Y540217D01*
X181100Y540550D01*
X181183Y540883D01*
X181392Y541175D01*
X181683Y541300D01*
X181975Y541217D01*
X182183Y541008D01*
X182267Y540758D01*
Y540342D01*
X182392Y539967D01*
X182642Y539717D01*
X182933Y539633D01*
X183225Y539717D01*
X183433Y539925D01*
X183558Y540258D01*
X183600Y540550D01*
G01X159017Y523000D02*
Y525500D01*
X160017D01*
X160350Y525375D01*
X160600Y525083D01*
X160683Y524750D01*
X160600Y524417D01*
X160392Y524167D01*
X160017Y524042D01*
X159017D01*
G01X163867Y525292D02*
X163617Y525417D01*
X163325Y525500D01*
X162992D01*
X162617Y525375D01*
X162325Y525167D01*
X162117Y524917D01*
X161950Y524500D01*
X161908Y524125D01*
X161992Y523750D01*
X162117Y523500D01*
X162367Y523250D01*
X162658Y523083D01*
X162950Y523000D01*
X163242D01*
X163533Y523083D01*
X163783Y523208D01*
X163992Y523375D01*
G01X166050Y523000D02*
X166342Y523042D01*
X166675Y523167D01*
X166883Y523375D01*
X166967Y523667D01*
X166883Y523958D01*
X166633Y524208D01*
X166258Y524333D01*
X165842D01*
X165592Y524417D01*
X165383Y524625D01*
X165300Y524917D01*
X165425Y525208D01*
X165717Y525417D01*
X166050Y525500D01*
X166383Y525417D01*
X166675Y525208D01*
X166800Y524917D01*
X166717Y524625D01*
X166508Y524417D01*
X166258Y524333D01*
X165842D01*
X165467Y524208D01*
X165217Y523958D01*
X165133Y523667D01*
X165217Y523375D01*
X165425Y523167D01*
X165758Y523042D01*
X166050Y523000D01*
G01X168358Y524042D02*
X168650Y524333D01*
X168900Y524500D01*
X169233Y524583D01*
X169525Y524500D01*
X169733Y524333D01*
X169900Y524083D01*
X169942Y523792D01*
X169900Y523542D01*
X169733Y523292D01*
X169483Y523083D01*
X169192Y523000D01*
X168858Y523083D01*
X168567Y523333D01*
X168400Y523708D01*
X168358Y524125D01*
X168442Y524667D01*
X168567Y524958D01*
X168775Y525250D01*
X169067Y525458D01*
X169358Y525500D01*
X169650Y525417D01*
X169858Y525208D01*
G01X179500Y540017D02*
X177000D01*
Y541017D01*
X177125Y541350D01*
X177417Y541600D01*
X177750Y541683D01*
X178083Y541600D01*
X178333Y541392D01*
X178458Y541017D01*
Y540017D01*
G01X177208Y544867D02*
X177083Y544617D01*
X177000Y544325D01*
Y543992D01*
X177125Y543617D01*
X177333Y543325D01*
X177583Y543117D01*
X178000Y542950D01*
X178375Y542908D01*
X178750Y542992D01*
X179000Y543117D01*
X179250Y543367D01*
X179417Y543658D01*
X179500Y543950D01*
Y544242D01*
X179417Y544533D01*
X179292Y544783D01*
X179125Y544992D01*
G01X179208Y546342D02*
X179417Y546633D01*
X179500Y546967D01*
X179417Y547300D01*
X179167Y547592D01*
X178792Y547800D01*
X178417Y547883D01*
X177958D01*
X177583Y547800D01*
X177250Y547592D01*
X177083Y547342D01*
X177000Y547050D01*
X177083Y546717D01*
X177250Y546467D01*
X177500Y546300D01*
X177833Y546217D01*
X178125Y546300D01*
X178417Y546508D01*
X178583Y546758D01*
X178625Y547050D01*
X178542Y547383D01*
X178333Y547633D01*
X177958Y547883D01*
G01X179125Y549233D02*
X179333Y549483D01*
X179458Y549775D01*
X179500Y550150D01*
X179417Y550525D01*
X179250Y550817D01*
X178958Y551025D01*
X178625Y551067D01*
X178292Y550983D01*
X178083Y550775D01*
X177917Y550483D01*
X177875Y550192D01*
X177917Y549900D01*
X178083Y549525D01*
X177000Y549650D01*
Y550775D01*
G01X170017Y501500D02*
Y504000D01*
X171017D01*
X171350Y503875D01*
X171600Y503583D01*
X171683Y503250D01*
X171600Y502917D01*
X171392Y502667D01*
X171017Y502542D01*
X170017D01*
G01X173117Y501500D02*
Y504000D01*
X174158D01*
X174492Y503875D01*
X174700Y503708D01*
X174783Y503375D01*
X174700Y503042D01*
X174450Y502833D01*
X174158Y502708D01*
X173117D01*
G01X174158D02*
X174783Y501500D01*
G01X176258Y502542D02*
X176550Y502833D01*
X176800Y503000D01*
X177133Y503083D01*
X177425Y503000D01*
X177633Y502833D01*
X177800Y502583D01*
X177842Y502292D01*
X177800Y502042D01*
X177633Y501792D01*
X177383Y501583D01*
X177092Y501500D01*
X176758Y501583D01*
X176467Y501833D01*
X176300Y502208D01*
X176258Y502625D01*
X176342Y503167D01*
X176467Y503458D01*
X176675Y503750D01*
X176967Y503958D01*
X177258Y504000D01*
X177550Y503917D01*
X177758Y503708D01*
G01X179358Y503583D02*
X179608Y503833D01*
X179900Y503958D01*
X180233Y504000D01*
X180650Y503917D01*
X180942Y503708D01*
X181025Y503458D01*
X180983Y503208D01*
X180817Y503000D01*
X179983Y502583D01*
X179608Y502292D01*
X179358Y501875D01*
X179275Y501500D01*
X181025D01*
G01X151517D02*
Y504000D01*
X152517D01*
X152850Y503875D01*
X153100Y503583D01*
X153183Y503250D01*
X153100Y502917D01*
X152892Y502667D01*
X152517Y502542D01*
X151517D01*
G01X154617Y501500D02*
Y504000D01*
X155658D01*
X155992Y503875D01*
X156200Y503708D01*
X156283Y503375D01*
X156200Y503042D01*
X155950Y502833D01*
X155658Y502708D01*
X154617D01*
G01X155658D02*
X156283Y501500D01*
G01X157758Y502542D02*
X158050Y502833D01*
X158300Y503000D01*
X158633Y503083D01*
X158925Y503000D01*
X159133Y502833D01*
X159300Y502583D01*
X159342Y502292D01*
X159300Y502042D01*
X159133Y501792D01*
X158883Y501583D01*
X158592Y501500D01*
X158258Y501583D01*
X157967Y501833D01*
X157800Y502208D01*
X157758Y502625D01*
X157842Y503167D01*
X157967Y503458D01*
X158175Y503750D01*
X158467Y503958D01*
X158758Y504000D01*
X159050Y503917D01*
X159258Y503708D01*
G01X160733Y502000D02*
X160983Y501708D01*
X161317Y501542D01*
X161692Y501500D01*
X162025Y501542D01*
X162358Y501750D01*
X162567Y502000D01*
X162608Y502250D01*
X162525Y502542D01*
X162233Y502750D01*
X161942Y502833D01*
X161567D01*
G01X161942D02*
X162192Y502958D01*
X162400Y503167D01*
X162483Y503417D01*
X162400Y503667D01*
X162192Y503875D01*
X161817Y504000D01*
X161442Y503958D01*
X161067Y503792D01*
G01X155400Y551100D02*
X156900Y549600D01*
G01X155400Y551100D02*
X156900Y552600D01*
G01X136000Y568517D02*
X133500D01*
Y569517D01*
X133625Y569850D01*
X133917Y570100D01*
X134250Y570183D01*
X134583Y570100D01*
X134833Y569892D01*
X134958Y569517D01*
Y568517D01*
G01X133708Y573367D02*
X133583Y573117D01*
X133500Y572825D01*
Y572492D01*
X133625Y572117D01*
X133833Y571825D01*
X134083Y571617D01*
X134500Y571450D01*
X134875Y571408D01*
X135250Y571492D01*
X135500Y571617D01*
X135750Y571867D01*
X135917Y572158D01*
X136000Y572450D01*
Y572742D01*
X135917Y573033D01*
X135792Y573283D01*
X135625Y573492D01*
G01X135708Y574842D02*
X135917Y575133D01*
X136000Y575467D01*
X135917Y575800D01*
X135667Y576092D01*
X135292Y576300D01*
X134917Y576383D01*
X134458D01*
X134083Y576300D01*
X133750Y576092D01*
X133583Y575842D01*
X133500Y575550D01*
X133583Y575217D01*
X133750Y574967D01*
X134000Y574800D01*
X134333Y574717D01*
X134625Y574800D01*
X134917Y575008D01*
X135083Y575258D01*
X135125Y575550D01*
X135042Y575883D01*
X134833Y576133D01*
X134458Y576383D01*
G01X133917Y577858D02*
X133667Y578108D01*
X133542Y578400D01*
X133500Y578733D01*
X133583Y579150D01*
X133792Y579442D01*
X134042Y579525D01*
X134292Y579483D01*
X134500Y579317D01*
X134917Y578483D01*
X135208Y578108D01*
X135625Y577858D01*
X136000Y577775D01*
Y579525D01*
G01X161000Y557017D02*
X158500D01*
Y558017D01*
X158625Y558350D01*
X158917Y558600D01*
X159250Y558683D01*
X159583Y558600D01*
X159833Y558392D01*
X159958Y558017D01*
Y557017D01*
G01X158708Y561867D02*
X158583Y561617D01*
X158500Y561325D01*
Y560992D01*
X158625Y560617D01*
X158833Y560325D01*
X159083Y560117D01*
X159500Y559950D01*
X159875Y559908D01*
X160250Y559992D01*
X160500Y560117D01*
X160750Y560367D01*
X160917Y560658D01*
X161000Y560950D01*
Y561242D01*
X160917Y561533D01*
X160792Y561783D01*
X160625Y561992D01*
G01X160708Y563342D02*
X160917Y563633D01*
X161000Y563967D01*
X160917Y564300D01*
X160667Y564592D01*
X160292Y564800D01*
X159917Y564883D01*
X159458D01*
X159083Y564800D01*
X158750Y564592D01*
X158583Y564342D01*
X158500Y564050D01*
X158583Y563717D01*
X158750Y563467D01*
X159000Y563300D01*
X159333Y563217D01*
X159625Y563300D01*
X159917Y563508D01*
X160083Y563758D01*
X160125Y564050D01*
X160042Y564383D01*
X159833Y564633D01*
X159458Y564883D01*
G01X161000Y567150D02*
X160958Y567442D01*
X160833Y567775D01*
X160625Y567983D01*
X160333Y568067D01*
X160042Y567983D01*
X159792Y567733D01*
X159667Y567358D01*
Y566942D01*
X159583Y566692D01*
X159375Y566483D01*
X159083Y566400D01*
X158792Y566525D01*
X158583Y566817D01*
X158500Y567150D01*
X158583Y567483D01*
X158792Y567775D01*
X159083Y567900D01*
X159375Y567817D01*
X159583Y567608D01*
X159667Y567358D01*
Y566942D01*
X159792Y566567D01*
X160042Y566317D01*
X160333Y566233D01*
X160625Y566317D01*
X160833Y566525D01*
X160958Y566858D01*
X161000Y567150D01*
G01X132500Y582400D02*
X135000D01*
G01X132500Y581442D02*
Y583358D01*
G01X135000Y584667D02*
X132500D01*
Y585667D01*
X132625Y586000D01*
X132917Y586250D01*
X133250Y586333D01*
X133583Y586250D01*
X133833Y586042D01*
X133958Y585667D01*
Y584667D01*
G01X134708Y587892D02*
X134917Y588183D01*
X135000Y588517D01*
X134917Y588850D01*
X134667Y589142D01*
X134292Y589350D01*
X133917Y589433D01*
X133458D01*
X133083Y589350D01*
X132750Y589142D01*
X132583Y588892D01*
X132500Y588600D01*
X132583Y588267D01*
X132750Y588017D01*
X133000Y587850D01*
X133333Y587767D01*
X133625Y587850D01*
X133917Y588058D01*
X134083Y588308D01*
X134125Y588600D01*
X134042Y588933D01*
X133833Y589183D01*
X133458Y589433D01*
G01X147500Y586350D02*
X150000D01*
G01X147500Y585392D02*
Y587308D01*
G01X150000Y588617D02*
X147500D01*
Y589617D01*
X147625Y589950D01*
X147917Y590200D01*
X148250Y590283D01*
X148583Y590200D01*
X148833Y589992D01*
X148958Y589617D01*
Y588617D01*
G01X150000Y592550D02*
X147500D01*
X148000Y592050D01*
G01X150000D02*
Y593050D01*
G01Y596150D02*
X147500D01*
X149292Y594608D01*
Y596692D01*
G01X143500Y585850D02*
X146000D01*
G01X143500Y584892D02*
Y586808D01*
G01X146000Y588117D02*
X143500D01*
Y589117D01*
X143625Y589450D01*
X143917Y589700D01*
X144250Y589783D01*
X144583Y589700D01*
X144833Y589492D01*
X144958Y589117D01*
Y588117D01*
G01X146000Y592050D02*
X143500D01*
X144000Y591550D01*
G01X146000D02*
Y592550D01*
G01X145500Y594233D02*
X145792Y594483D01*
X145958Y594817D01*
X146000Y595192D01*
X145958Y595525D01*
X145750Y595858D01*
X145500Y596067D01*
X145250Y596108D01*
X144958Y596025D01*
X144750Y595733D01*
X144667Y595442D01*
Y595067D01*
G01Y595442D02*
X144542Y595692D01*
X144333Y595900D01*
X144083Y595983D01*
X143833Y595900D01*
X143625Y595692D01*
X143500Y595317D01*
X143542Y594942D01*
X143708Y594567D01*
G01X137500Y580350D02*
X140000D01*
G01X137500Y579392D02*
Y581308D01*
G01X140000Y582617D02*
X137500D01*
Y583617D01*
X137625Y583950D01*
X137917Y584200D01*
X138250Y584283D01*
X138583Y584200D01*
X138833Y583992D01*
X138958Y583617D01*
Y582617D01*
G01X140000Y586550D02*
X137500D01*
X138000Y586050D01*
G01X140000D02*
Y587050D01*
G01Y589650D02*
X137500D01*
X138000Y589150D01*
G01X140000D02*
Y590150D01*
G01X164000Y582967D02*
X161500D01*
Y583967D01*
X161625Y584300D01*
X161917Y584550D01*
X162250Y584633D01*
X162583Y584550D01*
X162833Y584342D01*
X162958Y583967D01*
Y582967D01*
G01X164000Y586067D02*
X161500D01*
Y587108D01*
X161625Y587442D01*
X161792Y587650D01*
X162125Y587733D01*
X162458Y587650D01*
X162667Y587400D01*
X162792Y587108D01*
Y586067D01*
G01Y587108D02*
X164000Y587733D01*
G01Y590000D02*
X161500D01*
X162000Y589500D01*
G01X164000D02*
Y590500D01*
G01Y593100D02*
X161500D01*
X162000Y592600D01*
G01X164000D02*
Y593600D01*
G01X163625Y595283D02*
X163833Y595533D01*
X163958Y595825D01*
X164000Y596200D01*
X163917Y596575D01*
X163750Y596867D01*
X163458Y597075D01*
X163125Y597117D01*
X162792Y597033D01*
X162583Y596825D01*
X162417Y596533D01*
X162375Y596242D01*
X162417Y595950D01*
X162583Y595575D01*
X161500Y595700D01*
Y596825D01*
G01X143300Y576800D02*
X147300D01*
Y584200D01*
G01X151500Y564600D02*
X155500D01*
Y572000D01*
G01X150700Y566000D02*
Y570000D01*
X143300D01*
G01X134679Y551771D02*
X138679D01*
Y559171D01*
G01X163467Y599000D02*
Y601500D01*
X164467D01*
X164800Y601375D01*
X165050Y601083D01*
X165133Y600750D01*
X165050Y600417D01*
X164842Y600167D01*
X164467Y600042D01*
X163467D01*
G01X166567Y599000D02*
Y601500D01*
X167608D01*
X167942Y601375D01*
X168150Y601208D01*
X168233Y600875D01*
X168150Y600542D01*
X167900Y600333D01*
X167608Y600208D01*
X166567D01*
G01X167608D02*
X168233Y599000D01*
G01X170500D02*
Y601500D01*
X170000Y601000D01*
G01Y599000D02*
X171000D01*
G01X173600Y601500D02*
X173267Y601417D01*
X173017Y601208D01*
X172850Y600958D01*
X172725Y600625D01*
X172683Y600250D01*
X172725Y599875D01*
X172850Y599542D01*
X173017Y599292D01*
X173267Y599083D01*
X173600Y599000D01*
X173933Y599083D01*
X174183Y599292D01*
X174350Y599542D01*
X174475Y599875D01*
X174517Y600250D01*
X174475Y600625D01*
X174350Y600958D01*
X174183Y601208D01*
X173933Y601417D01*
X173600Y601500D01*
G01X176700Y599000D02*
X176992Y599042D01*
X177325Y599167D01*
X177533Y599375D01*
X177617Y599667D01*
X177533Y599958D01*
X177283Y600208D01*
X176908Y600333D01*
X176492D01*
X176242Y600417D01*
X176033Y600625D01*
X175950Y600917D01*
X176075Y601208D01*
X176367Y601417D01*
X176700Y601500D01*
X177033Y601417D01*
X177325Y601208D01*
X177450Y600917D01*
X177367Y600625D01*
X177158Y600417D01*
X176908Y600333D01*
X176492D01*
X176117Y600208D01*
X175867Y599958D01*
X175783Y599667D01*
X175867Y599375D01*
X176075Y599167D01*
X176408Y599042D01*
X176700Y599000D01*
G01X158200Y585000D02*
Y589000D01*
X150800D01*
G01X182500Y588467D02*
X180000D01*
Y589467D01*
X180125Y589800D01*
X180417Y590050D01*
X180750Y590133D01*
X181083Y590050D01*
X181333Y589842D01*
X181458Y589467D01*
Y588467D01*
G01X182500Y591567D02*
X180000D01*
Y592608D01*
X180125Y592942D01*
X180292Y593150D01*
X180625Y593233D01*
X180958Y593150D01*
X181167Y592900D01*
X181292Y592608D01*
Y591567D01*
G01Y592608D02*
X182500Y593233D01*
G01Y595500D02*
X180000D01*
X180500Y595000D01*
G01X182500D02*
Y596000D01*
G01X180000Y598600D02*
X180083Y598267D01*
X180292Y598017D01*
X180542Y597850D01*
X180875Y597725D01*
X181250Y597683D01*
X181625Y597725D01*
X181958Y597850D01*
X182208Y598017D01*
X182417Y598267D01*
X182500Y598600D01*
X182417Y598933D01*
X182208Y599183D01*
X181958Y599350D01*
X181625Y599475D01*
X181250Y599517D01*
X180875Y599475D01*
X180542Y599350D01*
X180292Y599183D01*
X180083Y598933D01*
X180000Y598600D01*
G01X182208Y600992D02*
X182417Y601283D01*
X182500Y601617D01*
X182417Y601950D01*
X182167Y602242D01*
X181792Y602450D01*
X181417Y602533D01*
X180958D01*
X180583Y602450D01*
X180250Y602242D01*
X180083Y601992D01*
X180000Y601700D01*
X180083Y601367D01*
X180250Y601117D01*
X180500Y600950D01*
X180833Y600867D01*
X181125Y600950D01*
X181417Y601158D01*
X181583Y601408D01*
X181625Y601700D01*
X181542Y602033D01*
X181333Y602283D01*
X180958Y602533D01*
G01X160000Y580600D02*
X156000D01*
Y573200D01*
G01X157000Y596617D02*
X159500D01*
Y598283D01*
G01Y600550D02*
X157000D01*
X157500Y600050D01*
G01X159500D02*
Y601050D01*
G01X168500Y586017D02*
X166000D01*
Y587017D01*
X166125Y587350D01*
X166417Y587600D01*
X166750Y587683D01*
X167083Y587600D01*
X167333Y587392D01*
X167458Y587017D01*
Y586017D01*
G01X166208Y590867D02*
X166083Y590617D01*
X166000Y590325D01*
Y589992D01*
X166125Y589617D01*
X166333Y589325D01*
X166583Y589117D01*
X167000Y588950D01*
X167375Y588908D01*
X167750Y588992D01*
X168000Y589117D01*
X168250Y589367D01*
X168417Y589658D01*
X168500Y589950D01*
Y590242D01*
X168417Y590533D01*
X168292Y590783D01*
X168125Y590992D01*
G01X168208Y592342D02*
X168417Y592633D01*
X168500Y592967D01*
X168417Y593300D01*
X168167Y593592D01*
X167792Y593800D01*
X167417Y593883D01*
X166958D01*
X166583Y593800D01*
X166250Y593592D01*
X166083Y593342D01*
X166000Y593050D01*
X166083Y592717D01*
X166250Y592467D01*
X166500Y592300D01*
X166833Y592217D01*
X167125Y592300D01*
X167417Y592508D01*
X167583Y592758D01*
X167625Y593050D01*
X167542Y593383D01*
X167333Y593633D01*
X166958Y593883D01*
G01X168500Y596650D02*
X166000D01*
X167792Y595108D01*
Y597192D01*
G01X152208Y594367D02*
X152083Y594117D01*
X152000Y593825D01*
Y593492D01*
X152125Y593117D01*
X152333Y592825D01*
X152583Y592617D01*
X153000Y592450D01*
X153375Y592408D01*
X153750Y592492D01*
X154000Y592617D01*
X154250Y592867D01*
X154417Y593158D01*
X154500Y593450D01*
Y593742D01*
X154417Y594033D01*
X154292Y594283D01*
X154125Y594492D01*
G01X154500Y596550D02*
X152000D01*
X152500Y596050D01*
G01X154500D02*
Y597050D01*
G01X139835Y632284D02*
X142835D01*
G01X139835Y622439D02*
X141835D01*
G01X143800Y620850D02*
X146300D01*
G01X143800Y619892D02*
Y621808D01*
G01X146300Y623117D02*
X143800D01*
Y624117D01*
X143925Y624450D01*
X144217Y624700D01*
X144550Y624783D01*
X144883Y624700D01*
X145133Y624492D01*
X145258Y624117D01*
Y623117D01*
G01X146300Y627050D02*
X143800D01*
X144300Y626550D01*
G01X146300D02*
Y627550D01*
G01X145925Y629233D02*
X146133Y629483D01*
X146258Y629775D01*
X146300Y630150D01*
X146217Y630525D01*
X146050Y630817D01*
X145758Y631025D01*
X145425Y631067D01*
X145092Y630983D01*
X144883Y630775D01*
X144717Y630483D01*
X144675Y630192D01*
X144717Y629900D01*
X144883Y629525D01*
X143800Y629650D01*
Y630775D01*
G01X181900Y618350D02*
X184400D01*
G01X181900Y617392D02*
Y619308D01*
G01X184400Y620617D02*
X181900D01*
Y621617D01*
X182025Y621950D01*
X182317Y622200D01*
X182650Y622283D01*
X182983Y622200D01*
X183233Y621992D01*
X183358Y621617D01*
Y620617D01*
G01X184400Y624550D02*
X181900D01*
X182400Y624050D01*
G01X184400D02*
Y625050D01*
G01X182317Y626858D02*
X182067Y627108D01*
X181942Y627400D01*
X181900Y627733D01*
X181983Y628150D01*
X182192Y628442D01*
X182442Y628525D01*
X182692Y628483D01*
X182900Y628317D01*
X183317Y627483D01*
X183608Y627108D01*
X184025Y626858D01*
X184400Y626775D01*
Y628525D01*
G01X172200Y629100D02*
X168200D01*
Y621700D01*
G01X160700Y624700D02*
Y620700D01*
X168100D01*
G01X150117Y620900D02*
Y623400D01*
X151158D01*
X151492Y623275D01*
X151700Y623108D01*
X151783Y622775D01*
X151700Y622442D01*
X151450Y622233D01*
X151158Y622108D01*
X150117D01*
G01X151158D02*
X151783Y620900D01*
G01X153258Y621942D02*
X153550Y622233D01*
X153800Y622400D01*
X154133Y622483D01*
X154425Y622400D01*
X154633Y622233D01*
X154800Y621983D01*
X154842Y621692D01*
X154800Y621442D01*
X154633Y621192D01*
X154383Y620983D01*
X154092Y620900D01*
X153758Y620983D01*
X153467Y621233D01*
X153300Y621608D01*
X153258Y622025D01*
X153342Y622567D01*
X153467Y622858D01*
X153675Y623150D01*
X153967Y623358D01*
X154258Y623400D01*
X154550Y623317D01*
X154758Y623108D01*
G01X150329Y617065D02*
Y613065D01*
X157729D01*
G01X148500Y637117D02*
X146000D01*
Y638158D01*
X146125Y638492D01*
X146292Y638700D01*
X146625Y638783D01*
X146958Y638700D01*
X147167Y638450D01*
X147292Y638158D01*
Y637117D01*
G01Y638158D02*
X148500Y638783D01*
G01X148125Y640133D02*
X148333Y640383D01*
X148458Y640675D01*
X148500Y641050D01*
X148417Y641425D01*
X148250Y641717D01*
X147958Y641925D01*
X147625Y641967D01*
X147292Y641883D01*
X147083Y641675D01*
X146917Y641383D01*
X146875Y641092D01*
X146917Y640800D01*
X147083Y640425D01*
X146000Y640550D01*
Y641675D01*
G01X149335Y630429D02*
X153335D01*
Y637829D01*
G01X182365Y647771D02*
X178365D01*
Y640371D01*
G01X146435Y647929D02*
X150435D01*
Y655329D01*
G01X168100Y624700D02*
Y628700D01*
X160700D01*
G01X179700Y622300D02*
Y626300D01*
X172300D01*
G01X142235Y647929D02*
X146235D01*
Y655329D01*
G01X176435Y650029D02*
Y630629D01*
G01X154735Y650029D02*
X176435D01*
G01X154735Y630629D02*
Y650029D01*
G01X176435Y630629D02*
X154735D01*
G01X144067Y615892D02*
X143817Y616017D01*
X143525Y616100D01*
X143192D01*
X142817Y615975D01*
X142525Y615767D01*
X142317Y615517D01*
X142150Y615100D01*
X142108Y614725D01*
X142192Y614350D01*
X142317Y614100D01*
X142567Y613850D01*
X142858Y613683D01*
X143150Y613600D01*
X143442D01*
X143733Y613683D01*
X143983Y613808D01*
X144192Y613975D01*
G01X145458Y615683D02*
X145708Y615933D01*
X146000Y616058D01*
X146333Y616100D01*
X146750Y616017D01*
X147042Y615808D01*
X147125Y615558D01*
X147083Y615308D01*
X146917Y615100D01*
X146083Y614683D01*
X145708Y614392D01*
X145458Y613975D01*
X145375Y613600D01*
X147125D01*
G01X132708Y673817D02*
X132583Y673567D01*
X132500Y673275D01*
Y672942D01*
X132625Y672567D01*
X132833Y672275D01*
X133083Y672067D01*
X133500Y671900D01*
X133875Y671858D01*
X134250Y671942D01*
X134500Y672067D01*
X134750Y672317D01*
X134917Y672608D01*
X135000Y672900D01*
Y673192D01*
X134917Y673483D01*
X134792Y673733D01*
X134625Y673942D01*
G01X135000Y676000D02*
X132500D01*
X133000Y675500D01*
G01X135000D02*
Y676500D01*
G01X132917Y678308D02*
X132667Y678558D01*
X132542Y678850D01*
X132500Y679183D01*
X132583Y679600D01*
X132792Y679892D01*
X133042Y679975D01*
X133292Y679933D01*
X133500Y679767D01*
X133917Y678933D01*
X134208Y678558D01*
X134625Y678308D01*
X135000Y678225D01*
Y679975D01*
G01X137000Y682567D02*
X134500D01*
Y683608D01*
X134625Y683942D01*
X134792Y684150D01*
X135125Y684233D01*
X135458Y684150D01*
X135667Y683900D01*
X135792Y683608D01*
Y682567D01*
G01Y683608D02*
X137000Y684233D01*
G01Y686500D02*
X134500D01*
X135000Y686000D01*
G01X137000D02*
Y687000D01*
G01Y689517D02*
X136458Y689600D01*
X136000Y689725D01*
X135583Y689892D01*
X135125Y690100D01*
X134500Y690433D01*
Y688767D01*
G01X156065Y658688D02*
X153565D01*
Y659729D01*
X153690Y660063D01*
X153857Y660271D01*
X154190Y660354D01*
X154523Y660271D01*
X154732Y660021D01*
X154857Y659729D01*
Y658688D01*
G01Y659729D02*
X156065Y660354D01*
G01X155773Y661913D02*
X155982Y662204D01*
X156065Y662538D01*
X155982Y662871D01*
X155732Y663163D01*
X155357Y663371D01*
X154982Y663454D01*
X154523D01*
X154148Y663371D01*
X153815Y663163D01*
X153648Y662913D01*
X153565Y662621D01*
X153648Y662288D01*
X153815Y662038D01*
X154065Y661871D01*
X154398Y661788D01*
X154690Y661871D01*
X154982Y662079D01*
X155148Y662329D01*
X155190Y662621D01*
X155107Y662954D01*
X154898Y663204D01*
X154523Y663454D01*
G01X139765Y664071D02*
X135765D01*
Y656671D01*
G01X147435Y658746D02*
X144935D01*
Y659787D01*
X145060Y660121D01*
X145227Y660329D01*
X145560Y660412D01*
X145893Y660329D01*
X146102Y660079D01*
X146227Y659787D01*
Y658746D01*
G01Y659787D02*
X147435Y660412D01*
G01Y662596D02*
X146893Y662679D01*
X146435Y662804D01*
X146018Y662971D01*
X145560Y663179D01*
X144935Y663512D01*
Y661846D01*
G01X165335Y656146D02*
X162835D01*
Y657187D01*
X162960Y657521D01*
X163127Y657729D01*
X163460Y657812D01*
X163793Y657729D01*
X164002Y657479D01*
X164127Y657187D01*
Y656146D01*
G01Y657187D02*
X165335Y657812D01*
G01X163252Y659287D02*
X163002Y659537D01*
X162877Y659829D01*
X162835Y660162D01*
X162918Y660579D01*
X163127Y660871D01*
X163377Y660954D01*
X163627Y660912D01*
X163835Y660746D01*
X164252Y659912D01*
X164543Y659537D01*
X164960Y659287D01*
X165335Y659204D01*
Y660954D01*
G01X151635Y658396D02*
X149135D01*
Y659437D01*
X149260Y659771D01*
X149427Y659979D01*
X149760Y660062D01*
X150093Y659979D01*
X150302Y659729D01*
X150427Y659437D01*
Y658396D01*
G01Y659437D02*
X151635Y660062D01*
G01Y662329D02*
X149135D01*
X149635Y661829D01*
G01X151635D02*
Y662829D01*
G01Y665429D02*
X149135D01*
X149635Y664929D01*
G01X151635D02*
Y665929D01*
G01X161135Y656146D02*
X158635D01*
Y657187D01*
X158760Y657521D01*
X158927Y657729D01*
X159260Y657812D01*
X159593Y657729D01*
X159802Y657479D01*
X159927Y657187D01*
Y656146D01*
G01Y657187D02*
X161135Y657812D01*
G01Y660079D02*
X158635D01*
X159135Y659579D01*
G01X161135D02*
Y660579D01*
G01X152500Y697300D02*
X156500D01*
Y704700D01*
G01X165700Y694200D02*
X169700D01*
Y701600D01*
G01X161500Y680617D02*
X159000D01*
Y681617D01*
X159125Y681950D01*
X159417Y682200D01*
X159750Y682283D01*
X160083Y682200D01*
X160333Y681992D01*
X160458Y681617D01*
Y680617D01*
G01X161500Y683717D02*
X159000D01*
Y684758D01*
X159125Y685092D01*
X159292Y685300D01*
X159625Y685383D01*
X159958Y685300D01*
X160167Y685050D01*
X160292Y684758D01*
Y683717D01*
G01Y684758D02*
X161500Y685383D01*
G01Y688150D02*
X159000D01*
X160792Y686608D01*
Y688692D01*
G01X161500Y691250D02*
X159000D01*
X160792Y689708D01*
Y691792D01*
G01X156500Y689200D02*
X152500D01*
Y681800D01*
G01X156500Y697300D02*
X160500D01*
Y704700D01*
G01X169800Y703100D02*
Y699100D01*
X177200D01*
G01X143200Y662017D02*
X140700D01*
Y663058D01*
X140825Y663392D01*
X140992Y663600D01*
X141325Y663683D01*
X141658Y663600D01*
X141867Y663350D01*
X141992Y663058D01*
Y662017D01*
G01Y663058D02*
X143200Y663683D01*
G01Y665950D02*
X140700D01*
X141200Y665450D01*
G01X143200D02*
Y666450D01*
G01X142158Y668258D02*
X141867Y668550D01*
X141700Y668800D01*
X141617Y669133D01*
X141700Y669425D01*
X141867Y669633D01*
X142117Y669800D01*
X142408Y669842D01*
X142658Y669800D01*
X142908Y669633D01*
X143117Y669383D01*
X143200Y669092D01*
X143117Y668758D01*
X142867Y668467D01*
X142492Y668300D01*
X142075Y668258D01*
X141533Y668342D01*
X141242Y668467D01*
X140950Y668675D01*
X140742Y668967D01*
X140700Y669258D01*
X140783Y669550D01*
X140992Y669758D01*
G01X143200Y672150D02*
X140700D01*
X141200Y671650D01*
G01X143200D02*
Y672650D01*
G01X155967Y676400D02*
Y678900D01*
X156967D01*
X157300Y678775D01*
X157550Y678483D01*
X157633Y678150D01*
X157550Y677817D01*
X157342Y677567D01*
X156967Y677442D01*
X155967D01*
G01X159900Y676400D02*
X159567Y676442D01*
X159275Y676608D01*
X159025Y676858D01*
X158858Y677150D01*
X158775Y677483D01*
Y677817D01*
X158858Y678150D01*
X159025Y678442D01*
X159275Y678692D01*
X159567Y678858D01*
X159900Y678900D01*
X160233Y678858D01*
X160525Y678692D01*
X160775Y678442D01*
X160942Y678150D01*
X161025Y677817D01*
Y677483D01*
X160942Y677150D01*
X160775Y676858D01*
X160525Y676608D01*
X160233Y676442D01*
X159900Y676400D01*
G01X160233Y677067D02*
X160733Y676400D01*
G01X162292Y676692D02*
X162583Y676483D01*
X162917Y676400D01*
X163250Y676483D01*
X163542Y676733D01*
X163750Y677108D01*
X163833Y677483D01*
Y677942D01*
X163750Y678317D01*
X163542Y678650D01*
X163292Y678817D01*
X163000Y678900D01*
X162667Y678817D01*
X162417Y678650D01*
X162250Y678400D01*
X162167Y678067D01*
X162250Y677775D01*
X162458Y677483D01*
X162708Y677317D01*
X163000Y677275D01*
X163333Y677358D01*
X163583Y677567D01*
X163833Y677942D01*
G01X139000Y693000D02*
Y679000D01*
G01X152000Y693000D02*
X139000D01*
G01X152000Y679000D02*
Y693000D01*
G01X139000Y679000D02*
X152000D01*
G01X171250Y656200D02*
X170917Y656242D01*
X170625Y656408D01*
X170375Y656658D01*
X170208Y656950D01*
X170125Y657283D01*
Y657617D01*
X170208Y657950D01*
X170375Y658242D01*
X170625Y658492D01*
X170917Y658658D01*
X171250Y658700D01*
X171583Y658658D01*
X171875Y658492D01*
X172125Y658242D01*
X172292Y657950D01*
X172375Y657617D01*
Y657283D01*
X172292Y656950D01*
X172125Y656658D01*
X171875Y656408D01*
X171583Y656242D01*
X171250Y656200D01*
G01X173475Y656533D02*
X173808Y656325D01*
X174183Y656200D01*
X174517D01*
X174850Y656325D01*
X175100Y656533D01*
X175225Y656825D01*
X175142Y657117D01*
X174933Y657367D01*
X174558Y657533D01*
X174058Y657617D01*
X173767Y657783D01*
X173642Y658075D01*
X173725Y658367D01*
X173933Y658575D01*
X174225Y658700D01*
X174517D01*
X174808Y658617D01*
X175058Y658408D01*
G01X178367Y658492D02*
X178117Y658617D01*
X177825Y658700D01*
X177492D01*
X177117Y658575D01*
X176825Y658367D01*
X176617Y658117D01*
X176450Y657700D01*
X176408Y657325D01*
X176492Y656950D01*
X176617Y656700D01*
X176867Y656450D01*
X177158Y656283D01*
X177450Y656200D01*
X177742D01*
X178033Y656283D01*
X178283Y656408D01*
X178492Y656575D01*
G01X180550Y656200D02*
Y658700D01*
X180050Y658200D01*
G01Y656200D02*
X181050D01*
G01X179708Y691267D02*
X179583Y691017D01*
X179500Y690725D01*
Y690392D01*
X179625Y690017D01*
X179833Y689725D01*
X180083Y689517D01*
X180500Y689350D01*
X180875Y689308D01*
X181250Y689392D01*
X181500Y689517D01*
X181750Y689767D01*
X181917Y690058D01*
X182000Y690350D01*
Y690642D01*
X181917Y690933D01*
X181792Y691183D01*
X181625Y691392D01*
G01X179917Y692658D02*
X179667Y692908D01*
X179542Y693200D01*
X179500Y693533D01*
X179583Y693950D01*
X179792Y694242D01*
X180042Y694325D01*
X180292Y694283D01*
X180500Y694117D01*
X180917Y693283D01*
X181208Y692908D01*
X181625Y692658D01*
X182000Y692575D01*
Y694325D01*
G01X181625Y695633D02*
X181833Y695883D01*
X181958Y696175D01*
X182000Y696550D01*
X181917Y696925D01*
X181750Y697217D01*
X181458Y697425D01*
X181125Y697467D01*
X180792Y697383D01*
X180583Y697175D01*
X180417Y696883D01*
X180375Y696592D01*
X180417Y696300D01*
X180583Y695925D01*
X179500Y696050D01*
Y697175D01*
G01X182000Y700150D02*
X179500D01*
X181292Y698608D01*
Y700692D01*
G01X180500Y711533D02*
X182292D01*
X182667Y711700D01*
X182917Y712033D01*
X183000Y712450D01*
X182917Y712867D01*
X182667Y713200D01*
X182292Y713367D01*
X180500D01*
G01X183000Y715550D02*
X182958Y715842D01*
X182833Y716175D01*
X182625Y716383D01*
X182333Y716467D01*
X182042Y716383D01*
X181792Y716133D01*
X181667Y715758D01*
Y715342D01*
X181583Y715092D01*
X181375Y714883D01*
X181083Y714800D01*
X180792Y714925D01*
X180583Y715217D01*
X180500Y715550D01*
X180583Y715883D01*
X180792Y716175D01*
X181083Y716300D01*
X181375Y716217D01*
X181583Y716008D01*
X181667Y715758D01*
Y715342D01*
X181792Y714967D01*
X182042Y714717D01*
X182333Y714633D01*
X182625Y714717D01*
X182833Y714925D01*
X182958Y715258D01*
X183000Y715550D01*
G01X171900Y728204D02*
Y714204D01*
X151800D01*
Y728204D01*
X171900D01*
G01X151950Y723054D02*
X152050D01*
X153900Y721204D01*
X152100Y719404D01*
X152000D01*
G01X151500Y737917D02*
X149000D01*
Y738917D01*
X149125Y739250D01*
X149417Y739500D01*
X149750Y739583D01*
X150083Y739500D01*
X150333Y739292D01*
X150458Y738917D01*
Y737917D01*
G01X149208Y742767D02*
X149083Y742517D01*
X149000Y742225D01*
Y741892D01*
X149125Y741517D01*
X149333Y741225D01*
X149583Y741017D01*
X150000Y740850D01*
X150375Y740808D01*
X150750Y740892D01*
X151000Y741017D01*
X151250Y741267D01*
X151417Y741558D01*
X151500Y741850D01*
Y742142D01*
X151417Y742433D01*
X151292Y742683D01*
X151125Y742892D01*
G01X151500Y744950D02*
X149000D01*
X149500Y744450D01*
G01X151500D02*
Y745450D01*
G01X149417Y747258D02*
X149167Y747508D01*
X149042Y747800D01*
X149000Y748133D01*
X149083Y748550D01*
X149292Y748842D01*
X149542Y748925D01*
X149792Y748883D01*
X150000Y748717D01*
X150417Y747883D01*
X150708Y747508D01*
X151125Y747258D01*
X151500Y747175D01*
Y748925D01*
G01X150458Y750358D02*
X150167Y750650D01*
X150000Y750900D01*
X149917Y751233D01*
X150000Y751525D01*
X150167Y751733D01*
X150417Y751900D01*
X150708Y751942D01*
X150958Y751900D01*
X151208Y751733D01*
X151417Y751483D01*
X151500Y751192D01*
X151417Y750858D01*
X151167Y750567D01*
X150792Y750400D01*
X150375Y750358D01*
X149833Y750442D01*
X149542Y750567D01*
X149250Y750775D01*
X149042Y751067D01*
X149000Y751358D01*
X149083Y751650D01*
X149292Y751858D01*
G01X149417Y753458D02*
X149167Y753708D01*
X149042Y754000D01*
X149000Y754333D01*
X149083Y754750D01*
X149292Y755042D01*
X149542Y755125D01*
X149792Y755083D01*
X150000Y754917D01*
X150417Y754083D01*
X150708Y753708D01*
X151125Y753458D01*
X151500Y753375D01*
Y755125D01*
G01X143000Y717700D02*
Y723200D01*
G01X151000Y717700D02*
X143000D01*
G01X151000Y723200D02*
Y717700D01*
G01Y735300D02*
Y729800D01*
G01X143000Y735300D02*
X151000D01*
G01X143000Y729800D02*
Y735300D01*
G01X179000Y711517D02*
X176500D01*
Y712558D01*
X176625Y712892D01*
X176792Y713100D01*
X177125Y713183D01*
X177458Y713100D01*
X177667Y712850D01*
X177792Y712558D01*
Y711517D01*
G01Y712558D02*
X179000Y713183D01*
G01X176917Y714658D02*
X176667Y714908D01*
X176542Y715200D01*
X176500Y715533D01*
X176583Y715950D01*
X176792Y716242D01*
X177042Y716325D01*
X177292Y716283D01*
X177500Y716117D01*
X177917Y715283D01*
X178208Y714908D01*
X178625Y714658D01*
X179000Y714575D01*
Y716325D01*
G01X177958Y717758D02*
X177667Y718050D01*
X177500Y718300D01*
X177417Y718633D01*
X177500Y718925D01*
X177667Y719133D01*
X177917Y719300D01*
X178208Y719342D01*
X178458Y719300D01*
X178708Y719133D01*
X178917Y718883D01*
X179000Y718592D01*
X178917Y718258D01*
X178667Y717967D01*
X178292Y717800D01*
X177875Y717758D01*
X177333Y717842D01*
X177042Y717967D01*
X176750Y718175D01*
X176542Y718467D01*
X176500Y718758D01*
X176583Y719050D01*
X176792Y719258D01*
G01X179000Y721650D02*
X176500D01*
X177000Y721150D01*
G01X179000D02*
Y722150D01*
G01X151500Y713700D02*
X147500D01*
Y706300D01*
G01X139500Y735517D02*
X137000D01*
Y736517D01*
X137125Y736850D01*
X137417Y737100D01*
X137750Y737183D01*
X138083Y737100D01*
X138333Y736892D01*
X138458Y736517D01*
Y735517D01*
G01X139500Y739450D02*
X139458Y739117D01*
X139292Y738825D01*
X139042Y738575D01*
X138750Y738408D01*
X138417Y738325D01*
X138083D01*
X137750Y738408D01*
X137458Y738575D01*
X137208Y738825D01*
X137042Y739117D01*
X137000Y739450D01*
X137042Y739783D01*
X137208Y740075D01*
X137458Y740325D01*
X137750Y740492D01*
X138083Y740575D01*
X138417D01*
X138750Y740492D01*
X139042Y740325D01*
X139292Y740075D01*
X139458Y739783D01*
X139500Y739450D01*
G01X138833Y739783D02*
X139500Y740283D01*
G01Y742550D02*
X137000D01*
X137500Y742050D01*
G01X139500D02*
Y743050D01*
G01X137000Y745650D02*
X137083Y745317D01*
X137292Y745067D01*
X137542Y744900D01*
X137875Y744775D01*
X138250Y744733D01*
X138625Y744775D01*
X138958Y744900D01*
X139208Y745067D01*
X139417Y745317D01*
X139500Y745650D01*
X139417Y745983D01*
X139208Y746233D01*
X138958Y746400D01*
X138625Y746525D01*
X138250Y746567D01*
X137875Y746525D01*
X137542Y746400D01*
X137292Y746233D01*
X137083Y745983D01*
X137000Y745650D01*
G01X141900Y719300D02*
Y733300D01*
G01X158720Y871585D02*
Y873835D01*
G01X164600Y871585D02*
X158720D01*
G01X164600Y873835D02*
Y871585D01*
G01X161565Y872935D02*
Y871585D01*
G01X162930Y877335D02*
X158720D01*
G01X163815Y877105D02*
X162930Y877335D01*
G01X164400Y876655D02*
X163815Y877105D01*
G01X164600Y876090D02*
X164400Y876655D01*
G01Y875525D02*
X164600Y876090D01*
G01X163815Y875075D02*
X164400Y875525D01*
G01X162930Y874850D02*
X163815Y875075D01*
G01X158720Y874850D02*
X162930D01*
G01X164505Y883300D02*
X164600Y882855D01*
G01X164110Y883700D02*
X164505Y883300D01*
G01X163520Y884035D02*
X164110Y883700D01*
G01X162835Y884265D02*
X163520Y884035D01*
G01X162050Y884375D02*
X162835Y884265D01*
G01X161270Y884375D02*
X162050D01*
G01X160485Y884265D02*
X161270Y884375D01*
G01X159800Y884035D02*
X160485Y884265D01*
G01X159210Y883700D02*
X159800Y884035D01*
G01X158815Y883300D02*
X159210Y883700D01*
G01X158720Y882855D02*
X158815Y883300D01*
G01Y882405D02*
X158720Y882855D01*
G01X159210Y882005D02*
X158815Y882405D01*
G01X159800Y881670D02*
X159210Y882005D01*
G01X160485Y881440D02*
X159800Y881670D01*
G01X161270Y881330D02*
X160485Y881440D01*
G01X162050Y881330D02*
X161270D01*
G01X162835Y881440D02*
X162050Y881330D01*
G01X163520Y881670D02*
X162835Y881440D01*
G01X164110Y882005D02*
X163520Y881670D01*
G01X164505Y882405D02*
X164110Y882005D01*
G01X164600Y882855D02*
X164505Y882405D01*
G01X164600Y885280D02*
X160680D01*
G01X161860Y887190D02*
X164600D01*
G01X161170Y887020D02*
X161860Y887190D01*
G01X160780Y886680D02*
X161170Y887020D01*
G01X160680Y886290D02*
X160780Y886680D01*
G01Y885835D02*
X160680Y886290D01*
G01X161170Y885500D02*
X160780Y885835D01*
G01X161660Y885280D02*
X161170Y885500D01*
G01X164600Y889615D02*
X158720D01*
G01X163915Y893445D02*
X160680Y894180D01*
G01X165480Y893105D02*
X163915Y893445D01*
G01X165975Y892885D02*
X165480Y893105D01*
G01X166365Y892600D02*
X165975Y892885D01*
G01X166560Y892150D02*
X166365Y892600D01*
G01Y891810D02*
X166560Y892150D01*
G01X160680Y892380D02*
X163915Y893445D01*
G01X151000Y930567D02*
X148500D01*
Y931608D01*
X148625Y931942D01*
X148792Y932150D01*
X149125Y932233D01*
X149458Y932150D01*
X149667Y931900D01*
X149792Y931608D01*
Y930567D01*
G01Y931608D02*
X151000Y932233D01*
G01Y934500D02*
X148500D01*
X149000Y934000D01*
G01X151000D02*
Y935000D01*
G01X150625Y936683D02*
X150833Y936933D01*
X150958Y937225D01*
X151000Y937600D01*
X150917Y937975D01*
X150750Y938267D01*
X150458Y938475D01*
X150125Y938517D01*
X149792Y938433D01*
X149583Y938225D01*
X149417Y937933D01*
X149375Y937642D01*
X149417Y937350D01*
X149583Y936975D01*
X148500Y937100D01*
Y938225D01*
G01X151000Y940617D02*
X150458Y940700D01*
X150000Y940825D01*
X149583Y940992D01*
X149125Y941200D01*
X148500Y941533D01*
Y939867D01*
G01X147000Y943800D02*
X151000D01*
Y951200D01*
G01X155000Y930567D02*
X152500D01*
Y931608D01*
X152625Y931942D01*
X152792Y932150D01*
X153125Y932233D01*
X153458Y932150D01*
X153667Y931900D01*
X153792Y931608D01*
Y930567D01*
G01Y931608D02*
X155000Y932233D01*
G01Y934500D02*
X152500D01*
X153000Y934000D01*
G01X155000D02*
Y935000D01*
G01X154625Y936683D02*
X154833Y936933D01*
X154958Y937225D01*
X155000Y937600D01*
X154917Y937975D01*
X154750Y938267D01*
X154458Y938475D01*
X154125Y938517D01*
X153792Y938433D01*
X153583Y938225D01*
X153417Y937933D01*
X153375Y937642D01*
X153417Y937350D01*
X153583Y936975D01*
X152500Y937100D01*
Y938225D01*
G01X153958Y939908D02*
X153667Y940200D01*
X153500Y940450D01*
X153417Y940783D01*
X153500Y941075D01*
X153667Y941283D01*
X153917Y941450D01*
X154208Y941492D01*
X154458Y941450D01*
X154708Y941283D01*
X154917Y941033D01*
X155000Y940742D01*
X154917Y940408D01*
X154667Y940117D01*
X154292Y939950D01*
X153875Y939908D01*
X153333Y939992D01*
X153042Y940117D01*
X152750Y940325D01*
X152542Y940617D01*
X152500Y940908D01*
X152583Y941200D01*
X152792Y941408D01*
G01X151000Y943800D02*
X155000D01*
Y951200D01*
G01X159000Y930567D02*
X156500D01*
Y931608D01*
X156625Y931942D01*
X156792Y932150D01*
X157125Y932233D01*
X157458Y932150D01*
X157667Y931900D01*
X157792Y931608D01*
Y930567D01*
G01Y931608D02*
X159000Y932233D01*
G01Y934500D02*
X156500D01*
X157000Y934000D01*
G01X159000D02*
Y935000D01*
G01X158625Y936683D02*
X158833Y936933D01*
X158958Y937225D01*
X159000Y937600D01*
X158917Y937975D01*
X158750Y938267D01*
X158458Y938475D01*
X158125Y938517D01*
X157792Y938433D01*
X157583Y938225D01*
X157417Y937933D01*
X157375Y937642D01*
X157417Y937350D01*
X157583Y936975D01*
X156500Y937100D01*
Y938225D01*
G01X158625Y939783D02*
X158833Y940033D01*
X158958Y940325D01*
X159000Y940700D01*
X158917Y941075D01*
X158750Y941367D01*
X158458Y941575D01*
X158125Y941617D01*
X157792Y941533D01*
X157583Y941325D01*
X157417Y941033D01*
X157375Y940742D01*
X157417Y940450D01*
X157583Y940075D01*
X156500Y940200D01*
Y941325D01*
G01X155000Y943800D02*
X159000D01*
Y951200D01*
G01X147000Y930567D02*
X144500D01*
Y931608D01*
X144625Y931942D01*
X144792Y932150D01*
X145125Y932233D01*
X145458Y932150D01*
X145667Y931900D01*
X145792Y931608D01*
Y930567D01*
G01Y931608D02*
X147000Y932233D01*
G01Y934500D02*
X144500D01*
X145000Y934000D01*
G01X147000D02*
Y935000D01*
G01Y938100D02*
X144500D01*
X146292Y936558D01*
Y938642D01*
G01X147000Y940700D02*
X146958Y940992D01*
X146833Y941325D01*
X146625Y941533D01*
X146333Y941617D01*
X146042Y941533D01*
X145792Y941283D01*
X145667Y940908D01*
Y940492D01*
X145583Y940242D01*
X145375Y940033D01*
X145083Y939950D01*
X144792Y940075D01*
X144583Y940367D01*
X144500Y940700D01*
X144583Y941033D01*
X144792Y941325D01*
X145083Y941450D01*
X145375Y941367D01*
X145583Y941158D01*
X145667Y940908D01*
Y940492D01*
X145792Y940117D01*
X146042Y939867D01*
X146333Y939783D01*
X146625Y939867D01*
X146833Y940075D01*
X146958Y940408D01*
X147000Y940700D01*
G01X143000Y943800D02*
X147000D01*
Y951200D01*
G01X141500Y931067D02*
X139000D01*
Y932108D01*
X139125Y932442D01*
X139292Y932650D01*
X139625Y932733D01*
X139958Y932650D01*
X140167Y932400D01*
X140292Y932108D01*
Y931067D01*
G01Y932108D02*
X141500Y932733D01*
G01X141125Y934083D02*
X141333Y934333D01*
X141458Y934625D01*
X141500Y935000D01*
X141417Y935375D01*
X141250Y935667D01*
X140958Y935875D01*
X140625Y935917D01*
X140292Y935833D01*
X140083Y935625D01*
X139917Y935333D01*
X139875Y935042D01*
X139917Y934750D01*
X140083Y934375D01*
X139000Y934500D01*
Y935625D01*
G01X140458Y937308D02*
X140167Y937600D01*
X140000Y937850D01*
X139917Y938183D01*
X140000Y938475D01*
X140167Y938683D01*
X140417Y938850D01*
X140708Y938892D01*
X140958Y938850D01*
X141208Y938683D01*
X141417Y938433D01*
X141500Y938142D01*
X141417Y937808D01*
X141167Y937517D01*
X140792Y937350D01*
X140375Y937308D01*
X139833Y937392D01*
X139542Y937517D01*
X139250Y937725D01*
X139042Y938017D01*
X139000Y938308D01*
X139083Y938600D01*
X139292Y938808D01*
G01X138500Y942400D02*
X142500D01*
Y949800D01*
G01X137500Y931067D02*
X135000D01*
Y932108D01*
X135125Y932442D01*
X135292Y932650D01*
X135625Y932733D01*
X135958Y932650D01*
X136167Y932400D01*
X136292Y932108D01*
Y931067D01*
G01Y932108D02*
X137500Y932733D01*
G01X137125Y934083D02*
X137333Y934333D01*
X137458Y934625D01*
X137500Y935000D01*
X137417Y935375D01*
X137250Y935667D01*
X136958Y935875D01*
X136625Y935917D01*
X136292Y935833D01*
X136083Y935625D01*
X135917Y935333D01*
X135875Y935042D01*
X135917Y934750D01*
X136083Y934375D01*
X135000Y934500D01*
Y935625D01*
G01X137125Y937183D02*
X137333Y937433D01*
X137458Y937725D01*
X137500Y938100D01*
X137417Y938475D01*
X137250Y938767D01*
X136958Y938975D01*
X136625Y939017D01*
X136292Y938933D01*
X136083Y938725D01*
X135917Y938433D01*
X135875Y938142D01*
X135917Y937850D01*
X136083Y937475D01*
X135000Y937600D01*
Y938725D01*
G01X134000Y942400D02*
X138000D01*
Y949800D01*
G01X160000Y970533D02*
X161792D01*
X162167Y970700D01*
X162417Y971033D01*
X162500Y971450D01*
X162417Y971867D01*
X162167Y972200D01*
X161792Y972367D01*
X160000D01*
G01X161458Y973758D02*
X161167Y974050D01*
X161000Y974300D01*
X160917Y974633D01*
X161000Y974925D01*
X161167Y975133D01*
X161417Y975300D01*
X161708Y975342D01*
X161958Y975300D01*
X162208Y975133D01*
X162417Y974883D01*
X162500Y974592D01*
X162417Y974258D01*
X162167Y973967D01*
X161792Y973800D01*
X161375Y973758D01*
X160833Y973842D01*
X160542Y973967D01*
X160250Y974175D01*
X160042Y974467D01*
X160000Y974758D01*
X160083Y975050D01*
X160292Y975258D01*
G01X136300Y970600D02*
X134100Y968400D01*
G01X136300Y970600D02*
X134100Y972800D01*
G01Y977600D02*
Y963600D01*
G01X155600D02*
X134800D01*
G01X155600Y977600D02*
Y963600D01*
G01X134100Y977600D02*
X155600D01*
G01X135208Y989317D02*
X135083Y989067D01*
X135000Y988775D01*
Y988442D01*
X135125Y988067D01*
X135333Y987775D01*
X135583Y987567D01*
X136000Y987400D01*
X136375Y987358D01*
X136750Y987442D01*
X137000Y987567D01*
X137250Y987817D01*
X137417Y988108D01*
X137500Y988400D01*
Y988692D01*
X137417Y988983D01*
X137292Y989233D01*
X137125Y989442D01*
G01X137500Y991500D02*
X135000D01*
X135500Y991000D01*
G01X137500D02*
Y992000D01*
G01X137208Y993892D02*
X137417Y994183D01*
X137500Y994517D01*
X137417Y994850D01*
X137167Y995142D01*
X136792Y995350D01*
X136417Y995433D01*
X135958D01*
X135583Y995350D01*
X135250Y995142D01*
X135083Y994892D01*
X135000Y994600D01*
X135083Y994267D01*
X135250Y994017D01*
X135500Y993850D01*
X135833Y993767D01*
X136125Y993850D01*
X136417Y994058D01*
X136583Y994308D01*
X136625Y994600D01*
X136542Y994933D01*
X136333Y995183D01*
X135958Y995433D01*
G01X163500Y980350D02*
X166000D01*
G01X163500Y979392D02*
Y981308D01*
G01X166000Y982617D02*
X163500D01*
Y983617D01*
X163625Y983950D01*
X163917Y984200D01*
X164250Y984283D01*
X164583Y984200D01*
X164833Y983992D01*
X164958Y983617D01*
Y982617D01*
G01X163917Y985758D02*
X163667Y986008D01*
X163542Y986300D01*
X163500Y986633D01*
X163583Y987050D01*
X163792Y987342D01*
X164042Y987425D01*
X164292Y987383D01*
X164500Y987217D01*
X164917Y986383D01*
X165208Y986008D01*
X165625Y985758D01*
X166000Y985675D01*
Y987425D01*
G01X164958Y988858D02*
X164667Y989150D01*
X164500Y989400D01*
X164417Y989733D01*
X164500Y990025D01*
X164667Y990233D01*
X164917Y990400D01*
X165208Y990442D01*
X165458Y990400D01*
X165708Y990233D01*
X165917Y989983D01*
X166000Y989692D01*
X165917Y989358D01*
X165667Y989067D01*
X165292Y988900D01*
X164875Y988858D01*
X164333Y988942D01*
X164042Y989067D01*
X163750Y989275D01*
X163542Y989567D01*
X163500Y989858D01*
X163583Y990150D01*
X163792Y990358D01*
G01X167500Y980350D02*
X170000D01*
G01X167500Y979392D02*
Y981308D01*
G01X170000Y982617D02*
X167500D01*
Y983617D01*
X167625Y983950D01*
X167917Y984200D01*
X168250Y984283D01*
X168583Y984200D01*
X168833Y983992D01*
X168958Y983617D01*
Y982617D01*
G01X170000Y986550D02*
X167500D01*
X168000Y986050D01*
G01X170000D02*
Y987050D01*
G01X169708Y988942D02*
X169917Y989233D01*
X170000Y989567D01*
X169917Y989900D01*
X169667Y990192D01*
X169292Y990400D01*
X168917Y990483D01*
X168458D01*
X168083Y990400D01*
X167750Y990192D01*
X167583Y989942D01*
X167500Y989650D01*
X167583Y989317D01*
X167750Y989067D01*
X168000Y988900D01*
X168333Y988817D01*
X168625Y988900D01*
X168917Y989108D01*
X169083Y989358D01*
X169125Y989650D01*
X169042Y989983D01*
X168833Y990233D01*
X168458Y990483D01*
G01X159500Y980350D02*
X162000D01*
G01X159500Y979392D02*
Y981308D01*
G01X162000Y982617D02*
X159500D01*
Y983617D01*
X159625Y983950D01*
X159917Y984200D01*
X160250Y984283D01*
X160583Y984200D01*
X160833Y983992D01*
X160958Y983617D01*
Y982617D01*
G01X162000Y986550D02*
X159500D01*
X160000Y986050D01*
G01X162000D02*
Y987050D01*
G01Y989650D02*
X161958Y989942D01*
X161833Y990275D01*
X161625Y990483D01*
X161333Y990567D01*
X161042Y990483D01*
X160792Y990233D01*
X160667Y989858D01*
Y989442D01*
X160583Y989192D01*
X160375Y988983D01*
X160083Y988900D01*
X159792Y989025D01*
X159583Y989317D01*
X159500Y989650D01*
X159583Y989983D01*
X159792Y990275D01*
X160083Y990400D01*
X160375Y990317D01*
X160583Y990108D01*
X160667Y989858D01*
Y989442D01*
X160792Y989067D01*
X161042Y988817D01*
X161333Y988733D01*
X161625Y988817D01*
X161833Y989025D01*
X161958Y989358D01*
X162000Y989650D01*
G01X149900Y1005100D02*
X145900D01*
Y997700D01*
G01X154100Y1005200D02*
X150100D01*
Y997800D01*
G01X165000Y1002017D02*
X162500D01*
Y1003058D01*
X162625Y1003392D01*
X162792Y1003600D01*
X163125Y1003683D01*
X163458Y1003600D01*
X163667Y1003350D01*
X163792Y1003058D01*
Y1002017D01*
G01Y1003058D02*
X165000Y1003683D01*
G01Y1005950D02*
X162500D01*
X163000Y1005450D01*
G01X165000D02*
Y1006450D01*
G01Y1009550D02*
X162500D01*
X164292Y1008008D01*
Y1010092D01*
G01X164708Y1011442D02*
X164917Y1011733D01*
X165000Y1012067D01*
X164917Y1012400D01*
X164667Y1012692D01*
X164292Y1012900D01*
X163917Y1012983D01*
X163458D01*
X163083Y1012900D01*
X162750Y1012692D01*
X162583Y1012442D01*
X162500Y1012150D01*
X162583Y1011817D01*
X162750Y1011567D01*
X163000Y1011400D01*
X163333Y1011317D01*
X163625Y1011400D01*
X163917Y1011608D01*
X164083Y1011858D01*
X164125Y1012150D01*
X164042Y1012483D01*
X163833Y1012733D01*
X163458Y1012983D01*
G01X165500Y999700D02*
X161500D01*
Y992300D01*
G01X161000Y1002017D02*
X158500D01*
Y1003058D01*
X158625Y1003392D01*
X158792Y1003600D01*
X159125Y1003683D01*
X159458Y1003600D01*
X159667Y1003350D01*
X159792Y1003058D01*
Y1002017D01*
G01Y1003058D02*
X161000Y1003683D01*
G01Y1005950D02*
X158500D01*
X159000Y1005450D01*
G01X161000D02*
Y1006450D01*
G01X158917Y1008258D02*
X158667Y1008508D01*
X158542Y1008800D01*
X158500Y1009133D01*
X158583Y1009550D01*
X158792Y1009842D01*
X159042Y1009925D01*
X159292Y1009883D01*
X159500Y1009717D01*
X159917Y1008883D01*
X160208Y1008508D01*
X160625Y1008258D01*
X161000Y1008175D01*
Y1009925D01*
G01X160708Y1011442D02*
X160917Y1011733D01*
X161000Y1012067D01*
X160917Y1012400D01*
X160667Y1012692D01*
X160292Y1012900D01*
X159917Y1012983D01*
X159458D01*
X159083Y1012900D01*
X158750Y1012692D01*
X158583Y1012442D01*
X158500Y1012150D01*
X158583Y1011817D01*
X158750Y1011567D01*
X159000Y1011400D01*
X159333Y1011317D01*
X159625Y1011400D01*
X159917Y1011608D01*
X160083Y1011858D01*
X160125Y1012150D01*
X160042Y1012483D01*
X159833Y1012733D01*
X159458Y1012983D01*
G01X161500Y999700D02*
X157500D01*
Y992300D01*
G01X145800Y1005200D02*
X141800D01*
Y997800D01*
G01X140500Y1007517D02*
X138000D01*
Y1008558D01*
X138125Y1008892D01*
X138292Y1009100D01*
X138625Y1009183D01*
X138958Y1009100D01*
X139167Y1008850D01*
X139292Y1008558D01*
Y1007517D01*
G01Y1008558D02*
X140500Y1009183D01*
G01Y1011450D02*
X138000D01*
X138500Y1010950D01*
G01X140500D02*
Y1011950D01*
G01X138000Y1014550D02*
X138083Y1014217D01*
X138292Y1013967D01*
X138542Y1013800D01*
X138875Y1013675D01*
X139250Y1013633D01*
X139625Y1013675D01*
X139958Y1013800D01*
X140208Y1013967D01*
X140417Y1014217D01*
X140500Y1014550D01*
X140417Y1014883D01*
X140208Y1015133D01*
X139958Y1015300D01*
X139625Y1015425D01*
X139250Y1015467D01*
X138875Y1015425D01*
X138542Y1015300D01*
X138292Y1015133D01*
X138083Y1014883D01*
X138000Y1014550D01*
G01X140500Y1017567D02*
X139958Y1017650D01*
X139500Y1017775D01*
X139083Y1017942D01*
X138625Y1018150D01*
X138000Y1018483D01*
Y1016817D01*
G01X137100Y997700D02*
X141100D01*
Y1005100D01*
G01X136500Y1007517D02*
X134000D01*
Y1008558D01*
X134125Y1008892D01*
X134292Y1009100D01*
X134625Y1009183D01*
X134958Y1009100D01*
X135167Y1008850D01*
X135292Y1008558D01*
Y1007517D01*
G01Y1008558D02*
X136500Y1009183D01*
G01Y1011450D02*
X134000D01*
X134500Y1010950D01*
G01X136500D02*
Y1011950D01*
G01X134000Y1014550D02*
X134083Y1014217D01*
X134292Y1013967D01*
X134542Y1013800D01*
X134875Y1013675D01*
X135250Y1013633D01*
X135625Y1013675D01*
X135958Y1013800D01*
X136208Y1013967D01*
X136417Y1014217D01*
X136500Y1014550D01*
X136417Y1014883D01*
X136208Y1015133D01*
X135958Y1015300D01*
X135625Y1015425D01*
X135250Y1015467D01*
X134875Y1015425D01*
X134542Y1015300D01*
X134292Y1015133D01*
X134083Y1014883D01*
X134000Y1014550D01*
G01X135458Y1016858D02*
X135167Y1017150D01*
X135000Y1017400D01*
X134917Y1017733D01*
X135000Y1018025D01*
X135167Y1018233D01*
X135417Y1018400D01*
X135708Y1018442D01*
X135958Y1018400D01*
X136208Y1018233D01*
X136417Y1017983D01*
X136500Y1017692D01*
X136417Y1017358D01*
X136167Y1017067D01*
X135792Y1016900D01*
X135375Y1016858D01*
X134833Y1016942D01*
X134542Y1017067D01*
X134250Y1017275D01*
X134042Y1017567D01*
X134000Y1017858D01*
X134083Y1018150D01*
X134292Y1018358D01*
G01X133000Y997800D02*
X137000D01*
Y1005200D01*
G01X148800Y1010017D02*
X146300D01*
Y1011058D01*
X146425Y1011392D01*
X146592Y1011600D01*
X146925Y1011683D01*
X147258Y1011600D01*
X147467Y1011350D01*
X147592Y1011058D01*
Y1010017D01*
G01Y1011058D02*
X148800Y1011683D01*
G01X148425Y1013033D02*
X148633Y1013283D01*
X148758Y1013575D01*
X148800Y1013950D01*
X148717Y1014325D01*
X148550Y1014617D01*
X148258Y1014825D01*
X147925Y1014867D01*
X147592Y1014783D01*
X147383Y1014575D01*
X147217Y1014283D01*
X147175Y1013992D01*
X147217Y1013700D01*
X147383Y1013325D01*
X146300Y1013450D01*
Y1014575D01*
G01X148508Y1016342D02*
X148717Y1016633D01*
X148800Y1016967D01*
X148717Y1017300D01*
X148467Y1017592D01*
X148092Y1017800D01*
X147717Y1017883D01*
X147258D01*
X146883Y1017800D01*
X146550Y1017592D01*
X146383Y1017342D01*
X146300Y1017050D01*
X146383Y1016717D01*
X146550Y1016467D01*
X146800Y1016300D01*
X147133Y1016217D01*
X147425Y1016300D01*
X147717Y1016508D01*
X147883Y1016758D01*
X147925Y1017050D01*
X147842Y1017383D01*
X147633Y1017633D01*
X147258Y1017883D01*
G01X152800Y1010017D02*
X150300D01*
Y1011058D01*
X150425Y1011392D01*
X150592Y1011600D01*
X150925Y1011683D01*
X151258Y1011600D01*
X151467Y1011350D01*
X151592Y1011058D01*
Y1010017D01*
G01Y1011058D02*
X152800Y1011683D01*
G01X152425Y1013033D02*
X152633Y1013283D01*
X152758Y1013575D01*
X152800Y1013950D01*
X152717Y1014325D01*
X152550Y1014617D01*
X152258Y1014825D01*
X151925Y1014867D01*
X151592Y1014783D01*
X151383Y1014575D01*
X151217Y1014283D01*
X151175Y1013992D01*
X151217Y1013700D01*
X151383Y1013325D01*
X150300Y1013450D01*
Y1014575D01*
G01X152800Y1017050D02*
X152758Y1017342D01*
X152633Y1017675D01*
X152425Y1017883D01*
X152133Y1017967D01*
X151842Y1017883D01*
X151592Y1017633D01*
X151467Y1017258D01*
Y1016842D01*
X151383Y1016592D01*
X151175Y1016383D01*
X150883Y1016300D01*
X150592Y1016425D01*
X150383Y1016717D01*
X150300Y1017050D01*
X150383Y1017383D01*
X150592Y1017675D01*
X150883Y1017800D01*
X151175Y1017717D01*
X151383Y1017508D01*
X151467Y1017258D01*
Y1016842D01*
X151592Y1016467D01*
X151842Y1016217D01*
X152133Y1016133D01*
X152425Y1016217D01*
X152633Y1016425D01*
X152758Y1016758D01*
X152800Y1017050D01*
G01X144800Y1010017D02*
X142300D01*
Y1011058D01*
X142425Y1011392D01*
X142592Y1011600D01*
X142925Y1011683D01*
X143258Y1011600D01*
X143467Y1011350D01*
X143592Y1011058D01*
Y1010017D01*
G01Y1011058D02*
X144800Y1011683D01*
G01Y1014450D02*
X142300D01*
X144092Y1012908D01*
Y1014992D01*
G01X144800Y1017050D02*
X144758Y1017342D01*
X144633Y1017675D01*
X144425Y1017883D01*
X144133Y1017967D01*
X143842Y1017883D01*
X143592Y1017633D01*
X143467Y1017258D01*
Y1016842D01*
X143383Y1016592D01*
X143175Y1016383D01*
X142883Y1016300D01*
X142592Y1016425D01*
X142383Y1016717D01*
X142300Y1017050D01*
X142383Y1017383D01*
X142592Y1017675D01*
X142883Y1017800D01*
X143175Y1017717D01*
X143383Y1017508D01*
X143467Y1017258D01*
Y1016842D01*
X143592Y1016467D01*
X143842Y1016217D01*
X144133Y1016133D01*
X144425Y1016217D01*
X144633Y1016425D01*
X144758Y1016758D01*
X144800Y1017050D01*
G01X134208Y1111317D02*
X134083Y1111067D01*
X134000Y1110775D01*
Y1110442D01*
X134125Y1110067D01*
X134333Y1109775D01*
X134583Y1109567D01*
X135000Y1109400D01*
X135375Y1109358D01*
X135750Y1109442D01*
X136000Y1109567D01*
X136250Y1109817D01*
X136417Y1110108D01*
X136500Y1110400D01*
Y1110692D01*
X136417Y1110983D01*
X136292Y1111233D01*
X136125Y1111442D01*
G01X136500Y1114000D02*
X134000D01*
X135792Y1112458D01*
Y1114542D01*
G01X136500Y1116600D02*
X136458Y1116892D01*
X136333Y1117225D01*
X136125Y1117433D01*
X135833Y1117517D01*
X135542Y1117433D01*
X135292Y1117183D01*
X135167Y1116808D01*
Y1116392D01*
X135083Y1116142D01*
X134875Y1115933D01*
X134583Y1115850D01*
X134292Y1115975D01*
X134083Y1116267D01*
X134000Y1116600D01*
X134083Y1116933D01*
X134292Y1117225D01*
X134583Y1117350D01*
X134875Y1117267D01*
X135083Y1117058D01*
X135167Y1116808D01*
Y1116392D01*
X135292Y1116017D01*
X135542Y1115767D01*
X135833Y1115683D01*
X136125Y1115767D01*
X136333Y1115975D01*
X136458Y1116308D01*
X136500Y1116600D01*
G01X138208Y1111317D02*
X138083Y1111067D01*
X138000Y1110775D01*
Y1110442D01*
X138125Y1110067D01*
X138333Y1109775D01*
X138583Y1109567D01*
X139000Y1109400D01*
X139375Y1109358D01*
X139750Y1109442D01*
X140000Y1109567D01*
X140250Y1109817D01*
X140417Y1110108D01*
X140500Y1110400D01*
Y1110692D01*
X140417Y1110983D01*
X140292Y1111233D01*
X140125Y1111442D01*
G01X140500Y1114000D02*
X138000D01*
X139792Y1112458D01*
Y1114542D01*
G01X140500Y1116517D02*
X139958Y1116600D01*
X139500Y1116725D01*
X139083Y1116892D01*
X138625Y1117100D01*
X138000Y1117433D01*
Y1115767D01*
G01X133597Y1158098D02*
Y1119298D01*
G01X141350Y1162500D02*
Y1160000D01*
G01X140392Y1162500D02*
X142308D01*
G01X145367Y1162292D02*
X145117Y1162417D01*
X144825Y1162500D01*
X144492D01*
X144117Y1162375D01*
X143825Y1162167D01*
X143617Y1161917D01*
X143450Y1161500D01*
X143408Y1161125D01*
X143492Y1160750D01*
X143617Y1160500D01*
X143867Y1160250D01*
X144158Y1160083D01*
X144450Y1160000D01*
X144742D01*
X145033Y1160083D01*
X145283Y1160208D01*
X145492Y1160375D01*
G01X147550Y1160000D02*
Y1162500D01*
X147050Y1162000D01*
G01Y1160000D02*
X148050D01*
G01X150567D02*
X150650Y1160542D01*
X150775Y1161000D01*
X150942Y1161417D01*
X151150Y1161875D01*
X151483Y1162500D01*
X149817D01*
G01X154798Y1119703D02*
Y1130903D01*
G01X136798Y1119703D02*
X154798D01*
G01X136798Y1130903D02*
Y1119703D01*
G01X154798Y1158103D02*
Y1146903D01*
G01X136798Y1158103D02*
X154798D01*
G01X136798Y1146903D02*
Y1158103D01*
G01X176709Y1181417D02*
Y1183917D01*
G01X178459D02*
Y1181417D01*
G01Y1182667D02*
X176709D01*
G01X179892Y1182459D02*
X180184Y1182750D01*
X180434Y1182917D01*
X180767Y1183000D01*
X181059Y1182917D01*
X181267Y1182750D01*
X181434Y1182500D01*
X181476Y1182209D01*
X181434Y1181959D01*
X181267Y1181709D01*
X181017Y1181500D01*
X180726Y1181417D01*
X180392Y1181500D01*
X180101Y1181750D01*
X179934Y1182125D01*
X179892Y1182542D01*
X179976Y1183084D01*
X180101Y1183375D01*
X180309Y1183667D01*
X180601Y1183875D01*
X180892Y1183917D01*
X181184Y1183834D01*
X181392Y1183625D01*
G01X165500Y1354067D02*
X165750Y1354275D01*
X165917Y1354525D01*
X166000Y1354817D01*
X165917Y1355150D01*
X165750Y1355400D01*
X165500Y1355650D01*
X165167Y1355733D01*
X163500D01*
G01X166000Y1357167D02*
X163500D01*
Y1358167D01*
X163625Y1358500D01*
X163917Y1358750D01*
X164250Y1358833D01*
X164583Y1358750D01*
X164833Y1358542D01*
X164958Y1358167D01*
Y1357167D01*
G01X166000Y1361100D02*
X163500D01*
X164000Y1360600D01*
G01X166000D02*
Y1361600D01*
G01X170900Y1365000D02*
Y1396000D01*
X159100D01*
Y1365000D01*
X170900D01*
G01X138996Y1388300D02*
X133496D01*
G01X138996Y1396300D02*
Y1388300D01*
G01X133496Y1396300D02*
X138996D01*
G01X142767Y1375292D02*
X142517Y1375417D01*
X142225Y1375500D01*
X141892D01*
X141517Y1375375D01*
X141225Y1375167D01*
X141017Y1374917D01*
X140850Y1374500D01*
X140808Y1374125D01*
X140892Y1373750D01*
X141017Y1373500D01*
X141267Y1373250D01*
X141558Y1373083D01*
X141850Y1373000D01*
X142142D01*
X142433Y1373083D01*
X142683Y1373208D01*
X142892Y1373375D01*
G01X144158Y1375083D02*
X144408Y1375333D01*
X144700Y1375458D01*
X145033Y1375500D01*
X145450Y1375417D01*
X145742Y1375208D01*
X145825Y1374958D01*
X145783Y1374708D01*
X145617Y1374500D01*
X144783Y1374083D01*
X144408Y1373792D01*
X144158Y1373375D01*
X144075Y1373000D01*
X145825D01*
G01X147258Y1374042D02*
X147550Y1374333D01*
X147800Y1374500D01*
X148133Y1374583D01*
X148425Y1374500D01*
X148633Y1374333D01*
X148800Y1374083D01*
X148842Y1373792D01*
X148800Y1373542D01*
X148633Y1373292D01*
X148383Y1373083D01*
X148092Y1373000D01*
X147758Y1373083D01*
X147467Y1373333D01*
X147300Y1373708D01*
X147258Y1374125D01*
X147342Y1374667D01*
X147467Y1374958D01*
X147675Y1375250D01*
X147967Y1375458D01*
X148258Y1375500D01*
X148550Y1375417D01*
X148758Y1375208D01*
G01X151150Y1373000D02*
Y1375500D01*
X150650Y1375000D01*
G01Y1373000D02*
X151650D01*
G01X139700Y1391500D02*
X145200D01*
G01X139700Y1383500D02*
Y1391500D01*
G01X145200Y1383500D02*
X139700D01*
G01X157300D02*
X151800D01*
G01X157300Y1391500D02*
Y1383500D01*
G01X151800Y1391500D02*
X157300D01*
G01X162017Y1418000D02*
Y1420500D01*
X163017D01*
X163350Y1420375D01*
X163600Y1420083D01*
X163683Y1419750D01*
X163600Y1419417D01*
X163392Y1419167D01*
X163017Y1419042D01*
X162017D01*
G01X165117Y1418000D02*
Y1420500D01*
X166158D01*
X166492Y1420375D01*
X166700Y1420208D01*
X166783Y1419875D01*
X166700Y1419542D01*
X166450Y1419333D01*
X166158Y1419208D01*
X165117D01*
G01X166158D02*
X166783Y1418000D01*
G01X169550D02*
Y1420500D01*
X168008Y1418708D01*
X170092D01*
G01X171358Y1419042D02*
X171650Y1419333D01*
X171900Y1419500D01*
X172233Y1419583D01*
X172525Y1419500D01*
X172733Y1419333D01*
X172900Y1419083D01*
X172942Y1418792D01*
X172900Y1418542D01*
X172733Y1418292D01*
X172483Y1418083D01*
X172192Y1418000D01*
X171858Y1418083D01*
X171567Y1418333D01*
X171400Y1418708D01*
X171358Y1419125D01*
X171442Y1419667D01*
X171567Y1419958D01*
X171775Y1420250D01*
X172067Y1420458D01*
X172358Y1420500D01*
X172650Y1420417D01*
X172858Y1420208D01*
G01X162500Y1398017D02*
X160000D01*
Y1399058D01*
X160125Y1399392D01*
X160292Y1399600D01*
X160625Y1399683D01*
X160958Y1399600D01*
X161167Y1399350D01*
X161292Y1399058D01*
Y1398017D01*
G01Y1399058D02*
X162500Y1399683D01*
G01X162000Y1401033D02*
X162292Y1401283D01*
X162458Y1401617D01*
X162500Y1401992D01*
X162458Y1402325D01*
X162250Y1402658D01*
X162000Y1402867D01*
X161750Y1402908D01*
X161458Y1402825D01*
X161250Y1402533D01*
X161167Y1402242D01*
Y1401867D01*
G01Y1402242D02*
X161042Y1402492D01*
X160833Y1402700D01*
X160583Y1402783D01*
X160333Y1402700D01*
X160125Y1402492D01*
X160000Y1402117D01*
X160042Y1401742D01*
X160208Y1401367D01*
G01X161458Y1404258D02*
X161167Y1404550D01*
X161000Y1404800D01*
X160917Y1405133D01*
X161000Y1405425D01*
X161167Y1405633D01*
X161417Y1405800D01*
X161708Y1405842D01*
X161958Y1405800D01*
X162208Y1405633D01*
X162417Y1405383D01*
X162500Y1405092D01*
X162417Y1404758D01*
X162167Y1404467D01*
X161792Y1404300D01*
X161375Y1404258D01*
X160833Y1404342D01*
X160542Y1404467D01*
X160250Y1404675D01*
X160042Y1404967D01*
X160000Y1405258D01*
X160083Y1405550D01*
X160292Y1405758D01*
G01X162500Y1408650D02*
X160000D01*
X161792Y1407108D01*
Y1409192D01*
G01X137000Y1413804D02*
X133000D01*
Y1406404D01*
G01X166500Y1398017D02*
X164000D01*
Y1399058D01*
X164125Y1399392D01*
X164292Y1399600D01*
X164625Y1399683D01*
X164958Y1399600D01*
X165167Y1399350D01*
X165292Y1399058D01*
Y1398017D01*
G01Y1399058D02*
X166500Y1399683D01*
G01X166000Y1401033D02*
X166292Y1401283D01*
X166458Y1401617D01*
X166500Y1401992D01*
X166458Y1402325D01*
X166250Y1402658D01*
X166000Y1402867D01*
X165750Y1402908D01*
X165458Y1402825D01*
X165250Y1402533D01*
X165167Y1402242D01*
Y1401867D01*
G01Y1402242D02*
X165042Y1402492D01*
X164833Y1402700D01*
X164583Y1402783D01*
X164333Y1402700D01*
X164125Y1402492D01*
X164000Y1402117D01*
X164042Y1401742D01*
X164208Y1401367D01*
G01X165458Y1404258D02*
X165167Y1404550D01*
X165000Y1404800D01*
X164917Y1405133D01*
X165000Y1405425D01*
X165167Y1405633D01*
X165417Y1405800D01*
X165708Y1405842D01*
X165958Y1405800D01*
X166208Y1405633D01*
X166417Y1405383D01*
X166500Y1405092D01*
X166417Y1404758D01*
X166167Y1404467D01*
X165792Y1404300D01*
X165375Y1404258D01*
X164833Y1404342D01*
X164542Y1404467D01*
X164250Y1404675D01*
X164042Y1404967D01*
X164000Y1405258D01*
X164083Y1405550D01*
X164292Y1405758D01*
G01X166125Y1407233D02*
X166333Y1407483D01*
X166458Y1407775D01*
X166500Y1408150D01*
X166417Y1408525D01*
X166250Y1408817D01*
X165958Y1409025D01*
X165625Y1409067D01*
X165292Y1408983D01*
X165083Y1408775D01*
X164917Y1408483D01*
X164875Y1408192D01*
X164917Y1407900D01*
X165083Y1407525D01*
X164000Y1407650D01*
Y1408775D01*
G01X136700Y1406004D02*
X132700D01*
Y1398604D01*
G01X144517Y1379000D02*
Y1381500D01*
X145558D01*
X145892Y1381375D01*
X146100Y1381208D01*
X146183Y1380875D01*
X146100Y1380542D01*
X145850Y1380333D01*
X145558Y1380208D01*
X144517D01*
G01X145558D02*
X146183Y1379000D01*
G01X147533Y1379500D02*
X147783Y1379208D01*
X148117Y1379042D01*
X148492Y1379000D01*
X148825Y1379042D01*
X149158Y1379250D01*
X149367Y1379500D01*
X149408Y1379750D01*
X149325Y1380042D01*
X149033Y1380250D01*
X148742Y1380333D01*
X148367D01*
G01X148742D02*
X148992Y1380458D01*
X149200Y1380667D01*
X149283Y1380917D01*
X149200Y1381167D01*
X148992Y1381375D01*
X148617Y1381500D01*
X148242Y1381458D01*
X147867Y1381292D01*
G01X150758Y1380042D02*
X151050Y1380333D01*
X151300Y1380500D01*
X151633Y1380583D01*
X151925Y1380500D01*
X152133Y1380333D01*
X152300Y1380083D01*
X152342Y1379792D01*
X152300Y1379542D01*
X152133Y1379292D01*
X151883Y1379083D01*
X151592Y1379000D01*
X151258Y1379083D01*
X150967Y1379333D01*
X150800Y1379708D01*
X150758Y1380125D01*
X150842Y1380667D01*
X150967Y1380958D01*
X151175Y1381250D01*
X151467Y1381458D01*
X151758Y1381500D01*
X152050Y1381417D01*
X152258Y1381208D01*
G01X153733Y1379500D02*
X153983Y1379208D01*
X154317Y1379042D01*
X154692Y1379000D01*
X155025Y1379042D01*
X155358Y1379250D01*
X155567Y1379500D01*
X155608Y1379750D01*
X155525Y1380042D01*
X155233Y1380250D01*
X154942Y1380333D01*
X154567D01*
G01X154942D02*
X155192Y1380458D01*
X155400Y1380667D01*
X155483Y1380917D01*
X155400Y1381167D01*
X155192Y1381375D01*
X154817Y1381500D01*
X154442Y1381458D01*
X154067Y1381292D01*
G01X153404Y1392000D02*
Y1396000D01*
X146004D01*
G01X162017Y1414500D02*
Y1417000D01*
X163017D01*
X163350Y1416875D01*
X163600Y1416583D01*
X163683Y1416250D01*
X163600Y1415917D01*
X163392Y1415667D01*
X163017Y1415542D01*
X162017D01*
G01X165117Y1414500D02*
Y1417000D01*
X166158D01*
X166492Y1416875D01*
X166700Y1416708D01*
X166783Y1416375D01*
X166700Y1416042D01*
X166450Y1415833D01*
X166158Y1415708D01*
X165117D01*
G01X166158D02*
X166783Y1414500D01*
G01X168133Y1414875D02*
X168383Y1414667D01*
X168675Y1414542D01*
X169050Y1414500D01*
X169425Y1414583D01*
X169717Y1414750D01*
X169925Y1415042D01*
X169967Y1415375D01*
X169883Y1415708D01*
X169675Y1415917D01*
X169383Y1416083D01*
X169092Y1416125D01*
X168800Y1416083D01*
X168425Y1415917D01*
X168550Y1417000D01*
X169675D01*
G01X171442Y1414792D02*
X171733Y1414583D01*
X172067Y1414500D01*
X172400Y1414583D01*
X172692Y1414833D01*
X172900Y1415208D01*
X172983Y1415583D01*
Y1416042D01*
X172900Y1416417D01*
X172692Y1416750D01*
X172442Y1416917D01*
X172150Y1417000D01*
X171817Y1416917D01*
X171567Y1416750D01*
X171400Y1416500D01*
X171317Y1416167D01*
X171400Y1415875D01*
X171608Y1415583D01*
X171858Y1415417D01*
X172150Y1415375D01*
X172483Y1415458D01*
X172733Y1415667D01*
X172983Y1416042D01*
G01X150096Y1421200D02*
Y1417200D01*
X157496D01*
G01X162017Y1411000D02*
Y1413500D01*
X163017D01*
X163350Y1413375D01*
X163600Y1413083D01*
X163683Y1412750D01*
X163600Y1412417D01*
X163392Y1412167D01*
X163017Y1412042D01*
X162017D01*
G01X165117Y1411000D02*
Y1413500D01*
X166158D01*
X166492Y1413375D01*
X166700Y1413208D01*
X166783Y1412875D01*
X166700Y1412542D01*
X166450Y1412333D01*
X166158Y1412208D01*
X165117D01*
G01X166158D02*
X166783Y1411000D01*
G01X168133Y1411375D02*
X168383Y1411167D01*
X168675Y1411042D01*
X169050Y1411000D01*
X169425Y1411083D01*
X169717Y1411250D01*
X169925Y1411542D01*
X169967Y1411875D01*
X169883Y1412208D01*
X169675Y1412417D01*
X169383Y1412583D01*
X169092Y1412625D01*
X168800Y1412583D01*
X168425Y1412417D01*
X168550Y1413500D01*
X169675D01*
G01X172150Y1411000D02*
X172442Y1411042D01*
X172775Y1411167D01*
X172983Y1411375D01*
X173067Y1411667D01*
X172983Y1411958D01*
X172733Y1412208D01*
X172358Y1412333D01*
X171942D01*
X171692Y1412417D01*
X171483Y1412625D01*
X171400Y1412917D01*
X171525Y1413208D01*
X171817Y1413417D01*
X172150Y1413500D01*
X172483Y1413417D01*
X172775Y1413208D01*
X172900Y1412917D01*
X172817Y1412625D01*
X172608Y1412417D01*
X172358Y1412333D01*
X171942D01*
X171567Y1412208D01*
X171317Y1411958D01*
X171233Y1411667D01*
X171317Y1411375D01*
X171525Y1411167D01*
X171858Y1411042D01*
X172150Y1411000D01*
G01X150096Y1417000D02*
Y1413000D01*
X157496D01*
G01X174500Y1398017D02*
X172000D01*
Y1399017D01*
X172125Y1399350D01*
X172417Y1399600D01*
X172750Y1399683D01*
X173083Y1399600D01*
X173333Y1399392D01*
X173458Y1399017D01*
Y1398017D01*
G01X174500Y1401950D02*
X174458Y1401617D01*
X174292Y1401325D01*
X174042Y1401075D01*
X173750Y1400908D01*
X173417Y1400825D01*
X173083D01*
X172750Y1400908D01*
X172458Y1401075D01*
X172208Y1401325D01*
X172042Y1401617D01*
X172000Y1401950D01*
X172042Y1402283D01*
X172208Y1402575D01*
X172458Y1402825D01*
X172750Y1402992D01*
X173083Y1403075D01*
X173417D01*
X173750Y1402992D01*
X174042Y1402825D01*
X174292Y1402575D01*
X174458Y1402283D01*
X174500Y1401950D01*
G01X173833Y1402283D02*
X174500Y1402783D01*
G01Y1405050D02*
X172000D01*
X172500Y1404550D01*
G01X174500D02*
Y1405550D01*
G01Y1408650D02*
X172000D01*
X173792Y1407108D01*
Y1409192D01*
G01X145400Y1412204D02*
Y1398204D01*
G01X158400Y1412204D02*
X145400D01*
G01X158400Y1398204D02*
Y1412204D01*
G01X145400Y1398204D02*
X158400D01*
G01X170500Y1397983D02*
X168000D01*
Y1398817D01*
X168125Y1399150D01*
X168292Y1399400D01*
X168542Y1399608D01*
X168833Y1399775D01*
X169250Y1399817D01*
X169667Y1399775D01*
X169958Y1399608D01*
X170208Y1399400D01*
X170375Y1399150D01*
X170500Y1398817D01*
Y1397983D01*
G01Y1402000D02*
X168000D01*
X168500Y1401500D01*
G01X170500D02*
Y1402500D01*
G01X170208Y1404392D02*
X170417Y1404683D01*
X170500Y1405017D01*
X170417Y1405350D01*
X170167Y1405642D01*
X169792Y1405850D01*
X169417Y1405933D01*
X168958D01*
X168583Y1405850D01*
X168250Y1405642D01*
X168083Y1405392D01*
X168000Y1405100D01*
X168083Y1404767D01*
X168250Y1404517D01*
X168500Y1404350D01*
X168833Y1404267D01*
X169125Y1404350D01*
X169417Y1404558D01*
X169583Y1404808D01*
X169625Y1405100D01*
X169542Y1405433D01*
X169333Y1405683D01*
X168958Y1405933D01*
G01X137900Y1413296D02*
Y1398496D01*
G01X144300Y1413296D02*
X137900D01*
G01X144300Y1398496D02*
Y1413296D01*
G01X137900Y1398496D02*
X144300D01*
G01X184500Y1436567D02*
X182000D01*
Y1437567D01*
X182125Y1437900D01*
X182417Y1438150D01*
X182750Y1438233D01*
X183083Y1438150D01*
X183333Y1437942D01*
X183458Y1437567D01*
Y1436567D01*
G01X184500Y1440500D02*
X184458Y1440167D01*
X184292Y1439875D01*
X184042Y1439625D01*
X183750Y1439458D01*
X183417Y1439375D01*
X183083D01*
X182750Y1439458D01*
X182458Y1439625D01*
X182208Y1439875D01*
X182042Y1440167D01*
X182000Y1440500D01*
X182042Y1440833D01*
X182208Y1441125D01*
X182458Y1441375D01*
X182750Y1441542D01*
X183083Y1441625D01*
X183417D01*
X183750Y1441542D01*
X184042Y1441375D01*
X184292Y1441125D01*
X184458Y1440833D01*
X184500Y1440500D01*
G01X183833Y1440833D02*
X184500Y1441333D01*
G01Y1444100D02*
X182000D01*
X183792Y1442558D01*
Y1444642D01*
G01X154000Y1434000D02*
Y1448000D01*
G01X141000Y1434000D02*
X154000D01*
G01X141000Y1448000D02*
Y1434000D01*
G01X154000Y1448000D02*
X141000D01*
G01X170500Y1468200D02*
Y1463000D01*
G01X163500Y1468200D02*
Y1460400D01*
G01X170500Y1468200D02*
X163500D01*
G01X170500Y1454800D02*
Y1463500D01*
G01X163500Y1454800D02*
X170500D01*
G01X163500Y1461200D02*
Y1454800D01*
G01X179000Y1422017D02*
X176500D01*
Y1423017D01*
X176625Y1423350D01*
X176917Y1423600D01*
X177250Y1423683D01*
X177583Y1423600D01*
X177833Y1423392D01*
X177958Y1423017D01*
Y1422017D01*
G01X179000Y1425117D02*
X176500D01*
Y1426158D01*
X176625Y1426492D01*
X176792Y1426700D01*
X177125Y1426783D01*
X177458Y1426700D01*
X177667Y1426450D01*
X177792Y1426158D01*
Y1425117D01*
G01Y1426158D02*
X179000Y1426783D01*
G01Y1429550D02*
X176500D01*
X178292Y1428008D01*
Y1430092D01*
G01X176917Y1431358D02*
X176667Y1431608D01*
X176542Y1431900D01*
X176500Y1432233D01*
X176583Y1432650D01*
X176792Y1432942D01*
X177042Y1433025D01*
X177292Y1432983D01*
X177500Y1432817D01*
X177917Y1431983D01*
X178208Y1431608D01*
X178625Y1431358D01*
X179000Y1431275D01*
Y1433025D01*
G01X154631Y1425681D02*
X158631D01*
Y1433081D01*
G01X182500Y1422017D02*
X180000D01*
Y1423017D01*
X180125Y1423350D01*
X180417Y1423600D01*
X180750Y1423683D01*
X181083Y1423600D01*
X181333Y1423392D01*
X181458Y1423017D01*
Y1422017D01*
G01X182500Y1425117D02*
X180000D01*
Y1426158D01*
X180125Y1426492D01*
X180292Y1426700D01*
X180625Y1426783D01*
X180958Y1426700D01*
X181167Y1426450D01*
X181292Y1426158D01*
Y1425117D01*
G01Y1426158D02*
X182500Y1426783D01*
G01Y1429550D02*
X180000D01*
X181792Y1428008D01*
Y1430092D01*
G01X182500Y1432150D02*
X180000D01*
X180500Y1431650D01*
G01X182500D02*
Y1432650D01*
G01X158831Y1424881D02*
X162831D01*
Y1432281D01*
G01X175500Y1422017D02*
X173000D01*
Y1423017D01*
X173125Y1423350D01*
X173417Y1423600D01*
X173750Y1423683D01*
X174083Y1423600D01*
X174333Y1423392D01*
X174458Y1423017D01*
Y1422017D01*
G01X175500Y1425117D02*
X173000D01*
Y1426158D01*
X173125Y1426492D01*
X173292Y1426700D01*
X173625Y1426783D01*
X173958Y1426700D01*
X174167Y1426450D01*
X174292Y1426158D01*
Y1425117D01*
G01Y1426158D02*
X175500Y1426783D01*
G01Y1429550D02*
X173000D01*
X174792Y1428008D01*
Y1430092D01*
G01X173000Y1432150D02*
X173083Y1431817D01*
X173292Y1431567D01*
X173542Y1431400D01*
X173875Y1431275D01*
X174250Y1431233D01*
X174625Y1431275D01*
X174958Y1431400D01*
X175208Y1431567D01*
X175417Y1431817D01*
X175500Y1432150D01*
X175417Y1432483D01*
X175208Y1432733D01*
X174958Y1432900D01*
X174625Y1433025D01*
X174250Y1433067D01*
X173875Y1433025D01*
X173542Y1432900D01*
X173292Y1432733D01*
X173083Y1432483D01*
X173000Y1432150D01*
G01X150331Y1425681D02*
X154331D01*
Y1433081D01*
G01X180500Y1436517D02*
X178000D01*
Y1437517D01*
X178125Y1437850D01*
X178417Y1438100D01*
X178750Y1438183D01*
X179083Y1438100D01*
X179333Y1437892D01*
X179458Y1437517D01*
Y1436517D01*
G01X180500Y1439617D02*
X178000D01*
Y1440658D01*
X178125Y1440992D01*
X178292Y1441200D01*
X178625Y1441283D01*
X178958Y1441200D01*
X179167Y1440950D01*
X179292Y1440658D01*
Y1439617D01*
G01Y1440658D02*
X180500Y1441283D01*
G01X180000Y1442633D02*
X180292Y1442883D01*
X180458Y1443217D01*
X180500Y1443592D01*
X180458Y1443925D01*
X180250Y1444258D01*
X180000Y1444467D01*
X179750Y1444508D01*
X179458Y1444425D01*
X179250Y1444133D01*
X179167Y1443842D01*
Y1443467D01*
G01Y1443842D02*
X179042Y1444092D01*
X178833Y1444300D01*
X178583Y1444383D01*
X178333Y1444300D01*
X178125Y1444092D01*
X178000Y1443717D01*
X178042Y1443342D01*
X178208Y1442967D01*
G01X180500Y1446650D02*
X180458Y1446942D01*
X180333Y1447275D01*
X180125Y1447483D01*
X179833Y1447567D01*
X179542Y1447483D01*
X179292Y1447233D01*
X179167Y1446858D01*
Y1446442D01*
X179083Y1446192D01*
X178875Y1445983D01*
X178583Y1445900D01*
X178292Y1446025D01*
X178083Y1446317D01*
X178000Y1446650D01*
X178083Y1446983D01*
X178292Y1447275D01*
X178583Y1447400D01*
X178875Y1447317D01*
X179083Y1447108D01*
X179167Y1446858D01*
Y1446442D01*
X179292Y1446067D01*
X179542Y1445817D01*
X179833Y1445733D01*
X180125Y1445817D01*
X180333Y1446025D01*
X180458Y1446358D01*
X180500Y1446650D01*
G01X139500Y1445700D02*
X135500D01*
Y1438300D01*
G01X174167Y1457200D02*
Y1459700D01*
X175167D01*
X175500Y1459575D01*
X175750Y1459283D01*
X175833Y1458950D01*
X175750Y1458617D01*
X175542Y1458367D01*
X175167Y1458242D01*
X174167D01*
G01X177267Y1457200D02*
Y1459700D01*
X178308D01*
X178642Y1459575D01*
X178850Y1459408D01*
X178933Y1459075D01*
X178850Y1458742D01*
X178600Y1458533D01*
X178308Y1458408D01*
X177267D01*
G01X178308D02*
X178933Y1457200D01*
G01X181200D02*
X181492Y1457242D01*
X181825Y1457367D01*
X182033Y1457575D01*
X182117Y1457867D01*
X182033Y1458158D01*
X181783Y1458408D01*
X181408Y1458533D01*
X180992D01*
X180742Y1458617D01*
X180533Y1458825D01*
X180450Y1459117D01*
X180575Y1459408D01*
X180867Y1459617D01*
X181200Y1459700D01*
X181533Y1459617D01*
X181825Y1459408D01*
X181950Y1459117D01*
X181867Y1458825D01*
X181658Y1458617D01*
X181408Y1458533D01*
X180992D01*
X180617Y1458408D01*
X180367Y1458158D01*
X180283Y1457867D01*
X180367Y1457575D01*
X180575Y1457367D01*
X180908Y1457242D01*
X181200Y1457200D01*
G01X138500Y1460400D02*
Y1456400D01*
X145900D01*
G01X174167Y1465200D02*
Y1467700D01*
X175167D01*
X175500Y1467575D01*
X175750Y1467283D01*
X175833Y1466950D01*
X175750Y1466617D01*
X175542Y1466367D01*
X175167Y1466242D01*
X174167D01*
G01X177267Y1465200D02*
Y1467700D01*
X178308D01*
X178642Y1467575D01*
X178850Y1467408D01*
X178933Y1467075D01*
X178850Y1466742D01*
X178600Y1466533D01*
X178308Y1466408D01*
X177267D01*
G01X178308D02*
X178933Y1465200D01*
G01X181117D02*
X181200Y1465742D01*
X181325Y1466200D01*
X181492Y1466617D01*
X181700Y1467075D01*
X182033Y1467700D01*
X180367D01*
G01X145900Y1464400D02*
Y1468400D01*
X138500D01*
G01X174167Y1461200D02*
Y1463700D01*
X175167D01*
X175500Y1463575D01*
X175750Y1463283D01*
X175833Y1462950D01*
X175750Y1462617D01*
X175542Y1462367D01*
X175167Y1462242D01*
X174167D01*
G01X177267Y1461200D02*
Y1463700D01*
X178308D01*
X178642Y1463575D01*
X178850Y1463408D01*
X178933Y1463075D01*
X178850Y1462742D01*
X178600Y1462533D01*
X178308Y1462408D01*
X177267D01*
G01X178308D02*
X178933Y1461200D01*
G01X180408Y1462242D02*
X180700Y1462533D01*
X180950Y1462700D01*
X181283Y1462783D01*
X181575Y1462700D01*
X181783Y1462533D01*
X181950Y1462283D01*
X181992Y1461992D01*
X181950Y1461742D01*
X181783Y1461492D01*
X181533Y1461283D01*
X181242Y1461200D01*
X180908Y1461283D01*
X180617Y1461533D01*
X180450Y1461908D01*
X180408Y1462325D01*
X180492Y1462867D01*
X180617Y1463158D01*
X180825Y1463450D01*
X181117Y1463658D01*
X181408Y1463700D01*
X181700Y1463617D01*
X181908Y1463408D01*
G01X145900Y1460400D02*
Y1464400D01*
X138500D01*
G01X173867Y1452100D02*
Y1454600D01*
X174867D01*
X175200Y1454475D01*
X175450Y1454183D01*
X175533Y1453850D01*
X175450Y1453517D01*
X175242Y1453267D01*
X174867Y1453142D01*
X173867D01*
G01X176967Y1452100D02*
Y1454600D01*
X178008D01*
X178342Y1454475D01*
X178550Y1454308D01*
X178633Y1453975D01*
X178550Y1453642D01*
X178300Y1453433D01*
X178008Y1453308D01*
X176967D01*
G01X178008D02*
X178633Y1452100D01*
G01X181400D02*
Y1454600D01*
X179858Y1452808D01*
X181942D01*
G01X145600Y1451300D02*
Y1455300D01*
X138200D01*
G01X155000Y1468017D02*
X152500D01*
Y1469017D01*
X152625Y1469350D01*
X152917Y1469600D01*
X153250Y1469683D01*
X153583Y1469600D01*
X153833Y1469392D01*
X153958Y1469017D01*
Y1468017D01*
G01X155000Y1471117D02*
X152500D01*
Y1472158D01*
X152625Y1472492D01*
X152792Y1472700D01*
X153125Y1472783D01*
X153458Y1472700D01*
X153667Y1472450D01*
X153792Y1472158D01*
Y1471117D01*
G01Y1472158D02*
X155000Y1472783D01*
G01X152917Y1474258D02*
X152667Y1474508D01*
X152542Y1474800D01*
X152500Y1475133D01*
X152583Y1475550D01*
X152792Y1475842D01*
X153042Y1475925D01*
X153292Y1475883D01*
X153500Y1475717D01*
X153917Y1474883D01*
X154208Y1474508D01*
X154625Y1474258D01*
X155000Y1474175D01*
Y1475925D01*
G01X154625Y1477233D02*
X154833Y1477483D01*
X154958Y1477775D01*
X155000Y1478150D01*
X154917Y1478525D01*
X154750Y1478817D01*
X154458Y1479025D01*
X154125Y1479067D01*
X153792Y1478983D01*
X153583Y1478775D01*
X153417Y1478483D01*
X153375Y1478192D01*
X153417Y1477900D01*
X153583Y1477525D01*
X152500Y1477650D01*
Y1478775D01*
G01X150100Y1425400D02*
Y1421400D01*
X157500D01*
G01X162700Y1456000D02*
Y1460000D01*
X155300D01*
G01X163400Y1424800D02*
X167400D01*
Y1432200D01*
G01X162869Y1448219D02*
Y1434219D01*
G01X175869Y1448219D02*
X162869D01*
G01X175869Y1434219D02*
Y1448219D01*
G01X162869Y1434219D02*
X175869D01*
G01X171500Y1422067D02*
X169000D01*
Y1423067D01*
X169125Y1423400D01*
X169417Y1423650D01*
X169750Y1423733D01*
X170083Y1423650D01*
X170333Y1423442D01*
X170458Y1423067D01*
Y1422067D01*
G01X171500Y1426000D02*
X171458Y1425667D01*
X171292Y1425375D01*
X171042Y1425125D01*
X170750Y1424958D01*
X170417Y1424875D01*
X170083D01*
X169750Y1424958D01*
X169458Y1425125D01*
X169208Y1425375D01*
X169042Y1425667D01*
X169000Y1426000D01*
X169042Y1426333D01*
X169208Y1426625D01*
X169458Y1426875D01*
X169750Y1427042D01*
X170083Y1427125D01*
X170417D01*
X170750Y1427042D01*
X171042Y1426875D01*
X171292Y1426625D01*
X171458Y1426333D01*
X171500Y1426000D01*
G01X170833Y1426333D02*
X171500Y1426833D01*
G01X171125Y1428183D02*
X171333Y1428433D01*
X171458Y1428725D01*
X171500Y1429100D01*
X171417Y1429475D01*
X171250Y1429767D01*
X170958Y1429975D01*
X170625Y1430017D01*
X170292Y1429933D01*
X170083Y1429725D01*
X169917Y1429433D01*
X169875Y1429142D01*
X169917Y1428850D01*
X170083Y1428475D01*
X169000Y1428600D01*
Y1429725D01*
G01X136069Y1433019D02*
Y1419019D01*
G01X149069Y1433019D02*
X136069D01*
G01X149069Y1419019D02*
Y1433019D01*
G01X136069Y1419019D02*
X149069D01*
G01X161800Y1434804D02*
Y1449604D01*
G01X155400Y1434804D02*
X161800D01*
G01X155400Y1449604D02*
Y1434804D01*
G01X161800Y1449604D02*
X155400D01*
G01X169600Y1482617D02*
X167100D01*
Y1483617D01*
X167225Y1483950D01*
X167517Y1484200D01*
X167850Y1484283D01*
X168183Y1484200D01*
X168433Y1483992D01*
X168558Y1483617D01*
Y1482617D01*
G01X169600Y1485717D02*
X167100D01*
Y1486758D01*
X167225Y1487092D01*
X167392Y1487300D01*
X167725Y1487383D01*
X168058Y1487300D01*
X168267Y1487050D01*
X168392Y1486758D01*
Y1485717D01*
G01Y1486758D02*
X169600Y1487383D01*
G01X167517Y1488858D02*
X167267Y1489108D01*
X167142Y1489400D01*
X167100Y1489733D01*
X167183Y1490150D01*
X167392Y1490442D01*
X167642Y1490525D01*
X167892Y1490483D01*
X168100Y1490317D01*
X168517Y1489483D01*
X168808Y1489108D01*
X169225Y1488858D01*
X169600Y1488775D01*
Y1490525D01*
G01Y1492750D02*
X169558Y1493042D01*
X169433Y1493375D01*
X169225Y1493583D01*
X168933Y1493667D01*
X168642Y1493583D01*
X168392Y1493333D01*
X168267Y1492958D01*
Y1492542D01*
X168183Y1492292D01*
X167975Y1492083D01*
X167683Y1492000D01*
X167392Y1492125D01*
X167183Y1492417D01*
X167100Y1492750D01*
X167183Y1493083D01*
X167392Y1493375D01*
X167683Y1493500D01*
X167975Y1493417D01*
X168183Y1493208D01*
X168267Y1492958D01*
Y1492542D01*
X168392Y1492167D01*
X168642Y1491917D01*
X168933Y1491833D01*
X169225Y1491917D01*
X169433Y1492125D01*
X169558Y1492458D01*
X169600Y1492750D01*
G01X149000Y1485800D02*
X153000D01*
Y1493200D01*
G01X165600Y1482617D02*
X163100D01*
Y1483617D01*
X163225Y1483950D01*
X163517Y1484200D01*
X163850Y1484283D01*
X164183Y1484200D01*
X164433Y1483992D01*
X164558Y1483617D01*
Y1482617D01*
G01X165600Y1485717D02*
X163100D01*
Y1486758D01*
X163225Y1487092D01*
X163392Y1487300D01*
X163725Y1487383D01*
X164058Y1487300D01*
X164267Y1487050D01*
X164392Y1486758D01*
Y1485717D01*
G01Y1486758D02*
X165600Y1487383D01*
G01X163517Y1488858D02*
X163267Y1489108D01*
X163142Y1489400D01*
X163100Y1489733D01*
X163183Y1490150D01*
X163392Y1490442D01*
X163642Y1490525D01*
X163892Y1490483D01*
X164100Y1490317D01*
X164517Y1489483D01*
X164808Y1489108D01*
X165225Y1488858D01*
X165600Y1488775D01*
Y1490525D01*
G01Y1492667D02*
X165058Y1492750D01*
X164600Y1492875D01*
X164183Y1493042D01*
X163725Y1493250D01*
X163100Y1493583D01*
Y1491917D01*
G01X144500Y1485800D02*
X148500D01*
Y1493200D01*
G01X161600Y1482617D02*
X159100D01*
Y1483617D01*
X159225Y1483950D01*
X159517Y1484200D01*
X159850Y1484283D01*
X160183Y1484200D01*
X160433Y1483992D01*
X160558Y1483617D01*
Y1482617D01*
G01X161600Y1485717D02*
X159100D01*
Y1486758D01*
X159225Y1487092D01*
X159392Y1487300D01*
X159725Y1487383D01*
X160058Y1487300D01*
X160267Y1487050D01*
X160392Y1486758D01*
Y1485717D01*
G01Y1486758D02*
X161600Y1487383D01*
G01X159517Y1488858D02*
X159267Y1489108D01*
X159142Y1489400D01*
X159100Y1489733D01*
X159183Y1490150D01*
X159392Y1490442D01*
X159642Y1490525D01*
X159892Y1490483D01*
X160100Y1490317D01*
X160517Y1489483D01*
X160808Y1489108D01*
X161225Y1488858D01*
X161600Y1488775D01*
Y1490525D01*
G01X160558Y1491958D02*
X160267Y1492250D01*
X160100Y1492500D01*
X160017Y1492833D01*
X160100Y1493125D01*
X160267Y1493333D01*
X160517Y1493500D01*
X160808Y1493542D01*
X161058Y1493500D01*
X161308Y1493333D01*
X161517Y1493083D01*
X161600Y1492792D01*
X161517Y1492458D01*
X161267Y1492167D01*
X160892Y1492000D01*
X160475Y1491958D01*
X159933Y1492042D01*
X159642Y1492167D01*
X159350Y1492375D01*
X159142Y1492667D01*
X159100Y1492958D01*
X159183Y1493250D01*
X159392Y1493458D01*
G01X140000Y1485800D02*
X144000D01*
Y1493200D01*
G01X138000Y1505517D02*
X135500D01*
Y1506517D01*
X135625Y1506850D01*
X135917Y1507100D01*
X136250Y1507183D01*
X136583Y1507100D01*
X136833Y1506892D01*
X136958Y1506517D01*
Y1505517D01*
G01X138000Y1508617D02*
X135500D01*
Y1509658D01*
X135625Y1509992D01*
X135792Y1510200D01*
X136125Y1510283D01*
X136458Y1510200D01*
X136667Y1509950D01*
X136792Y1509658D01*
Y1508617D01*
G01Y1509658D02*
X138000Y1510283D01*
G01X135917Y1511758D02*
X135667Y1512008D01*
X135542Y1512300D01*
X135500Y1512633D01*
X135583Y1513050D01*
X135792Y1513342D01*
X136042Y1513425D01*
X136292Y1513383D01*
X136500Y1513217D01*
X136917Y1512383D01*
X137208Y1512008D01*
X137625Y1511758D01*
X138000Y1511675D01*
Y1513425D01*
G01Y1516150D02*
X135500D01*
X137292Y1514608D01*
Y1516692D01*
G01X135000Y1496300D02*
X139000D01*
Y1503700D01*
G01X157500Y1482517D02*
X155000D01*
Y1483517D01*
X155125Y1483850D01*
X155417Y1484100D01*
X155750Y1484183D01*
X156083Y1484100D01*
X156333Y1483892D01*
X156458Y1483517D01*
Y1482517D01*
G01X157500Y1485617D02*
X155000D01*
Y1486658D01*
X155125Y1486992D01*
X155292Y1487200D01*
X155625Y1487283D01*
X155958Y1487200D01*
X156167Y1486950D01*
X156292Y1486658D01*
Y1485617D01*
G01Y1486658D02*
X157500Y1487283D01*
G01X157125Y1488633D02*
X157333Y1488883D01*
X157458Y1489175D01*
X157500Y1489550D01*
X157417Y1489925D01*
X157250Y1490217D01*
X156958Y1490425D01*
X156625Y1490467D01*
X156292Y1490383D01*
X156083Y1490175D01*
X155917Y1489883D01*
X155875Y1489592D01*
X155917Y1489300D01*
X156083Y1488925D01*
X155000Y1489050D01*
Y1490175D01*
G01X157500Y1492650D02*
X155000D01*
X155500Y1492150D01*
G01X157500D02*
Y1493150D01*
G01X135900Y1485700D02*
X139900D01*
Y1493100D01*
G01X145800Y1484800D02*
Y1468700D01*
G01X138800Y1484800D02*
X145800D01*
G01X138800Y1468700D02*
Y1484800D01*
G01X145800Y1468700D02*
X138800D01*
G01X168500Y1469417D02*
X166000D01*
Y1470417D01*
X166125Y1470750D01*
X166417Y1471000D01*
X166750Y1471083D01*
X167083Y1471000D01*
X167333Y1470792D01*
X167458Y1470417D01*
Y1469417D01*
G01X168500Y1472517D02*
X166000D01*
Y1473558D01*
X166125Y1473892D01*
X166292Y1474100D01*
X166625Y1474183D01*
X166958Y1474100D01*
X167167Y1473850D01*
X167292Y1473558D01*
Y1472517D01*
G01Y1473558D02*
X168500Y1474183D01*
G01Y1476950D02*
X166000D01*
X167792Y1475408D01*
Y1477492D01*
G01X168000Y1478633D02*
X168292Y1478883D01*
X168458Y1479217D01*
X168500Y1479592D01*
X168458Y1479925D01*
X168250Y1480258D01*
X168000Y1480467D01*
X167750Y1480508D01*
X167458Y1480425D01*
X167250Y1480133D01*
X167167Y1479842D01*
Y1479467D01*
G01Y1479842D02*
X167042Y1480092D01*
X166833Y1480300D01*
X166583Y1480383D01*
X166333Y1480300D01*
X166125Y1480092D01*
X166000Y1479717D01*
X166042Y1479342D01*
X166208Y1478967D01*
G01X146500Y1468700D02*
X150500D01*
Y1476100D01*
G01X152600Y1495200D02*
Y1520200D01*
G01X192800Y1495200D02*
X152600D01*
G01X153300Y1522500D02*
X164500D01*
G01X153300Y1540500D02*
Y1522500D01*
G01X164500Y1540500D02*
X153300D01*
G01X191700Y1522500D02*
X180500D01*
G01Y1540500D02*
X191700D01*
G01X153400Y1542600D02*
X164600D01*
G01X153400Y1560600D02*
Y1542600D01*
G01X164600Y1560600D02*
X153400D01*
G01X191800Y1542600D02*
X180600D01*
G01Y1560600D02*
X191800D01*
G01X152600Y1520200D02*
X192800D01*
G01X164967Y1604100D02*
Y1606600D01*
X165967D01*
X166300Y1606475D01*
X166550Y1606183D01*
X166633Y1605850D01*
X166550Y1605517D01*
X166342Y1605267D01*
X165967Y1605142D01*
X164967D01*
G01X168900Y1604100D02*
X168567Y1604142D01*
X168275Y1604308D01*
X168025Y1604558D01*
X167858Y1604850D01*
X167775Y1605183D01*
Y1605517D01*
X167858Y1605850D01*
X168025Y1606142D01*
X168275Y1606392D01*
X168567Y1606558D01*
X168900Y1606600D01*
X169233Y1606558D01*
X169525Y1606392D01*
X169775Y1606142D01*
X169942Y1605850D01*
X170025Y1605517D01*
Y1605183D01*
X169942Y1604850D01*
X169775Y1604558D01*
X169525Y1604308D01*
X169233Y1604142D01*
X168900Y1604100D01*
G01X169233Y1604767D02*
X169733Y1604100D01*
G01X171083Y1604600D02*
X171333Y1604308D01*
X171667Y1604142D01*
X172042Y1604100D01*
X172375Y1604142D01*
X172708Y1604350D01*
X172917Y1604600D01*
X172958Y1604850D01*
X172875Y1605142D01*
X172583Y1605350D01*
X172292Y1605433D01*
X171917D01*
G01X172292D02*
X172542Y1605558D01*
X172750Y1605767D01*
X172833Y1606017D01*
X172750Y1606267D01*
X172542Y1606475D01*
X172167Y1606600D01*
X171792Y1606558D01*
X171417Y1606392D01*
G01X180850Y1601300D02*
X159150D01*
G01X180850Y1571300D02*
Y1601300D01*
G01X159150Y1571300D02*
X180850D01*
G01X159150Y1601300D02*
Y1571300D01*
G01X132967Y1603600D02*
Y1606100D01*
X133967D01*
X134300Y1605975D01*
X134550Y1605683D01*
X134633Y1605350D01*
X134550Y1605017D01*
X134342Y1604767D01*
X133967Y1604642D01*
X132967D01*
G01X136900Y1603600D02*
X136567Y1603642D01*
X136275Y1603808D01*
X136025Y1604058D01*
X135858Y1604350D01*
X135775Y1604683D01*
Y1605017D01*
X135858Y1605350D01*
X136025Y1605642D01*
X136275Y1605892D01*
X136567Y1606058D01*
X136900Y1606100D01*
X137233Y1606058D01*
X137525Y1605892D01*
X137775Y1605642D01*
X137942Y1605350D01*
X138025Y1605017D01*
Y1604683D01*
X137942Y1604350D01*
X137775Y1604058D01*
X137525Y1603808D01*
X137233Y1603642D01*
X136900Y1603600D01*
G01X137233Y1604267D02*
X137733Y1603600D01*
G01X139208Y1605683D02*
X139458Y1605933D01*
X139750Y1606058D01*
X140083Y1606100D01*
X140500Y1606017D01*
X140792Y1605808D01*
X140875Y1605558D01*
X140833Y1605308D01*
X140667Y1605100D01*
X139833Y1604683D01*
X139458Y1604392D01*
X139208Y1603975D01*
X139125Y1603600D01*
X140875D01*
G01X146850Y1571300D02*
Y1601300D01*
G01X183067Y1612000D02*
Y1614500D01*
X184067D01*
X184400Y1614375D01*
X184650Y1614083D01*
X184733Y1613750D01*
X184650Y1613417D01*
X184442Y1613167D01*
X184067Y1613042D01*
X183067D01*
G01X187917Y1614292D02*
X187667Y1614417D01*
X187375Y1614500D01*
X187042D01*
X186667Y1614375D01*
X186375Y1614167D01*
X186167Y1613917D01*
X186000Y1613500D01*
X185958Y1613125D01*
X186042Y1612750D01*
X186167Y1612500D01*
X186417Y1612250D01*
X186708Y1612083D01*
X187000Y1612000D01*
X187292D01*
X187583Y1612083D01*
X187833Y1612208D01*
X188042Y1612375D01*
G01X190017Y1612000D02*
X190100Y1612542D01*
X190225Y1613000D01*
X190392Y1613417D01*
X190600Y1613875D01*
X190933Y1614500D01*
X189267D01*
G01X144500Y1612017D02*
X142000D01*
Y1613017D01*
X142125Y1613350D01*
X142417Y1613600D01*
X142750Y1613683D01*
X143083Y1613600D01*
X143333Y1613392D01*
X143458Y1613017D01*
Y1612017D01*
G01X144500Y1615117D02*
X142000D01*
Y1616158D01*
X142125Y1616492D01*
X142292Y1616700D01*
X142625Y1616783D01*
X142958Y1616700D01*
X143167Y1616450D01*
X143292Y1616158D01*
Y1615117D01*
G01Y1616158D02*
X144500Y1616783D01*
G01X144000Y1618133D02*
X144292Y1618383D01*
X144458Y1618717D01*
X144500Y1619092D01*
X144458Y1619425D01*
X144250Y1619758D01*
X144000Y1619967D01*
X143750Y1620008D01*
X143458Y1619925D01*
X143250Y1619633D01*
X143167Y1619342D01*
Y1618967D01*
G01Y1619342D02*
X143042Y1619592D01*
X142833Y1619800D01*
X142583Y1619883D01*
X142333Y1619800D01*
X142125Y1619592D01*
X142000Y1619217D01*
X142042Y1618842D01*
X142208Y1618467D01*
G01X144500Y1622150D02*
X142000D01*
X142500Y1621650D01*
G01X144500D02*
Y1622650D01*
G01X172000Y1611517D02*
X169500D01*
Y1612517D01*
X169625Y1612850D01*
X169917Y1613100D01*
X170250Y1613183D01*
X170583Y1613100D01*
X170833Y1612892D01*
X170958Y1612517D01*
Y1611517D01*
G01X172000Y1614617D02*
X169500D01*
Y1615658D01*
X169625Y1615992D01*
X169792Y1616200D01*
X170125Y1616283D01*
X170458Y1616200D01*
X170667Y1615950D01*
X170792Y1615658D01*
Y1614617D01*
G01Y1615658D02*
X172000Y1616283D01*
G01X171500Y1617633D02*
X171792Y1617883D01*
X171958Y1618217D01*
X172000Y1618592D01*
X171958Y1618925D01*
X171750Y1619258D01*
X171500Y1619467D01*
X171250Y1619508D01*
X170958Y1619425D01*
X170750Y1619133D01*
X170667Y1618842D01*
Y1618467D01*
G01Y1618842D02*
X170542Y1619092D01*
X170333Y1619300D01*
X170083Y1619383D01*
X169833Y1619300D01*
X169625Y1619092D01*
X169500Y1618717D01*
X169542Y1618342D01*
X169708Y1617967D01*
G01X169917Y1620858D02*
X169667Y1621108D01*
X169542Y1621400D01*
X169500Y1621733D01*
X169583Y1622150D01*
X169792Y1622442D01*
X170042Y1622525D01*
X170292Y1622483D01*
X170500Y1622317D01*
X170917Y1621483D01*
X171208Y1621108D01*
X171625Y1620858D01*
X172000Y1620775D01*
Y1622525D01*
G01X152250Y1610000D02*
Y1623000D01*
X167750D01*
Y1610000D01*
X152250D01*
G01X189367Y1688975D02*
X133467D01*
Y1773126D01*
X138779D01*
G03Y1784512I0J5693D01*
G01X133467D01*
Y1857875D01*
X189367D01*
Y1688975D01*
G01X133298Y1876703D02*
Y1887903D01*
G01X152517Y1861500D02*
Y1864000D01*
X153517D01*
X153850Y1863875D01*
X154100Y1863583D01*
X154183Y1863250D01*
X154100Y1862917D01*
X153892Y1862667D01*
X153517Y1862542D01*
X152517D01*
G01X155408Y1861500D02*
X156450Y1864000D01*
X157492Y1861500D01*
G01X157117Y1862375D02*
X155783D01*
G01X158633Y1861500D02*
Y1864000D01*
X159467D01*
X159800Y1863875D01*
X160050Y1863708D01*
X160258Y1863458D01*
X160425Y1863167D01*
X160467Y1862750D01*
X160425Y1862333D01*
X160258Y1862042D01*
X160050Y1861792D01*
X159800Y1861625D01*
X159467Y1861500D01*
X158633D01*
G01X161858Y1863583D02*
X162108Y1863833D01*
X162400Y1863958D01*
X162733Y1864000D01*
X163150Y1863917D01*
X163442Y1863708D01*
X163525Y1863458D01*
X163483Y1863208D01*
X163317Y1863000D01*
X162483Y1862583D01*
X162108Y1862292D01*
X161858Y1861875D01*
X161775Y1861500D01*
X163525D01*
G01X133298Y1915103D02*
Y1903903D01*
G01X144317Y1889792D02*
X144067Y1889917D01*
X143775Y1890000D01*
X143442D01*
X143067Y1889875D01*
X142775Y1889667D01*
X142567Y1889417D01*
X142400Y1889000D01*
X142358Y1888625D01*
X142442Y1888250D01*
X142567Y1888000D01*
X142817Y1887750D01*
X143108Y1887583D01*
X143400Y1887500D01*
X143692D01*
X143983Y1887583D01*
X144233Y1887708D01*
X144442Y1887875D01*
G01X145583D02*
X145833Y1887667D01*
X146125Y1887542D01*
X146500Y1887500D01*
X146875Y1887583D01*
X147167Y1887750D01*
X147375Y1888042D01*
X147417Y1888375D01*
X147333Y1888708D01*
X147125Y1888917D01*
X146833Y1889083D01*
X146542Y1889125D01*
X146250Y1889083D01*
X145875Y1888917D01*
X146000Y1890000D01*
X147125D01*
G01X149600D02*
X149267Y1889917D01*
X149017Y1889708D01*
X148850Y1889458D01*
X148725Y1889125D01*
X148683Y1888750D01*
X148725Y1888375D01*
X148850Y1888042D01*
X149017Y1887792D01*
X149267Y1887583D01*
X149600Y1887500D01*
X149933Y1887583D01*
X150183Y1887792D01*
X150350Y1888042D01*
X150475Y1888375D01*
X150517Y1888750D01*
X150475Y1889125D01*
X150350Y1889458D01*
X150183Y1889708D01*
X149933Y1889917D01*
X149600Y1890000D01*
G01X144317Y1894292D02*
X144067Y1894417D01*
X143775Y1894500D01*
X143442D01*
X143067Y1894375D01*
X142775Y1894167D01*
X142567Y1893917D01*
X142400Y1893500D01*
X142358Y1893125D01*
X142442Y1892750D01*
X142567Y1892500D01*
X142817Y1892250D01*
X143108Y1892083D01*
X143400Y1892000D01*
X143692D01*
X143983Y1892083D01*
X144233Y1892208D01*
X144442Y1892375D01*
G01X147000Y1892000D02*
Y1894500D01*
X145458Y1892708D01*
X147542D01*
G01X148892Y1892292D02*
X149183Y1892083D01*
X149517Y1892000D01*
X149850Y1892083D01*
X150142Y1892333D01*
X150350Y1892708D01*
X150433Y1893083D01*
Y1893542D01*
X150350Y1893917D01*
X150142Y1894250D01*
X149892Y1894417D01*
X149600Y1894500D01*
X149267Y1894417D01*
X149017Y1894250D01*
X148850Y1894000D01*
X148767Y1893667D01*
X148850Y1893375D01*
X149058Y1893083D01*
X149308Y1892917D01*
X149600Y1892875D01*
X149933Y1892958D01*
X150183Y1893167D01*
X150433Y1893542D01*
G01X176575Y1908500D02*
Y1911000D01*
G01X178325D02*
Y1908500D01*
G01Y1909750D02*
X176575D01*
G01X179633Y1909000D02*
X179883Y1908708D01*
X180217Y1908542D01*
X180592Y1908500D01*
X180925Y1908542D01*
X181258Y1908750D01*
X181467Y1909000D01*
X181508Y1909250D01*
X181425Y1909542D01*
X181133Y1909750D01*
X180842Y1909833D01*
X180467D01*
G01X180842D02*
X181092Y1909958D01*
X181300Y1910167D01*
X181383Y1910417D01*
X181300Y1910667D01*
X181092Y1910875D01*
X180717Y1911000D01*
X180342Y1910958D01*
X179967Y1910792D01*
G01X167814Y1966620D02*
X168214Y1967020D01*
X168681Y1967220D01*
X169214Y1967287D01*
X169881Y1967154D01*
X170348Y1966820D01*
X170481Y1966420D01*
X170414Y1966020D01*
X170148Y1965687D01*
X168814Y1965020D01*
X168214Y1964554D01*
X167814Y1963887D01*
X167681Y1963287D01*
X170481D01*
G01X137586D02*
Y1967287D01*
X136786Y1966487D01*
G01Y1963287D02*
X138386D01*
G01X192100Y406900D02*
Y388900D01*
G01X192000Y365700D02*
Y347700D01*
G01X192200Y385900D02*
Y367900D01*
G01X188967Y443500D02*
Y446000D01*
X189967D01*
X190300Y445875D01*
X190550Y445583D01*
X190633Y445250D01*
X190550Y444917D01*
X190342Y444667D01*
X189967Y444542D01*
X188967D01*
G01X192067Y443500D02*
Y446000D01*
X193108D01*
X193442Y445875D01*
X193650Y445708D01*
X193733Y445375D01*
X193650Y445042D01*
X193400Y444833D01*
X193108Y444708D01*
X192067D01*
G01X193108D02*
X193733Y443500D01*
G01X196000D02*
Y446000D01*
X195500Y445500D01*
G01Y443500D02*
X196500D01*
G01X199100D02*
Y446000D01*
X198600Y445500D01*
G01Y443500D02*
X199600D01*
G01X201492Y443792D02*
X201783Y443583D01*
X202117Y443500D01*
X202450Y443583D01*
X202742Y443833D01*
X202950Y444208D01*
X203033Y444583D01*
Y445042D01*
X202950Y445417D01*
X202742Y445750D01*
X202492Y445917D01*
X202200Y446000D01*
X201867Y445917D01*
X201617Y445750D01*
X201450Y445500D01*
X201367Y445167D01*
X201450Y444875D01*
X201658Y444583D01*
X201908Y444417D01*
X202200Y444375D01*
X202533Y444458D01*
X202783Y444667D01*
X203033Y445042D01*
G01X188800Y441500D02*
Y437500D01*
X196200D01*
G01X187350Y435300D02*
Y465300D01*
G01X192100Y427400D02*
Y409400D01*
G01X189017Y455500D02*
Y458000D01*
X190017D01*
X190350Y457875D01*
X190600Y457583D01*
X190683Y457250D01*
X190600Y456917D01*
X190392Y456667D01*
X190017Y456542D01*
X189017D01*
G01X192950Y455500D02*
X192617Y455542D01*
X192325Y455708D01*
X192075Y455958D01*
X191908Y456250D01*
X191825Y456583D01*
Y456917D01*
X191908Y457250D01*
X192075Y457542D01*
X192325Y457792D01*
X192617Y457958D01*
X192950Y458000D01*
X193283Y457958D01*
X193575Y457792D01*
X193825Y457542D01*
X193992Y457250D01*
X194075Y456917D01*
Y456583D01*
X193992Y456250D01*
X193825Y455958D01*
X193575Y455708D01*
X193283Y455542D01*
X192950Y455500D01*
G01X193283Y456167D02*
X193783Y455500D01*
G01X196050D02*
Y458000D01*
X195550Y457500D01*
G01Y455500D02*
X196550D01*
G01X198358Y457583D02*
X198608Y457833D01*
X198900Y457958D01*
X199233Y458000D01*
X199650Y457917D01*
X199942Y457708D01*
X200025Y457458D01*
X199983Y457208D01*
X199817Y457000D01*
X198983Y456583D01*
X198608Y456292D01*
X198358Y455875D01*
X198275Y455500D01*
X200025D01*
G01X201000Y547967D02*
X198500D01*
Y548967D01*
X198625Y549300D01*
X198917Y549550D01*
X199250Y549633D01*
X199583Y549550D01*
X199833Y549342D01*
X199958Y548967D01*
Y547967D01*
G01X201000Y551067D02*
X198500D01*
Y552108D01*
X198625Y552442D01*
X198792Y552650D01*
X199125Y552733D01*
X199458Y552650D01*
X199667Y552400D01*
X199792Y552108D01*
Y551067D01*
G01Y552108D02*
X201000Y552733D01*
G01Y555000D02*
X198500D01*
X199000Y554500D01*
G01X201000D02*
Y555500D01*
G01Y558100D02*
X198500D01*
X199000Y557600D01*
G01X201000D02*
Y558600D01*
G01X200500Y560283D02*
X200792Y560533D01*
X200958Y560867D01*
X201000Y561242D01*
X200958Y561575D01*
X200750Y561908D01*
X200500Y562117D01*
X200250Y562158D01*
X199958Y562075D01*
X199750Y561783D01*
X199667Y561492D01*
Y561117D01*
G01Y561492D02*
X199542Y561742D01*
X199333Y561950D01*
X199083Y562033D01*
X198833Y561950D01*
X198625Y561742D01*
X198500Y561367D01*
X198542Y560992D01*
X198708Y560617D01*
G01X188100Y530417D02*
X185600D01*
Y531417D01*
X185725Y531750D01*
X186017Y532000D01*
X186350Y532083D01*
X186683Y532000D01*
X186933Y531792D01*
X187058Y531417D01*
Y530417D01*
G01X185808Y535267D02*
X185683Y535017D01*
X185600Y534725D01*
Y534392D01*
X185725Y534017D01*
X185933Y533725D01*
X186183Y533517D01*
X186600Y533350D01*
X186975Y533308D01*
X187350Y533392D01*
X187600Y533517D01*
X187850Y533767D01*
X188017Y534058D01*
X188100Y534350D01*
Y534642D01*
X188017Y534933D01*
X187892Y535183D01*
X187725Y535392D01*
G01X187808Y536742D02*
X188017Y537033D01*
X188100Y537367D01*
X188017Y537700D01*
X187767Y537992D01*
X187392Y538200D01*
X187017Y538283D01*
X186558D01*
X186183Y538200D01*
X185850Y537992D01*
X185683Y537742D01*
X185600Y537450D01*
X185683Y537117D01*
X185850Y536867D01*
X186100Y536700D01*
X186433Y536617D01*
X186725Y536700D01*
X187017Y536908D01*
X187183Y537158D01*
X187225Y537450D01*
X187142Y537783D01*
X186933Y538033D01*
X186558Y538283D01*
G01X185600Y540550D02*
X185683Y540217D01*
X185892Y539967D01*
X186142Y539800D01*
X186475Y539675D01*
X186850Y539633D01*
X187225Y539675D01*
X187558Y539800D01*
X187808Y539967D01*
X188017Y540217D01*
X188100Y540550D01*
X188017Y540883D01*
X187808Y541133D01*
X187558Y541300D01*
X187225Y541425D01*
X186850Y541467D01*
X186475Y541425D01*
X186142Y541300D01*
X185892Y541133D01*
X185683Y540883D01*
X185600Y540550D01*
G01X188575Y588500D02*
Y591000D01*
G01X190325D02*
Y588500D01*
G01Y589750D02*
X188575D01*
G01X192550Y588500D02*
X192842Y588542D01*
X193175Y588667D01*
X193383Y588875D01*
X193467Y589167D01*
X193383Y589458D01*
X193133Y589708D01*
X192758Y589833D01*
X192342D01*
X192092Y589917D01*
X191883Y590125D01*
X191800Y590417D01*
X191925Y590708D01*
X192217Y590917D01*
X192550Y591000D01*
X192883Y590917D01*
X193175Y590708D01*
X193300Y590417D01*
X193217Y590125D01*
X193008Y589917D01*
X192758Y589833D01*
X192342D01*
X191967Y589708D01*
X191717Y589458D01*
X191633Y589167D01*
X191717Y588875D01*
X191925Y588667D01*
X192258Y588542D01*
X192550Y588500D01*
G01X195900Y632800D02*
X195817Y632133D01*
X195483Y631550D01*
X194983Y631050D01*
X194400Y630717D01*
X193733Y630550D01*
X193067D01*
X192400Y630717D01*
X191817Y631050D01*
X191317Y631550D01*
X190983Y632133D01*
X190900Y632800D01*
X190983Y633467D01*
X191317Y634050D01*
X191817Y634550D01*
X192400Y634883D01*
X193067Y635050D01*
X193733D01*
X194400Y634883D01*
X194983Y634550D01*
X195483Y634050D01*
X195817Y633467D01*
X195900Y632800D01*
G01X195233Y636650D02*
X195650Y637317D01*
X195900Y638067D01*
Y638733D01*
X195650Y639400D01*
X195233Y639900D01*
X194650Y640150D01*
X194067Y639983D01*
X193567Y639567D01*
X193233Y638817D01*
X193067Y637817D01*
X192733Y637233D01*
X192150Y636983D01*
X191567Y637150D01*
X191150Y637567D01*
X190900Y638150D01*
Y638733D01*
X191067Y639317D01*
X191483Y639817D01*
G01X191317Y645833D02*
X191067Y645333D01*
X190900Y644750D01*
Y644083D01*
X191150Y643333D01*
X191567Y642750D01*
X192067Y642333D01*
X192900Y642000D01*
X193650Y641917D01*
X194400Y642083D01*
X194900Y642333D01*
X195400Y642833D01*
X195733Y643417D01*
X195900Y644000D01*
Y644583D01*
X195733Y645167D01*
X195483Y645667D01*
X195150Y646083D01*
G01X195900Y649600D02*
X190900D01*
X191900Y648600D01*
G01X195900D02*
Y650600D01*
G01X196067Y655200D02*
X195983Y655033D01*
X195817D01*
X195733Y655200D01*
X195817Y655367D01*
X195983D01*
X196067Y655200D01*
G01X193817D02*
X193733Y655033D01*
X193567D01*
X193483Y655200D01*
X193567Y655367D01*
X193733D01*
X193817Y655200D01*
G01X194900Y658967D02*
X195483Y659467D01*
X195817Y660133D01*
X195900Y660883D01*
X195817Y661550D01*
X195400Y662217D01*
X194900Y662633D01*
X194400Y662717D01*
X193817Y662550D01*
X193400Y661967D01*
X193233Y661383D01*
Y660633D01*
G01Y661383D02*
X192983Y661883D01*
X192567Y662300D01*
X192067Y662467D01*
X191567Y662300D01*
X191150Y661883D01*
X190900Y661133D01*
X190983Y660383D01*
X191317Y659633D01*
G01X194900Y664567D02*
X195483Y665067D01*
X195817Y665733D01*
X195900Y666483D01*
X195817Y667150D01*
X195400Y667817D01*
X194900Y668233D01*
X194400Y668317D01*
X193817Y668150D01*
X193400Y667567D01*
X193233Y666983D01*
Y666233D01*
G01Y666983D02*
X192983Y667483D01*
X192567Y667900D01*
X192067Y668067D01*
X191567Y667900D01*
X191150Y667483D01*
X190900Y666733D01*
X190983Y665983D01*
X191317Y665233D01*
G01X195900Y669833D02*
X190900D01*
X195067Y672000D01*
X190900Y674167D01*
X195900D01*
G01Y675850D02*
X190900D01*
G01Y679350D02*
X195900D01*
G01X193400D02*
Y675850D01*
G01X190900Y681617D02*
Y684783D01*
X195900Y681617D01*
Y684783D01*
G01X186500Y606350D02*
X189000D01*
G01X186500Y605392D02*
Y607308D01*
G01X189000Y608617D02*
X186500D01*
Y609617D01*
X186625Y609950D01*
X186917Y610200D01*
X187250Y610283D01*
X187583Y610200D01*
X187833Y609992D01*
X187958Y609617D01*
Y608617D01*
G01X189000Y612550D02*
X186500D01*
X187000Y612050D01*
G01X189000D02*
Y613050D01*
G01Y615567D02*
X188458Y615650D01*
X188000Y615775D01*
X187583Y615942D01*
X187125Y616150D01*
X186500Y616483D01*
Y614817D01*
G01X199500Y619567D02*
X197000D01*
Y620608D01*
X197125Y620942D01*
X197292Y621150D01*
X197625Y621233D01*
X197958Y621150D01*
X198167Y620900D01*
X198292Y620608D01*
Y619567D01*
G01Y620608D02*
X199500Y621233D01*
G01X199125Y622583D02*
X199333Y622833D01*
X199458Y623125D01*
X199500Y623500D01*
X199417Y623875D01*
X199250Y624167D01*
X198958Y624375D01*
X198625Y624417D01*
X198292Y624333D01*
X198083Y624125D01*
X197917Y623833D01*
X197875Y623542D01*
X197917Y623250D01*
X198083Y622875D01*
X197000Y623000D01*
Y624125D01*
G01X199500Y626600D02*
X197000D01*
X197500Y626100D01*
G01X199500D02*
Y627100D01*
G01X187067Y619500D02*
Y622000D01*
X188108D01*
X188442Y621875D01*
X188650Y621708D01*
X188733Y621375D01*
X188650Y621042D01*
X188400Y620833D01*
X188108Y620708D01*
X187067D01*
G01X188108D02*
X188733Y619500D01*
G01X190083Y619875D02*
X190333Y619667D01*
X190625Y619542D01*
X191000Y619500D01*
X191375Y619583D01*
X191667Y619750D01*
X191875Y620042D01*
X191917Y620375D01*
X191833Y620708D01*
X191625Y620917D01*
X191333Y621083D01*
X191042Y621125D01*
X190750Y621083D01*
X190375Y620917D01*
X190500Y622000D01*
X191625D01*
G01X194100D02*
X193767Y621917D01*
X193517Y621708D01*
X193350Y621458D01*
X193225Y621125D01*
X193183Y620750D01*
X193225Y620375D01*
X193350Y620042D01*
X193517Y619792D01*
X193767Y619583D01*
X194100Y619500D01*
X194433Y619583D01*
X194683Y619792D01*
X194850Y620042D01*
X194975Y620375D01*
X195017Y620750D01*
X194975Y621125D01*
X194850Y621458D01*
X194683Y621708D01*
X194433Y621917D01*
X194100Y622000D01*
G01X186000Y641617D02*
X183500D01*
Y642658D01*
X183625Y642992D01*
X183792Y643200D01*
X184125Y643283D01*
X184458Y643200D01*
X184667Y642950D01*
X184792Y642658D01*
Y641617D01*
G01Y642658D02*
X186000Y643283D01*
G01X185500Y644633D02*
X185792Y644883D01*
X185958Y645217D01*
X186000Y645592D01*
X185958Y645925D01*
X185750Y646258D01*
X185500Y646467D01*
X185250Y646508D01*
X184958Y646425D01*
X184750Y646133D01*
X184667Y645842D01*
Y645467D01*
G01Y645842D02*
X184542Y646092D01*
X184333Y646300D01*
X184083Y646383D01*
X183833Y646300D01*
X183625Y646092D01*
X183500Y645717D01*
X183542Y645342D01*
X183708Y644967D01*
G01X187067Y624500D02*
Y627000D01*
X188108D01*
X188442Y626875D01*
X188650Y626708D01*
X188733Y626375D01*
X188650Y626042D01*
X188400Y625833D01*
X188108Y625708D01*
X187067D01*
G01X188108D02*
X188733Y624500D01*
G01X191000D02*
Y627000D01*
X190500Y626500D01*
G01Y624500D02*
X191500D01*
G01X193183Y624875D02*
X193433Y624667D01*
X193725Y624542D01*
X194100Y624500D01*
X194475Y624583D01*
X194767Y624750D01*
X194975Y625042D01*
X195017Y625375D01*
X194933Y625708D01*
X194725Y625917D01*
X194433Y626083D01*
X194142Y626125D01*
X193850Y626083D01*
X193475Y625917D01*
X193600Y627000D01*
X194725D01*
G01X203500Y619067D02*
X201000D01*
Y620108D01*
X201125Y620442D01*
X201292Y620650D01*
X201625Y620733D01*
X201958Y620650D01*
X202167Y620400D01*
X202292Y620108D01*
Y619067D01*
G01Y620108D02*
X203500Y620733D01*
G01Y623000D02*
X201000D01*
X201500Y622500D01*
G01X203500D02*
Y623500D01*
G01Y626600D02*
X201000D01*
X202792Y625058D01*
Y627142D01*
G01X198500Y605517D02*
X201000D01*
Y607183D01*
G01X198917Y608658D02*
X198667Y608908D01*
X198542Y609200D01*
X198500Y609533D01*
X198583Y609950D01*
X198792Y610242D01*
X199042Y610325D01*
X199292Y610283D01*
X199500Y610117D01*
X199917Y609283D01*
X200208Y608908D01*
X200625Y608658D01*
X201000Y608575D01*
Y610325D01*
G01X184208Y632367D02*
X184083Y632117D01*
X184000Y631825D01*
Y631492D01*
X184125Y631117D01*
X184333Y630825D01*
X184583Y630617D01*
X185000Y630450D01*
X185375Y630408D01*
X185750Y630492D01*
X186000Y630617D01*
X186250Y630867D01*
X186417Y631158D01*
X186500Y631450D01*
Y631742D01*
X186417Y632033D01*
X186292Y632283D01*
X186125Y632492D01*
G01X185458Y633758D02*
X185167Y634050D01*
X185000Y634300D01*
X184917Y634633D01*
X185000Y634925D01*
X185167Y635133D01*
X185417Y635300D01*
X185708Y635342D01*
X185958Y635300D01*
X186208Y635133D01*
X186417Y634883D01*
X186500Y634592D01*
X186417Y634258D01*
X186167Y633967D01*
X185792Y633800D01*
X185375Y633758D01*
X184833Y633842D01*
X184542Y633967D01*
X184250Y634175D01*
X184042Y634467D01*
X184000Y634758D01*
X184083Y635050D01*
X184292Y635258D01*
G01X190708Y607267D02*
X190583Y607017D01*
X190500Y606725D01*
Y606392D01*
X190625Y606017D01*
X190833Y605725D01*
X191083Y605517D01*
X191500Y605350D01*
X191875Y605308D01*
X192250Y605392D01*
X192500Y605517D01*
X192750Y605767D01*
X192917Y606058D01*
X193000Y606350D01*
Y606642D01*
X192917Y606933D01*
X192792Y607183D01*
X192625Y607392D01*
G01X193000Y609950D02*
X190500D01*
X192292Y608408D01*
Y610492D01*
G01X194708Y607267D02*
X194583Y607017D01*
X194500Y606725D01*
Y606392D01*
X194625Y606017D01*
X194833Y605725D01*
X195083Y605517D01*
X195500Y605350D01*
X195875Y605308D01*
X196250Y605392D01*
X196500Y605517D01*
X196750Y605767D01*
X196917Y606058D01*
X197000Y606350D01*
Y606642D01*
X196917Y606933D01*
X196792Y607183D01*
X196625Y607392D01*
G01X196500Y608533D02*
X196792Y608783D01*
X196958Y609117D01*
X197000Y609492D01*
X196958Y609825D01*
X196750Y610158D01*
X196500Y610367D01*
X196250Y610408D01*
X195958Y610325D01*
X195750Y610033D01*
X195667Y609742D01*
Y609367D01*
G01Y609742D02*
X195542Y609992D01*
X195333Y610200D01*
X195083Y610283D01*
X194833Y610200D01*
X194625Y609992D01*
X194500Y609617D01*
X194542Y609242D01*
X194708Y608867D01*
G01X191708Y691267D02*
X191583Y691017D01*
X191500Y690725D01*
Y690392D01*
X191625Y690017D01*
X191833Y689725D01*
X192083Y689517D01*
X192500Y689350D01*
X192875Y689308D01*
X193250Y689392D01*
X193500Y689517D01*
X193750Y689767D01*
X193917Y690058D01*
X194000Y690350D01*
Y690642D01*
X193917Y690933D01*
X193792Y691183D01*
X193625Y691392D01*
G01X191917Y692658D02*
X191667Y692908D01*
X191542Y693200D01*
X191500Y693533D01*
X191583Y693950D01*
X191792Y694242D01*
X192042Y694325D01*
X192292Y694283D01*
X192500Y694117D01*
X192917Y693283D01*
X193208Y692908D01*
X193625Y692658D01*
X194000Y692575D01*
Y694325D01*
G01X193625Y695633D02*
X193833Y695883D01*
X193958Y696175D01*
X194000Y696550D01*
X193917Y696925D01*
X193750Y697217D01*
X193458Y697425D01*
X193125Y697467D01*
X192792Y697383D01*
X192583Y697175D01*
X192417Y696883D01*
X192375Y696592D01*
X192417Y696300D01*
X192583Y695925D01*
X191500Y696050D01*
Y697175D01*
G01X193500Y698733D02*
X193792Y698983D01*
X193958Y699317D01*
X194000Y699692D01*
X193958Y700025D01*
X193750Y700358D01*
X193500Y700567D01*
X193250Y700608D01*
X192958Y700525D01*
X192750Y700233D01*
X192667Y699942D01*
Y699567D01*
G01Y699942D02*
X192542Y700192D01*
X192333Y700400D01*
X192083Y700483D01*
X191833Y700400D01*
X191625Y700192D01*
X191500Y699817D01*
X191542Y699442D01*
X191708Y699067D01*
G01X186000Y689517D02*
X183500D01*
Y690517D01*
X183625Y690850D01*
X183917Y691100D01*
X184250Y691183D01*
X184583Y691100D01*
X184833Y690892D01*
X184958Y690517D01*
Y689517D01*
G01X186000Y692617D02*
X183500D01*
Y693658D01*
X183625Y693992D01*
X183792Y694200D01*
X184125Y694283D01*
X184458Y694200D01*
X184667Y693950D01*
X184792Y693658D01*
Y692617D01*
G01Y693658D02*
X186000Y694283D01*
G01Y697050D02*
X183500D01*
X185292Y695508D01*
Y697592D01*
G01X185625Y698733D02*
X185833Y698983D01*
X185958Y699275D01*
X186000Y699650D01*
X185917Y700025D01*
X185750Y700317D01*
X185458Y700525D01*
X185125Y700567D01*
X184792Y700483D01*
X184583Y700275D01*
X184417Y699983D01*
X184375Y699692D01*
X184417Y699400D01*
X184583Y699025D01*
X183500Y699150D01*
Y700275D01*
G01X198000Y689517D02*
X195500D01*
Y690517D01*
X195625Y690850D01*
X195917Y691100D01*
X196250Y691183D01*
X196583Y691100D01*
X196833Y690892D01*
X196958Y690517D01*
Y689517D01*
G01X198000Y692617D02*
X195500D01*
Y693658D01*
X195625Y693992D01*
X195792Y694200D01*
X196125Y694283D01*
X196458Y694200D01*
X196667Y693950D01*
X196792Y693658D01*
Y692617D01*
G01Y693658D02*
X198000Y694283D01*
G01Y697050D02*
X195500D01*
X197292Y695508D01*
Y697592D01*
G01X198000Y699567D02*
X197458Y699650D01*
X197000Y699775D01*
X196583Y699942D01*
X196125Y700150D01*
X195500Y700483D01*
Y698817D01*
G01X190000Y689517D02*
X187500D01*
Y690558D01*
X187625Y690892D01*
X187792Y691100D01*
X188125Y691183D01*
X188458Y691100D01*
X188667Y690850D01*
X188792Y690558D01*
Y689517D01*
G01Y690558D02*
X190000Y691183D01*
G01X187917Y692658D02*
X187667Y692908D01*
X187542Y693200D01*
X187500Y693533D01*
X187583Y693950D01*
X187792Y694242D01*
X188042Y694325D01*
X188292Y694283D01*
X188500Y694117D01*
X188917Y693283D01*
X189208Y692908D01*
X189625Y692658D01*
X190000Y692575D01*
Y694325D01*
G01X188958Y695758D02*
X188667Y696050D01*
X188500Y696300D01*
X188417Y696633D01*
X188500Y696925D01*
X188667Y697133D01*
X188917Y697300D01*
X189208Y697342D01*
X189458Y697300D01*
X189708Y697133D01*
X189917Y696883D01*
X190000Y696592D01*
X189917Y696258D01*
X189667Y695967D01*
X189292Y695800D01*
X188875Y695758D01*
X188333Y695842D01*
X188042Y695967D01*
X187750Y696175D01*
X187542Y696467D01*
X187500Y696758D01*
X187583Y697050D01*
X187792Y697258D01*
G01X187500Y699650D02*
X187583Y699317D01*
X187792Y699067D01*
X188042Y698900D01*
X188375Y698775D01*
X188750Y698733D01*
X189125Y698775D01*
X189458Y698900D01*
X189708Y699067D01*
X189917Y699317D01*
X190000Y699650D01*
X189917Y699983D01*
X189708Y700233D01*
X189458Y700400D01*
X189125Y700525D01*
X188750Y700567D01*
X188375Y700525D01*
X188042Y700400D01*
X187792Y700233D01*
X187583Y699983D01*
X187500Y699650D01*
G01X201500Y689517D02*
X199000D01*
Y690558D01*
X199125Y690892D01*
X199292Y691100D01*
X199625Y691183D01*
X199958Y691100D01*
X200167Y690850D01*
X200292Y690558D01*
Y689517D01*
G01Y690558D02*
X201500Y691183D01*
G01X199417Y692658D02*
X199167Y692908D01*
X199042Y693200D01*
X199000Y693533D01*
X199083Y693950D01*
X199292Y694242D01*
X199542Y694325D01*
X199792Y694283D01*
X200000Y694117D01*
X200417Y693283D01*
X200708Y692908D01*
X201125Y692658D01*
X201500Y692575D01*
Y694325D01*
G01Y696467D02*
X200958Y696550D01*
X200500Y696675D01*
X200083Y696842D01*
X199625Y697050D01*
X199000Y697383D01*
Y695717D01*
G01Y699650D02*
X199083Y699317D01*
X199292Y699067D01*
X199542Y698900D01*
X199875Y698775D01*
X200250Y698733D01*
X200625Y698775D01*
X200958Y698900D01*
X201208Y699067D01*
X201417Y699317D01*
X201500Y699650D01*
X201417Y699983D01*
X201208Y700233D01*
X200958Y700400D01*
X200625Y700525D01*
X200250Y700567D01*
X199875Y700525D01*
X199542Y700400D01*
X199292Y700233D01*
X199083Y699983D01*
X199000Y699650D01*
G01X186100Y707750D02*
X188600D01*
G01X186100Y706792D02*
Y708708D01*
G01X188600Y710017D02*
X186100D01*
Y711017D01*
X186225Y711350D01*
X186517Y711600D01*
X186850Y711683D01*
X187183Y711600D01*
X187433Y711392D01*
X187558Y711017D01*
Y710017D01*
G01X186517Y713158D02*
X186267Y713408D01*
X186142Y713700D01*
X186100Y714033D01*
X186183Y714450D01*
X186392Y714742D01*
X186642Y714825D01*
X186892Y714783D01*
X187100Y714617D01*
X187517Y713783D01*
X187808Y713408D01*
X188225Y713158D01*
X188600Y713075D01*
Y714825D01*
G01Y717050D02*
X186100D01*
X186600Y716550D01*
G01X188600D02*
Y717550D01*
G01X186267Y1465792D02*
X186017Y1465917D01*
X185725Y1466000D01*
X185392D01*
X185017Y1465875D01*
X184725Y1465667D01*
X184517Y1465417D01*
X184350Y1465000D01*
X184308Y1464625D01*
X184392Y1464250D01*
X184517Y1464000D01*
X184767Y1463750D01*
X185058Y1463583D01*
X185350Y1463500D01*
X185642D01*
X185933Y1463583D01*
X186183Y1463708D01*
X186392Y1463875D01*
G01X187658Y1465583D02*
X187908Y1465833D01*
X188200Y1465958D01*
X188533Y1466000D01*
X188950Y1465917D01*
X189242Y1465708D01*
X189325Y1465458D01*
X189283Y1465208D01*
X189117Y1465000D01*
X188283Y1464583D01*
X187908Y1464292D01*
X187658Y1463875D01*
X187575Y1463500D01*
X189325D01*
G01X190633Y1463875D02*
X190883Y1463667D01*
X191175Y1463542D01*
X191550Y1463500D01*
X191925Y1463583D01*
X192217Y1463750D01*
X192425Y1464042D01*
X192467Y1464375D01*
X192383Y1464708D01*
X192175Y1464917D01*
X191883Y1465083D01*
X191592Y1465125D01*
X191300Y1465083D01*
X190925Y1464917D01*
X191050Y1466000D01*
X192175D01*
G01X193733Y1463875D02*
X193983Y1463667D01*
X194275Y1463542D01*
X194650Y1463500D01*
X195025Y1463583D01*
X195317Y1463750D01*
X195525Y1464042D01*
X195567Y1464375D01*
X195483Y1464708D01*
X195275Y1464917D01*
X194983Y1465083D01*
X194692Y1465125D01*
X194400Y1465083D01*
X194025Y1464917D01*
X194150Y1466000D01*
X195275D01*
G01X185017Y1458500D02*
Y1461000D01*
X186017D01*
X186350Y1460875D01*
X186600Y1460583D01*
X186683Y1460250D01*
X186600Y1459917D01*
X186392Y1459667D01*
X186017Y1459542D01*
X185017D01*
G01X188117Y1458500D02*
Y1461000D01*
X189158D01*
X189492Y1460875D01*
X189700Y1460708D01*
X189783Y1460375D01*
X189700Y1460042D01*
X189450Y1459833D01*
X189158Y1459708D01*
X188117D01*
G01X189158D02*
X189783Y1458500D01*
G01X192550D02*
Y1461000D01*
X191008Y1459208D01*
X193092D01*
G01X195150Y1458500D02*
X195442Y1458542D01*
X195775Y1458667D01*
X195983Y1458875D01*
X196067Y1459167D01*
X195983Y1459458D01*
X195733Y1459708D01*
X195358Y1459833D01*
X194942D01*
X194692Y1459917D01*
X194483Y1460125D01*
X194400Y1460417D01*
X194525Y1460708D01*
X194817Y1460917D01*
X195150Y1461000D01*
X195483Y1460917D01*
X195775Y1460708D01*
X195900Y1460417D01*
X195817Y1460125D01*
X195608Y1459917D01*
X195358Y1459833D01*
X194942D01*
X194567Y1459708D01*
X194317Y1459458D01*
X194233Y1459167D01*
X194317Y1458875D01*
X194525Y1458667D01*
X194858Y1458542D01*
X195150Y1458500D01*
G01X186000Y1422017D02*
X183500D01*
Y1423017D01*
X183625Y1423350D01*
X183917Y1423600D01*
X184250Y1423683D01*
X184583Y1423600D01*
X184833Y1423392D01*
X184958Y1423017D01*
Y1422017D01*
G01X186000Y1425117D02*
X183500D01*
Y1426158D01*
X183625Y1426492D01*
X183792Y1426700D01*
X184125Y1426783D01*
X184458Y1426700D01*
X184667Y1426450D01*
X184792Y1426158D01*
Y1425117D01*
G01Y1426158D02*
X186000Y1426783D01*
G01Y1429550D02*
X183500D01*
X185292Y1428008D01*
Y1430092D01*
G01X185708Y1431442D02*
X185917Y1431733D01*
X186000Y1432067D01*
X185917Y1432400D01*
X185667Y1432692D01*
X185292Y1432900D01*
X184917Y1432983D01*
X184458D01*
X184083Y1432900D01*
X183750Y1432692D01*
X183583Y1432442D01*
X183500Y1432150D01*
X183583Y1431817D01*
X183750Y1431567D01*
X184000Y1431400D01*
X184333Y1431317D01*
X184625Y1431400D01*
X184917Y1431608D01*
X185083Y1431858D01*
X185125Y1432150D01*
X185042Y1432483D01*
X184833Y1432733D01*
X184458Y1432983D01*
G01X192500Y1437067D02*
X190000D01*
Y1438067D01*
X190125Y1438400D01*
X190417Y1438650D01*
X190750Y1438733D01*
X191083Y1438650D01*
X191333Y1438442D01*
X191458Y1438067D01*
Y1437067D01*
G01X192500Y1441000D02*
X192458Y1440667D01*
X192292Y1440375D01*
X192042Y1440125D01*
X191750Y1439958D01*
X191417Y1439875D01*
X191083D01*
X190750Y1439958D01*
X190458Y1440125D01*
X190208Y1440375D01*
X190042Y1440667D01*
X190000Y1441000D01*
X190042Y1441333D01*
X190208Y1441625D01*
X190458Y1441875D01*
X190750Y1442042D01*
X191083Y1442125D01*
X191417D01*
X191750Y1442042D01*
X192042Y1441875D01*
X192292Y1441625D01*
X192458Y1441333D01*
X192500Y1441000D01*
G01X191833Y1441333D02*
X192500Y1441833D01*
G01X191458Y1443308D02*
X191167Y1443600D01*
X191000Y1443850D01*
X190917Y1444183D01*
X191000Y1444475D01*
X191167Y1444683D01*
X191417Y1444850D01*
X191708Y1444892D01*
X191958Y1444850D01*
X192208Y1444683D01*
X192417Y1444433D01*
X192500Y1444142D01*
X192417Y1443808D01*
X192167Y1443517D01*
X191792Y1443350D01*
X191375Y1443308D01*
X190833Y1443392D01*
X190542Y1443517D01*
X190250Y1443725D01*
X190042Y1444017D01*
X190000Y1444308D01*
X190083Y1444600D01*
X190292Y1444808D01*
G01X188500Y1436983D02*
X186000D01*
Y1437817D01*
X186125Y1438150D01*
X186292Y1438400D01*
X186542Y1438608D01*
X186833Y1438775D01*
X187250Y1438817D01*
X187667Y1438775D01*
X187958Y1438608D01*
X188208Y1438400D01*
X188375Y1438150D01*
X188500Y1437817D01*
Y1436983D01*
G01Y1441000D02*
X186000D01*
X186500Y1440500D01*
G01X188500D02*
Y1441500D01*
G01Y1444100D02*
X188458Y1444392D01*
X188333Y1444725D01*
X188125Y1444933D01*
X187833Y1445017D01*
X187542Y1444933D01*
X187292Y1444683D01*
X187167Y1444308D01*
Y1443892D01*
X187083Y1443642D01*
X186875Y1443433D01*
X186583Y1443350D01*
X186292Y1443475D01*
X186083Y1443767D01*
X186000Y1444100D01*
X186083Y1444433D01*
X186292Y1444725D01*
X186583Y1444850D01*
X186875Y1444767D01*
X187083Y1444558D01*
X187167Y1444308D01*
Y1443892D01*
X187292Y1443517D01*
X187542Y1443267D01*
X187833Y1443183D01*
X188125Y1443267D01*
X188333Y1443475D01*
X188458Y1443808D01*
X188500Y1444100D01*
G01X194483Y1508000D02*
Y1510500D01*
X195317D01*
X195650Y1510375D01*
X195900Y1510208D01*
X196108Y1509958D01*
X196275Y1509667D01*
X196317Y1509250D01*
X196275Y1508833D01*
X196108Y1508542D01*
X195900Y1508292D01*
X195650Y1508125D01*
X195317Y1508000D01*
X194483D01*
G01X198500D02*
Y1510500D01*
X198000Y1510000D01*
G01Y1508000D02*
X199000D01*
G01X202100D02*
Y1510500D01*
X200558Y1508708D01*
X202642D01*
G01X192800Y1520200D02*
Y1495200D01*
G01X195900Y1528900D02*
Y1526400D01*
G01X194942Y1528900D02*
X196858D01*
G01X199917Y1528692D02*
X199667Y1528817D01*
X199375Y1528900D01*
X199042D01*
X198667Y1528775D01*
X198375Y1528567D01*
X198167Y1528317D01*
X198000Y1527900D01*
X197958Y1527525D01*
X198042Y1527150D01*
X198167Y1526900D01*
X198417Y1526650D01*
X198708Y1526483D01*
X199000Y1526400D01*
X199292D01*
X199583Y1526483D01*
X199833Y1526608D01*
X200042Y1526775D01*
G01X201392Y1526692D02*
X201683Y1526483D01*
X202017Y1526400D01*
X202350Y1526483D01*
X202642Y1526733D01*
X202850Y1527108D01*
X202933Y1527483D01*
Y1527942D01*
X202850Y1528317D01*
X202642Y1528650D01*
X202392Y1528817D01*
X202100Y1528900D01*
X201767Y1528817D01*
X201517Y1528650D01*
X201350Y1528400D01*
X201267Y1528067D01*
X201350Y1527775D01*
X201558Y1527483D01*
X201808Y1527317D01*
X202100Y1527275D01*
X202433Y1527358D01*
X202683Y1527567D01*
X202933Y1527942D01*
G01X191700Y1540500D02*
Y1522500D01*
G01X194350Y1549000D02*
Y1546500D01*
G01X193392Y1549000D02*
X195308D01*
G01X198367Y1548792D02*
X198117Y1548917D01*
X197825Y1549000D01*
X197492D01*
X197117Y1548875D01*
X196825Y1548667D01*
X196617Y1548417D01*
X196450Y1548000D01*
X196408Y1547625D01*
X196492Y1547250D01*
X196617Y1547000D01*
X196867Y1546750D01*
X197158Y1546583D01*
X197450Y1546500D01*
X197742D01*
X198033Y1546583D01*
X198283Y1546708D01*
X198492Y1546875D01*
G01X200550Y1546500D02*
Y1549000D01*
X200050Y1548500D01*
G01Y1546500D02*
X201050D01*
G01X203650Y1549000D02*
X203317Y1548917D01*
X203067Y1548708D01*
X202900Y1548458D01*
X202775Y1548125D01*
X202733Y1547750D01*
X202775Y1547375D01*
X202900Y1547042D01*
X203067Y1546792D01*
X203317Y1546583D01*
X203650Y1546500D01*
X203983Y1546583D01*
X204233Y1546792D01*
X204400Y1547042D01*
X204525Y1547375D01*
X204567Y1547750D01*
X204525Y1548125D01*
X204400Y1548458D01*
X204233Y1548708D01*
X203983Y1548917D01*
X203650Y1549000D01*
G01X191800Y1560600D02*
Y1542600D01*
G01X194067Y1639500D02*
Y1642000D01*
X195067D01*
X195400Y1641875D01*
X195650Y1641583D01*
X195733Y1641250D01*
X195650Y1640917D01*
X195442Y1640667D01*
X195067Y1640542D01*
X194067D01*
G01X198917Y1641792D02*
X198667Y1641917D01*
X198375Y1642000D01*
X198042D01*
X197667Y1641875D01*
X197375Y1641667D01*
X197167Y1641417D01*
X197000Y1641000D01*
X196958Y1640625D01*
X197042Y1640250D01*
X197167Y1640000D01*
X197417Y1639750D01*
X197708Y1639583D01*
X198000Y1639500D01*
X198292D01*
X198583Y1639583D01*
X198833Y1639708D01*
X199042Y1639875D01*
G01X201100Y1639500D02*
X201392Y1639542D01*
X201725Y1639667D01*
X201933Y1639875D01*
X202017Y1640167D01*
X201933Y1640458D01*
X201683Y1640708D01*
X201308Y1640833D01*
X200892D01*
X200642Y1640917D01*
X200433Y1641125D01*
X200350Y1641417D01*
X200475Y1641708D01*
X200767Y1641917D01*
X201100Y1642000D01*
X201433Y1641917D01*
X201725Y1641708D01*
X201850Y1641417D01*
X201767Y1641125D01*
X201558Y1640917D01*
X201308Y1640833D01*
X200892D01*
X200517Y1640708D01*
X200267Y1640458D01*
X200183Y1640167D01*
X200267Y1639875D01*
X200475Y1639667D01*
X200808Y1639542D01*
X201100Y1639500D01*
G01X196317Y1653292D02*
X196067Y1653417D01*
X195775Y1653500D01*
X195442D01*
X195067Y1653375D01*
X194775Y1653167D01*
X194567Y1652917D01*
X194400Y1652500D01*
X194358Y1652125D01*
X194442Y1651750D01*
X194567Y1651500D01*
X194817Y1651250D01*
X195108Y1651083D01*
X195400Y1651000D01*
X195692D01*
X195983Y1651083D01*
X196233Y1651208D01*
X196442Y1651375D01*
G01X197708Y1653083D02*
X197958Y1653333D01*
X198250Y1653458D01*
X198583Y1653500D01*
X199000Y1653417D01*
X199292Y1653208D01*
X199375Y1652958D01*
X199333Y1652708D01*
X199167Y1652500D01*
X198333Y1652083D01*
X197958Y1651792D01*
X197708Y1651375D01*
X197625Y1651000D01*
X199375D01*
G01X200808Y1652042D02*
X201100Y1652333D01*
X201350Y1652500D01*
X201683Y1652583D01*
X201975Y1652500D01*
X202183Y1652333D01*
X202350Y1652083D01*
X202392Y1651792D01*
X202350Y1651542D01*
X202183Y1651292D01*
X201933Y1651083D01*
X201642Y1651000D01*
X201308Y1651083D01*
X201017Y1651333D01*
X200850Y1651708D01*
X200808Y1652125D01*
X200892Y1652667D01*
X201017Y1652958D01*
X201225Y1653250D01*
X201517Y1653458D01*
X201808Y1653500D01*
X202100Y1653417D01*
X202308Y1653208D01*
G01X196317Y1649292D02*
X196067Y1649417D01*
X195775Y1649500D01*
X195442D01*
X195067Y1649375D01*
X194775Y1649167D01*
X194567Y1648917D01*
X194400Y1648500D01*
X194358Y1648125D01*
X194442Y1647750D01*
X194567Y1647500D01*
X194817Y1647250D01*
X195108Y1647083D01*
X195400Y1647000D01*
X195692D01*
X195983Y1647083D01*
X196233Y1647208D01*
X196442Y1647375D01*
G01X197708Y1649083D02*
X197958Y1649333D01*
X198250Y1649458D01*
X198583Y1649500D01*
X199000Y1649417D01*
X199292Y1649208D01*
X199375Y1648958D01*
X199333Y1648708D01*
X199167Y1648500D01*
X198333Y1648083D01*
X197958Y1647792D01*
X197708Y1647375D01*
X197625Y1647000D01*
X199375D01*
G01X200683Y1647375D02*
X200933Y1647167D01*
X201225Y1647042D01*
X201600Y1647000D01*
X201975Y1647083D01*
X202267Y1647250D01*
X202475Y1647542D01*
X202517Y1647875D01*
X202433Y1648208D01*
X202225Y1648417D01*
X201933Y1648583D01*
X201642Y1648625D01*
X201350Y1648583D01*
X200975Y1648417D01*
X201100Y1649500D01*
X202225D01*
G01X232871Y1963287D02*
Y1967287D01*
X230404Y1964420D01*
X233738D01*
G01X199109Y1964087D02*
X199509Y1963620D01*
X200043Y1963354D01*
X200643Y1963287D01*
X201176Y1963354D01*
X201709Y1963687D01*
X202043Y1964087D01*
X202109Y1964487D01*
X201976Y1964954D01*
X201509Y1965287D01*
X201043Y1965420D01*
X200443D01*
G01X201043D02*
X201443Y1965620D01*
X201776Y1965954D01*
X201909Y1966354D01*
X201776Y1966754D01*
X201443Y1967087D01*
X200843Y1967287D01*
X200243Y1967220D01*
X199643Y1966954D01*
G01X262099Y1963887D02*
X262499Y1963554D01*
X262966Y1963354D01*
X263566Y1963287D01*
X264166Y1963420D01*
X264633Y1963687D01*
X264966Y1964154D01*
X265033Y1964687D01*
X264899Y1965220D01*
X264566Y1965554D01*
X264099Y1965820D01*
X263633Y1965887D01*
X263166Y1965820D01*
X262566Y1965554D01*
X262766Y1967287D01*
X264566D01*
G01X293795Y1964954D02*
X294262Y1965420D01*
X294662Y1965687D01*
X295195Y1965820D01*
X295662Y1965687D01*
X295995Y1965420D01*
X296262Y1965020D01*
X296329Y1964554D01*
X296262Y1964154D01*
X295995Y1963754D01*
X295595Y1963420D01*
X295129Y1963287D01*
X294595Y1963420D01*
X294129Y1963820D01*
X293862Y1964420D01*
X293795Y1965087D01*
X293929Y1965954D01*
X294129Y1966420D01*
X294462Y1966887D01*
X294929Y1967220D01*
X295395Y1967287D01*
X295862Y1967154D01*
X296195Y1966820D01*
M02*
